G04 ================== begin FILE IDENTIFICATION RECORD ==================*
G04 Layout Name:  15105-1.brd*
G04 Film Name:    15105-1_X_Y*
G04 File Format:  Gerber RS274X*
G04 File Origin:  Cadence Allegro 16.5-S056*
G04 Origin Date:  Wed Nov 16 16:28:43 2016*
G04 *
G04 Layer:  BOARD GEOMETRY/PANEL_DRAWING*
G04 *
G04 Offset:    (0.00 0.00)*
G04 Mirror:    No*
G04 Mode:      Positive*
G04 Rotation:  0*
G04 FullContactRelief:  No*
G04 UndefLineWidth:     6.00*
G04 ================== end FILE IDENTIFICATION RECORD ====================*
%FSLAX25Y25*MOIN*%
%IR0*IPPOS*OFA0.00000B0.00000*MIA0B0*SFA1.00000B1.00000*%
%ADD10C,.006*%
G75*
%LPD*%
G75*
G36*
G01X32115Y799357D02*
X21708Y798773D01*
X22667Y794954D01*
X32115Y799357D01*
G37*
G36*
G01X25012Y794711D02*
X14871Y792301D01*
X16488Y788712D01*
X25012Y794711D01*
G37*
G36*
G01X46761Y234185D02*
X36566Y232018D01*
X38097Y228390D01*
X46761Y234185D01*
G37*
G36*
G01X44631Y248489D02*
X39352Y257477D01*
X36394Y254878D01*
X44631Y248489D01*
G37*
G36*
G01X43194Y243616D02*
X35203Y250309D01*
X33291Y246868D01*
X43194Y243616D01*
G37*
G36*
G01X169130Y-727083D02*
X171098Y-716847D01*
X167161D01*
X169130Y-727083D01*
G37*
G36*
G01Y-615272D02*
X167161Y-625508D01*
X171098D01*
X169130Y-615272D01*
G37*
G36*
G01X189325Y176991D02*
X191630Y187157D01*
X185719Y178571D01*
X189325Y176991D01*
G37*
G36*
G01X260928Y-410049D02*
X271164Y-412018D01*
Y-408081D01*
X260928Y-410049D01*
G37*
G36*
G01X255836Y-41842D02*
X258608Y-31794D01*
X252307Y-40097D01*
X255836Y-41842D01*
G37*
G36*
G01X237844Y318722D02*
X243758Y310138D01*
X241449Y320303D01*
X237844Y318722D01*
G37*
G36*
G01X294360Y-626384D02*
X287800Y-634484D01*
X291272Y-636340D01*
X294360Y-626384D01*
G37*
G36*
G01X292126Y943488D02*
X281890Y945456D01*
Y941519D01*
X292126Y943488D01*
G37*
G36*
G01X296457Y1028599D02*
X306693Y1026630D01*
Y1030568D01*
X296457Y1028599D01*
G37*
G36*
G01X300298Y-438904D02*
X310534Y-440872D01*
Y-436935D01*
X300298Y-438904D01*
G37*
G36*
G01X300787Y943488D02*
X311024Y941519D01*
Y945456D01*
X300787Y943488D01*
G37*
G36*
G01X364788Y586D02*
X357804Y8324D01*
X361420Y-1452D01*
X364788Y586D01*
G37*
G36*
G01X386912Y-467637D02*
X397148Y-469605D01*
Y-465668D01*
X386912Y-467637D01*
G37*
G36*
G01X422345Y-778308D02*
X412109Y-776340D01*
Y-780277D01*
X422345Y-778308D01*
G37*
G36*
G01X429010Y-643929D02*
X437520Y-637910D01*
X434681Y-635183D01*
X429010Y-643929D01*
G37*
G36*
G01X428776Y-586823D02*
X433737Y-595990D01*
X436783Y-593496D01*
X428776Y-586823D01*
G37*
G36*
G01X449904Y-778308D02*
X460141Y-780277D01*
Y-776340D01*
X449904Y-778308D01*
G37*
G36*
G01Y-467637D02*
X439668Y-465668D01*
Y-469605D01*
X449904Y-467637D01*
G37*
G36*
G01Y-438904D02*
X439668Y-436935D01*
Y-440872D01*
X449904Y-438904D01*
G37*
G36*
G01Y-410049D02*
X439668Y-408081D01*
Y-412018D01*
X449904Y-410049D01*
G37*
G36*
G01X472168Y43859D02*
X468399Y53578D01*
X468294Y43155D01*
X472168Y43859D01*
G37*
G36*
G01X495477Y-727083D02*
X497446Y-716847D01*
X493509D01*
X495477Y-727083D01*
G37*
G36*
G01Y-684564D02*
X493508Y-694800D01*
X497445D01*
X495477Y-684564D01*
G37*
G36*
G01X574109Y-727083D02*
X576078Y-716847D01*
X572141D01*
X574109Y-727083D01*
G37*
G36*
G01Y-650705D02*
X572141Y-660942D01*
X576078D01*
X574109Y-650705D01*
G37*
G36*
G01X574077D02*
X576046Y-640469D01*
X572109D01*
X574077Y-650705D01*
G37*
G36*
G01Y-579839D02*
X572109Y-590075D01*
X576046D01*
X574077Y-579839D01*
G37*
G36*
G01X625700Y-727083D02*
X627669Y-716847D01*
X623732D01*
X625700Y-727083D01*
G37*
G36*
G01Y-545981D02*
X623732Y-556217D01*
X627669D01*
X625700Y-545981D01*
G37*
G36*
G01X659711Y-727083D02*
X661680Y-716847D01*
X657743D01*
X659711Y-727083D01*
G37*
G36*
G01Y-506611D02*
X657743Y-516847D01*
X661680D01*
X659711Y-506611D01*
G37*
G36*
G01X709449Y937212D02*
X699213Y939180D01*
Y935243D01*
X709449Y937212D01*
G37*
G36*
G01X713780Y1028599D02*
X703543Y1030568D01*
Y1026630D01*
X713780Y1028599D01*
G37*
G36*
G01X718110Y937212D02*
X728346Y935243D01*
Y939180D01*
X718110Y937212D01*
G37*
G36*
G01X713780Y1029375D02*
X724016Y1027406D01*
Y1031343D01*
X713780Y1029375D01*
G37*
G36*
G01X804789Y311638D02*
X798741Y303149D01*
X807507Y308790D01*
X804789Y311638D01*
G37*
G36*
G01X844403Y207689D02*
X835718Y213453D01*
X841646Y204879D01*
X844403Y207689D01*
G37*
G36*
G01X1097993Y-444388D02*
X1108229Y-446357D01*
Y-442420D01*
X1097993Y-444388D01*
G37*
G36*
G01Y-402323D02*
X1108229Y-404291D01*
Y-400354D01*
X1097993Y-402323D01*
G37*
G36*
G01X1140607Y-641170D02*
X1130687Y-637967D01*
X1130207Y-641874D01*
X1140607Y-641170D01*
G37*
G36*
G01X1140683Y-546151D02*
X1130909Y-542529D01*
X1130263Y-546412D01*
X1140683Y-546151D01*
G37*
G36*
G01X1153111Y-444388D02*
X1142874Y-442420D01*
Y-446357D01*
X1153111Y-444388D01*
G37*
G36*
G01X1192481Y-402323D02*
X1182245Y-400354D01*
Y-404291D01*
X1192481Y-402323D01*
G37*
G36*
G01X1205512Y939354D02*
X1195276Y941322D01*
Y937385D01*
X1205512Y939354D01*
G37*
G36*
G01X1209843Y1029375D02*
X1199606Y1031343D01*
Y1027406D01*
X1209843Y1029375D01*
G37*
G36*
G01X1214173Y939354D02*
X1224409Y937385D01*
Y941322D01*
X1214173Y939354D01*
G37*
G36*
G01X1285204Y-682078D02*
X1287172Y-671842D01*
X1283235D01*
X1285204Y-682078D01*
G37*
G36*
G01Y-642708D02*
X1283235Y-652944D01*
X1287172D01*
X1285204Y-642708D01*
G37*
G36*
G01X1309117Y-35108D02*
X1313504Y-25653D01*
X1305923Y-32807D01*
X1309117Y-35108D01*
G37*
G36*
G01X1317337Y-682078D02*
X1319305Y-671842D01*
X1315368D01*
X1317337Y-682078D01*
G37*
G36*
G01Y-548220D02*
X1315368Y-558456D01*
X1319305D01*
X1317337Y-548220D01*
G37*
G36*
G01X1348612Y-682078D02*
X1350581Y-671842D01*
X1346644D01*
X1348612Y-682078D01*
G37*
G36*
G01Y-508849D02*
X1346644Y-519086D01*
X1350581D01*
X1348612Y-508849D01*
G37*
G36*
G01X1367218Y139369D02*
X1377166Y142483D01*
X1375301Y145951D01*
X1367218Y139369D01*
G37*
G36*
G01X1369382Y148918D02*
X1376707Y156334D01*
X1373435Y158521D01*
X1369382Y148918D01*
G37*
G36*
G01X1371422Y789711D02*
X1377003Y780907D01*
X1379870Y783605D01*
X1371422Y789711D01*
G37*
G36*
G01X1367870Y799298D02*
X1377281Y794817D01*
X1378272Y798627D01*
X1367870Y799298D01*
G37*
G36*
G01X1400172Y406D02*
X1390693Y4743D01*
X1397887Y-2801D01*
X1400172Y406D01*
G37*
G36*
G01X1423574Y-3990D02*
X1413150Y-4063D01*
X1422857Y-7861D01*
X1423574Y-3990D01*
G37*
G36*
G01X1427572Y116271D02*
X1420824Y108327D01*
X1430038Y113201D01*
X1427572Y116271D01*
G37*
G36*
G01X1556811Y-651977D02*
X1558780Y-641740D01*
X1554843D01*
X1556811Y-651977D01*
G37*
G36*
G01Y-470874D02*
X1554843Y-481110D01*
X1558780D01*
X1556811Y-470874D01*
G37*
G36*
G01X1595648Y-651977D02*
X1597616Y-641740D01*
X1593679D01*
X1595648Y-651977D01*
G37*
G36*
G01Y-540166D02*
X1593679Y-550402D01*
X1597616D01*
X1595648Y-540166D01*
G37*
G36*
G01X1643546Y-651977D02*
X1645515Y-641740D01*
X1641578D01*
X1643546Y-651977D01*
G37*
G36*
G01Y-609457D02*
X1641578Y-619693D01*
X1645515D01*
X1643546Y-609457D01*
G37*
G36*
G01X1709716Y-331212D02*
X1719952Y-333181D01*
Y-329244D01*
X1709716Y-331212D01*
G37*
G36*
G01X1704326Y913763D02*
X1702357Y903527D01*
X1706294D01*
X1704326Y913763D01*
G37*
G36*
G01Y918881D02*
X1706294Y929118D01*
X1702357D01*
X1704326Y918881D01*
G37*
G36*
G01X1740418Y-531024D02*
X1734803Y-522242D01*
X1731946Y-524951D01*
X1740418Y-531024D01*
G37*
G36*
G01X1749086Y-348668D02*
X1759322Y-350637D01*
Y-346700D01*
X1749086Y-348668D01*
G37*
G36*
G01X1733524Y861008D02*
X1743904Y861957D01*
X1733912Y864926D01*
X1733524Y861008D01*
G37*
G36*
G01X1743904Y955850D02*
X1754141Y953882D01*
Y957819D01*
X1743904Y955850D01*
G37*
G36*
G01X1737605D02*
X1727369Y957819D01*
Y953882D01*
X1737605Y955850D01*
G37*
G36*
G01X1769997Y871288D02*
X1761623Y865081D01*
X1771702Y867740D01*
X1769997Y871288D01*
G37*
G36*
G01X1835700Y-370488D02*
X1845937Y-372456D01*
Y-368519D01*
X1835700Y-370488D01*
G37*
G36*
G01X1881284Y-581418D02*
X1889334Y-588041D01*
X1891216Y-584583D01*
X1881284Y-581418D01*
G37*
G36*
G01X1881763Y-395801D02*
X1892000Y-397770D01*
Y-393833D01*
X1881763Y-395801D01*
G37*
G36*
G01Y-370488D02*
X1871527Y-368519D01*
Y-372456D01*
X1881763Y-370488D01*
G37*
G36*
G01X1871133Y-395801D02*
X1860897Y-393833D01*
Y-397770D01*
X1871133Y-395801D01*
G37*
G36*
G01X1881763Y-331212D02*
X1871527Y-329244D01*
Y-333181D01*
X1881763Y-331212D01*
G37*
G36*
G01Y-348668D02*
X1871527Y-346700D01*
Y-350637D01*
X1881763Y-348668D01*
G37*
G36*
G01X2032457Y-575599D02*
X2034426Y-565362D01*
X2030489D01*
X2032457Y-575599D01*
G37*
G36*
G01X2032899Y-504732D02*
X2034867Y-494496D01*
X2030930D01*
X2032899Y-504732D01*
G37*
G36*
G01X2032457D02*
X2030489Y-514969D01*
X2034426D01*
X2032457Y-504732D01*
G37*
G36*
G01X2032899Y-431504D02*
X2030930Y-441740D01*
X2034867D01*
X2032899Y-431504D01*
G37*
G36*
G01X2093238Y-651977D02*
X2095207Y-641740D01*
X2091270D01*
X2093238Y-651977D01*
G37*
G36*
G01Y-431504D02*
X2091270Y-441740D01*
X2095207D01*
X2093238Y-431504D01*
G37*
G36*
G01X2195289Y262045D02*
X2186769Y268049D01*
X2185149Y264460D01*
X2195289Y262045D01*
G37*
G36*
G01X2191704Y268354D02*
X2185286Y276568D01*
X2182697Y273602D01*
X2191704Y268354D01*
G37*
G36*
G01X2173498Y828977D02*
X2165009Y835027D01*
X2163370Y831447D01*
X2173498Y828977D01*
G37*
G36*
G01X2180355Y822940D02*
X2170279Y825608D01*
X2170007Y821681D01*
X2180355Y822940D01*
G37*
G36*
G01X2687344Y49364D02*
X2688502Y39005D01*
X2692262Y40174D01*
X2687344Y49364D01*
G37*
G36*
G01X2686626Y55035D02*
X2690141Y45222D01*
X2693530Y47226D01*
X2686626Y55035D01*
G37*
G36*
G01X2955948Y252710D02*
X2945676Y254485D01*
X2954557Y249027D01*
X2955948Y252710D01*
G37*
G36*
G01X2951627Y296700D02*
X2942359Y301472D01*
X2949196Y293603D01*
X2951627Y296700D01*
G37*
G36*
G01X3290843Y49797D02*
X3293272Y39660D01*
X3296858Y41283D01*
X3290843Y49797D01*
G37*
G36*
G01X3289337Y55264D02*
X3293779Y45834D01*
X3296959Y48155D01*
X3289337Y55264D01*
G37*
G36*
G01X3499044Y-1108555D02*
Y-1105288D01*
X3500196D01*
X3499044Y-1108555D01*
G37*
G36*
G01X3500196Y-1105288D02*
Y-1108555D01*
X3499044D01*
X3500196Y-1105288D01*
G37*
G36*
G01X3500388Y-1109426D02*
X3499236Y-1109862D01*
X3500196Y-1108555D01*
X3500388Y-1109426D01*
G37*
G36*
G01X3499236Y-1109862D02*
X3499044Y-1108555D01*
X3500196D01*
X3499236Y-1109862D01*
G37*
G36*
G01X3500388Y-1109426D02*
X3500772Y-1110080D01*
X3499236Y-1109862D01*
X3500388Y-1109426D01*
G37*
G36*
G01X3501348Y-1110515D02*
X3499812Y-1110733D01*
X3500772Y-1110080D01*
X3501348Y-1110515D01*
G37*
G36*
G01X3499812Y-1110733D02*
X3499236Y-1109862D01*
X3500772Y-1110080D01*
X3499812Y-1110733D01*
G37*
G36*
G01X3501348Y-1110515D02*
X3502115Y-1110733D01*
X3499812D01*
X3501348Y-1110515D01*
G37*
G36*
G01X3504994Y-1110080D02*
X3506530Y-1109862D01*
X3504419Y-1110515D01*
X3504994Y-1110080D01*
G37*
G36*
G01X3503651Y-1110733D02*
X3504419Y-1110515D01*
X3505954Y-1110733D01*
X3503651D01*
G37*
G36*
G01X3506530Y-1109862D02*
X3505954Y-1110733D01*
X3504419Y-1110515D01*
X3506530Y-1109862D01*
G37*
G36*
G01X3505954Y-1110733D02*
X3500196Y-1111169D01*
X3503651Y-1110733D01*
X3505954D01*
G37*
G36*
G01X3503651D02*
X3500196Y-1111169D01*
X3502115Y-1110733D01*
X3503651D01*
G37*
G36*
G01X3500196Y-1111169D02*
X3499812Y-1110733D01*
X3502115D01*
X3500196Y-1111169D01*
G37*
G36*
G01X3505954Y-1110733D02*
X3505570Y-1111169D01*
X3500196D01*
X3505954Y-1110733D01*
G37*
G36*
G01X3500963Y-1111822D02*
X3500196Y-1111169D01*
X3505570D01*
X3500963Y-1111822D01*
G37*
G36*
G01X3505570Y-1111169D02*
X3504802Y-1111822D01*
X3500963D01*
X3505570Y-1111169D01*
G37*
G36*
G01X3502115Y-1112040D02*
X3500963Y-1111822D01*
X3504802D01*
X3502115Y-1112040D01*
G37*
G36*
G01X3504802Y-1111822D02*
X3503651Y-1112040D01*
X3502115D01*
X3504802Y-1111822D01*
G37*
G36*
G01X3503893Y-1079214D02*
X3505045Y-1079432D01*
X3502742D01*
X3503893Y-1079214D01*
G37*
G36*
G01X3502166Y-1079649D02*
X3502742Y-1079432D01*
X3505045D01*
X3502166Y-1079649D01*
G37*
G36*
G01D02*
X3505045Y-1079432D01*
X3501590Y-1080085D01*
X3502166Y-1079649D01*
G37*
G36*
G01X3501590Y-1080085D02*
X3505045Y-1079432D01*
X3503702Y-1080085D01*
X3501590D01*
G37*
G36*
G01X3505045Y-1079432D02*
X3506005Y-1080085D01*
X3503702D01*
X3505045Y-1079432D01*
G37*
G36*
G01X3504853Y-1080303D02*
X3503702Y-1080085D01*
X3506005D01*
X3504853Y-1080303D01*
G37*
G36*
G01X3502933D02*
X3501206Y-1080521D01*
X3503702Y-1080085D01*
X3502933Y-1080303D01*
G37*
G36*
G01X3501206Y-1080521D02*
X3501590Y-1080085D01*
X3503702D01*
X3501206Y-1080521D01*
G37*
G36*
G01X3502933Y-1080303D02*
X3502550Y-1080521D01*
X3501206D01*
X3502933Y-1080303D01*
G37*
G36*
G01X3501974Y-1081174D02*
X3500822Y-1081392D01*
X3502550Y-1080521D01*
X3501974Y-1081174D01*
G37*
G36*
G01X3500822Y-1081392D02*
X3501206Y-1080521D01*
X3502550D01*
X3500822Y-1081392D01*
G37*
G36*
G01X3501974Y-1081174D02*
X3501782Y-1081610D01*
X3500822Y-1081392D01*
X3501974Y-1081174D01*
G37*
G36*
G01X3501590Y-1082263D02*
X3500630Y-1082699D01*
X3501782Y-1081610D01*
X3501590Y-1082263D01*
G37*
G36*
G01X3500630Y-1082699D02*
X3500822Y-1081392D01*
X3501782Y-1081610D01*
X3500630Y-1082699D01*
G37*
G36*
G01X3501590Y-1082263D02*
Y-1083134D01*
X3500630Y-1082699D01*
X3501590Y-1082263D01*
G37*
G36*
G01X3501782Y-1083788D02*
X3500822Y-1084005D01*
X3501590Y-1083134D01*
X3501782Y-1083788D01*
G37*
G36*
G01X3500822Y-1084005D02*
X3500630Y-1082699D01*
X3501590Y-1083134D01*
X3500822Y-1084005D01*
G37*
G36*
G01X3501782Y-1083788D02*
X3501974Y-1084223D01*
X3500822Y-1084005D01*
X3501782Y-1083788D01*
G37*
G36*
G01X3501206Y-1084877D02*
X3500822Y-1084005D01*
X3501974Y-1084223D01*
X3501206Y-1084877D01*
G37*
G36*
G01X3501974Y-1084223D02*
X3502550Y-1084877D01*
X3501206D01*
X3501974Y-1084223D01*
G37*
G36*
G01X3502933Y-1085094D02*
X3501590Y-1085312D01*
X3502550Y-1084877D01*
X3502933Y-1085094D01*
G37*
G36*
G01X3501590Y-1085312D02*
X3501206Y-1084877D01*
X3502550D01*
X3501590Y-1085312D01*
G37*
G36*
G01X3502933Y-1085094D02*
X3503702Y-1085312D01*
X3501590D01*
X3502933Y-1085094D01*
G37*
G36*
G01X3505045D02*
X3506580Y-1084877D01*
X3503702Y-1085312D01*
X3505045Y-1085094D01*
G37*
G36*
G01X3506580Y-1084877D02*
X3506005Y-1085530D01*
X3503702Y-1085312D01*
X3506580Y-1084877D01*
G37*
G36*
G01X3506005Y-1085530D02*
X3502166Y-1085748D01*
X3503702Y-1085312D01*
X3506005Y-1085530D01*
G37*
G36*
G01X3502166Y-1085748D02*
X3501590Y-1085312D01*
X3503702D01*
X3502166Y-1085748D01*
G37*
G36*
G01D02*
X3506005Y-1085530D01*
X3502742Y-1085966D01*
X3502166Y-1085748D01*
G37*
G36*
G01X3506005Y-1085530D02*
X3505237Y-1085966D01*
X3502742D01*
X3506005Y-1085530D01*
G37*
G36*
G01X3503893Y-1086183D02*
X3502742Y-1085966D01*
X3505237D01*
X3503893Y-1086183D01*
G37*
G36*
G01X3506772Y-1081827D02*
X3501590D01*
Y-1082699D01*
X3506772D01*
Y-1081827D01*
G37*
G36*
G01X3500963Y-1102021D02*
X3502115Y-1101804D01*
X3503651D01*
X3500963Y-1102021D01*
G37*
G36*
G01X3503651Y-1101804D02*
X3504802Y-1102021D01*
X3500963D01*
X3503651Y-1101804D01*
G37*
G36*
G01X3500196Y-1102675D02*
X3500963Y-1102021D01*
X3504802D01*
X3500196Y-1102675D01*
G37*
G36*
G01X3504802Y-1102021D02*
X3505570Y-1102675D01*
X3500196D01*
X3504802Y-1102021D01*
G37*
G36*
G01X3499812Y-1103110D02*
X3500196Y-1102675D01*
X3505570D01*
X3499812Y-1103110D01*
G37*
G36*
G01D02*
X3505570Y-1102675D01*
X3502115Y-1103110D01*
X3499812D01*
G37*
G36*
G01X3502115D02*
X3505570Y-1102675D01*
X3503651Y-1103110D01*
X3502115D01*
G37*
G36*
G01X3505570Y-1102675D02*
X3505954Y-1103110D01*
X3503651D01*
X3505570Y-1102675D01*
G37*
G36*
G01X3504419Y-1103328D02*
X3503651Y-1103110D01*
X3505954D01*
X3504419Y-1103328D01*
G37*
G36*
G01X3500772Y-1103764D02*
X3499236Y-1103982D01*
X3501348Y-1103328D01*
X3500772Y-1103764D01*
G37*
G36*
G01X3502115Y-1103110D02*
X3501348Y-1103328D01*
X3499812Y-1103110D01*
X3502115D01*
G37*
G36*
G01X3499236Y-1103982D02*
X3499812Y-1103110D01*
X3501348Y-1103328D01*
X3499236Y-1103982D01*
G37*
G36*
G01X3504419Y-1103328D02*
X3505954Y-1103110D01*
X3504994Y-1103764D01*
X3504419Y-1103328D01*
G37*
G36*
G01X3500772Y-1103764D02*
X3500388Y-1104417D01*
X3499236Y-1103982D01*
X3500772Y-1103764D01*
G37*
G36*
G01X3499044Y-1105288D02*
X3499236Y-1103982D01*
X3500388Y-1104417D01*
X3499044Y-1105288D01*
G37*
G36*
G01X3500388Y-1104417D02*
X3500196Y-1105288D01*
X3499044D01*
X3500388Y-1104417D01*
G37*
G36*
G01X3492185Y-1075947D02*
Y-1086183D01*
X3493337D01*
Y-1075947D01*
X3492185D01*
G37*
G36*
G01X3493337Y-1084877D02*
Y-1086183D01*
X3499095D01*
Y-1084877D01*
X3493337D01*
G37*
G36*
G01X3496050Y-1052154D02*
X3497205Y-1060816D01*
X3498072D01*
X3496917Y-1052154D01*
X3496050D01*
G37*
G36*
G01X3498937D02*
X3497494Y-1060816D01*
X3498360D01*
X3499804Y-1052154D01*
X3498937D01*
G37*
G36*
G01X3499226D02*
X3500670Y-1060816D01*
X3501536D01*
X3500093Y-1052154D01*
X3499226D01*
G37*
G36*
G01X3502113D02*
X3500959Y-1060816D01*
X3501825D01*
X3502980Y-1052154D01*
X3502113D01*
G37*
G36*
G01X3504134D02*
Y-1053075D01*
X3504856D01*
Y-1052154D01*
X3504134D01*
G37*
G36*
G01Y-1054918D02*
Y-1060816D01*
X3504856D01*
Y-1054918D01*
X3504134D01*
G37*
G36*
G01Y-1027438D02*
Y-1028360D01*
X3504856D01*
Y-1027438D01*
X3504134D01*
G37*
G36*
G01X3496050D02*
X3497205Y-1036100D01*
X3498072D01*
X3496917Y-1027438D01*
X3496050D01*
G37*
G36*
G01X3498937D02*
X3497494Y-1036100D01*
X3498360D01*
X3499804Y-1027438D01*
X3498937D01*
G37*
G36*
G01X3499226D02*
X3500670Y-1036100D01*
X3501536D01*
X3500093Y-1027438D01*
X3499226D01*
G37*
G36*
G01X3502113D02*
X3500959Y-1036100D01*
X3501825D01*
X3502980Y-1027438D01*
X3502113D01*
G37*
G36*
G01X3504134Y-1030203D02*
Y-1036100D01*
X3504856D01*
Y-1030203D01*
X3504134D01*
G37*
G36*
G01X3492289Y-983071D02*
Y-1002756D01*
X3494011D01*
Y-983071D01*
X3492289D01*
G37*
G36*
G01X3494011Y-1000243D02*
Y-1002756D01*
X3502624D01*
Y-1000243D01*
X3494011D01*
G37*
G36*
G01X3530905Y-1101804D02*
Y-1112040D01*
X3532056D01*
Y-1101804D01*
X3530905D01*
G37*
G36*
G01X3534743Y-1107249D02*
X3533976Y-1107684D01*
X3534551Y-1106813D01*
X3534743Y-1107249D01*
G37*
G36*
G01X3533976Y-1107684D02*
X3533591Y-1106813D01*
X3534551D01*
X3533976Y-1107684D01*
G37*
G36*
G01X3534743Y-1107249D02*
X3535319Y-1107684D01*
X3533976D01*
X3534743Y-1107249D01*
G37*
G36*
G01Y-1108337D02*
X3533976Y-1107684D01*
X3535319D01*
X3534743Y-1108337D01*
G37*
G36*
G01X3535319Y-1107684D02*
X3538582Y-1108773D01*
X3534743Y-1108337D01*
X3535319Y-1107684D01*
G37*
G36*
G01X3538006Y-1109426D02*
X3534743Y-1108337D01*
X3538582Y-1108773D01*
X3538006Y-1109426D01*
G37*
G36*
G01X3538582Y-1108773D02*
X3539350Y-1109426D01*
X3538006D01*
X3538582Y-1108773D01*
G37*
G36*
G01Y-1109862D02*
X3538006Y-1109426D01*
X3539350D01*
X3538582Y-1109862D01*
G37*
G36*
G01X3538198Y-1110951D02*
X3538582Y-1110733D01*
X3539733D01*
X3538198Y-1110951D01*
G37*
G36*
G01X3535127D02*
X3533976Y-1111169D01*
X3534743Y-1110733D01*
X3535127Y-1110951D01*
G37*
G36*
G01X3534743Y-1110733D02*
X3533976Y-1111169D01*
X3534551Y-1110297D01*
X3534743Y-1110733D01*
G37*
G36*
G01X3533976Y-1111169D02*
X3533591Y-1110297D01*
X3534551D01*
X3533976Y-1111169D01*
G37*
G36*
G01X3535127Y-1110951D02*
X3536279Y-1111169D01*
X3533976D01*
X3535127Y-1110951D01*
G37*
G36*
G01X3538198D02*
X3539733Y-1110733D01*
X3537430Y-1111169D01*
X3538198Y-1110951D01*
G37*
G36*
G01X3539733Y-1110733D02*
X3539350Y-1111386D01*
X3537430Y-1111169D01*
X3539733Y-1110733D01*
G37*
G36*
G01X3539350Y-1111386D02*
X3534551Y-1111604D01*
X3537430Y-1111169D01*
X3539350Y-1111386D01*
G37*
G36*
G01X3537430Y-1111169D02*
X3534551Y-1111604D01*
X3536279Y-1111169D01*
X3537430D01*
G37*
G36*
G01X3534551Y-1111604D02*
X3533976Y-1111169D01*
X3536279D01*
X3534551Y-1111604D01*
G37*
G36*
G01D02*
X3539350Y-1111386D01*
X3535127Y-1111822D01*
X3534551Y-1111604D01*
G37*
G36*
G01X3539350Y-1111386D02*
X3538582Y-1111822D01*
X3535127D01*
X3539350Y-1111386D01*
G37*
G36*
G01X3536279Y-1112040D02*
X3535127Y-1111822D01*
X3538582D01*
X3536279Y-1112040D01*
G37*
G36*
G01X3538582Y-1111822D02*
X3537430Y-1112040D01*
X3536279D01*
X3538582Y-1111822D01*
G37*
G36*
G01X3506530Y-1109862D02*
X3504994Y-1110080D01*
X3506530Y-1109426D01*
Y-1109862D01*
G37*
G36*
G01X3504994Y-1110080D02*
X3505186Y-1109426D01*
X3506530D01*
X3504994Y-1110080D01*
G37*
G36*
G01X3508257Y-1101804D02*
Y-1112040D01*
X3509217D01*
Y-1101804D01*
X3508257D01*
G37*
G36*
G01X3509217Y-1107031D02*
Y-1106159D01*
X3509600Y-1106595D01*
X3509217Y-1107031D01*
G37*
G36*
G01X3512480Y-1106813D02*
X3513439Y-1106595D01*
X3512671Y-1107684D01*
X3512480Y-1106813D01*
G37*
G36*
G01X3513439Y-1106595D02*
X3513631Y-1107684D01*
X3512671D01*
X3513439Y-1106595D01*
G37*
G36*
G01X3512671Y-1112040D02*
Y-1107684D01*
X3513631D01*
X3512671Y-1112040D01*
G37*
G36*
G01X3513631Y-1107684D02*
Y-1112040D01*
X3512671D01*
X3513631Y-1107684D01*
G37*
G36*
G01X3524379Y-1101804D02*
Y-1112040D01*
X3525530D01*
Y-1101804D01*
X3524379D01*
G37*
G36*
G01X3525530Y-1105942D02*
Y-1107249D01*
X3530905D01*
Y-1105942D01*
X3525530D01*
G37*
G36*
G01X3534743Y-1105288D02*
X3535894Y-1105071D01*
X3537046D01*
X3534743Y-1105288D01*
G37*
G36*
G01X3537046Y-1105071D02*
X3538198Y-1105288D01*
X3534743D01*
X3537046Y-1105071D01*
G37*
G36*
G01X3538774Y-1105506D02*
X3533976Y-1105724D01*
X3538198Y-1105288D01*
X3538774Y-1105506D01*
G37*
G36*
G01X3533976Y-1105724D02*
X3534743Y-1105288D01*
X3538198D01*
X3533976Y-1105724D01*
G37*
G36*
G01D02*
X3538774Y-1105506D01*
X3535894Y-1105942D01*
X3533976Y-1105724D01*
G37*
G36*
G01X3535894Y-1105942D02*
X3538774Y-1105506D01*
X3537046Y-1105942D01*
X3535894D01*
G37*
G36*
G01X3538774Y-1105506D02*
X3539350Y-1105942D01*
X3537046D01*
X3538774Y-1105506D01*
G37*
G36*
G01X3538198Y-1106159D02*
X3537046Y-1105942D01*
X3539350D01*
X3538198Y-1106159D01*
G37*
G36*
G01X3535127D02*
X3533591Y-1106377D01*
X3535894Y-1105942D01*
X3535127Y-1106159D01*
G37*
G36*
G01X3533591Y-1106377D02*
X3533976Y-1105724D01*
X3535894Y-1105942D01*
X3533591Y-1106377D01*
G37*
G36*
G01X3535127Y-1106159D02*
X3534743Y-1106377D01*
X3533591D01*
X3535127Y-1106159D01*
G37*
G36*
G01X3533591Y-1106813D02*
Y-1106377D01*
X3534743D01*
X3533591Y-1106813D01*
G37*
G36*
G01X3534743Y-1106377D02*
X3534551Y-1106813D01*
X3533591D01*
X3534743Y-1106377D01*
G37*
G36*
G01X3538198Y-1106159D02*
X3539350Y-1105942D01*
X3538582Y-1106377D01*
X3538198Y-1106159D01*
G37*
G36*
G01X3504853Y-1080303D02*
X3506005Y-1080085D01*
X3505429Y-1080738D01*
X3504853Y-1080303D01*
G37*
G36*
G01X3506005Y-1080085D02*
X3506580Y-1080956D01*
X3505429Y-1080738D01*
X3506005Y-1080085D01*
G37*
G36*
G01X3505813Y-1081392D02*
X3505429Y-1080738D01*
X3506580Y-1080956D01*
X3505813Y-1081392D01*
G37*
G36*
G01D02*
X3506580Y-1080956D01*
X3505813Y-1081827D01*
Y-1081392D01*
G37*
G36*
G01X3506580Y-1080956D02*
X3506772Y-1081827D01*
X3505813D01*
X3506580Y-1080956D01*
G37*
G36*
G01X3505620Y-1084659D02*
X3505813Y-1084005D01*
X3506772D01*
X3505620Y-1084659D01*
G37*
G36*
G01X3506772Y-1084005D02*
X3506580Y-1084877D01*
X3505620Y-1084659D01*
X3506772Y-1084005D01*
G37*
G36*
G01X3505045Y-1085094D02*
X3505620Y-1084659D01*
X3506580Y-1084877D01*
X3505045Y-1085094D01*
G37*
G36*
G01X3508308Y-1079214D02*
Y-1086183D01*
X3509267D01*
Y-1079214D01*
X3508308D01*
G37*
G36*
G01X3510227Y-1079432D02*
X3510994Y-1079214D01*
X3511762D01*
X3510227Y-1079432D01*
G37*
G36*
G01X3511762Y-1079214D02*
X3512338Y-1079432D01*
X3510227D01*
X3511762Y-1079214D01*
G37*
G36*
G01X3509651Y-1079867D02*
X3510227Y-1079432D01*
X3512338D01*
X3509651Y-1079867D01*
G37*
G36*
G01X3512338Y-1079432D02*
X3512914Y-1079867D01*
X3509651D01*
X3512338Y-1079432D01*
G37*
G36*
G01X3512914Y-1079867D02*
X3510994Y-1080085D01*
X3509651Y-1079867D01*
X3512914D01*
G37*
G36*
G01X3509267Y-1080303D02*
X3509651Y-1079867D01*
X3510994Y-1080085D01*
X3509267Y-1080303D01*
G37*
G36*
G01X3510994Y-1080085D02*
X3510227Y-1080303D01*
X3509267D01*
X3510994Y-1080085D01*
G37*
G36*
G01D02*
X3512914Y-1079867D01*
X3511762Y-1080303D01*
X3510994Y-1080085D01*
G37*
G36*
G01X3512914Y-1079867D02*
X3513298Y-1080303D01*
X3511762D01*
X3512914Y-1079867D01*
G37*
G36*
G01X3512146Y-1080521D02*
X3511762Y-1080303D01*
X3513298D01*
X3512146Y-1080521D01*
G37*
G36*
G01X3513298Y-1080303D02*
X3513490Y-1080738D01*
X3512146Y-1080521D01*
X3513298Y-1080303D01*
G37*
G36*
G01X3512530Y-1080956D02*
X3512146Y-1080521D01*
X3513490Y-1080738D01*
X3512530Y-1080956D01*
G37*
G36*
G01X3510227Y-1080303D02*
X3509651Y-1080738D01*
X3509267Y-1080303D01*
X3510227D01*
G37*
G36*
G01X3509267Y-1081174D02*
Y-1080303D01*
X3509651Y-1080738D01*
X3509267Y-1081174D01*
G37*
G36*
G01X3512530Y-1080956D02*
X3513490Y-1080738D01*
X3512722Y-1081827D01*
X3512530Y-1080956D01*
G37*
G36*
G01X3513490Y-1080738D02*
X3513681Y-1081827D01*
X3512722D01*
X3513490Y-1080738D01*
G37*
G36*
G01X3512722Y-1086183D02*
Y-1081827D01*
X3513681D01*
X3512722Y-1086183D01*
G37*
G36*
G01X3513681Y-1081827D02*
Y-1086183D01*
X3512722D01*
X3513681Y-1081827D01*
G37*
G36*
G01X3515217Y-1079214D02*
Y-1086183D01*
X3516177D01*
Y-1079214D01*
X3515217D01*
G37*
G36*
G01X3517137Y-1079432D02*
X3517904Y-1079214D01*
X3518672D01*
X3517137Y-1079432D01*
G37*
G36*
G01X3518672Y-1079214D02*
X3519248Y-1079432D01*
X3517137D01*
X3518672Y-1079214D01*
G37*
G36*
G01X3516561Y-1079867D02*
X3517137Y-1079432D01*
X3519248D01*
X3516561Y-1079867D01*
G37*
G36*
G01X3519248Y-1079432D02*
X3519823Y-1079867D01*
X3516561D01*
X3519248Y-1079432D01*
G37*
G36*
G01X3519823Y-1079867D02*
X3517904Y-1080085D01*
X3516561Y-1079867D01*
X3519823D01*
G37*
G36*
G01X3516177Y-1080303D02*
X3516561Y-1079867D01*
X3517904Y-1080085D01*
X3516177Y-1080303D01*
G37*
G36*
G01X3517904Y-1080085D02*
X3517137Y-1080303D01*
X3516177D01*
X3517904Y-1080085D01*
G37*
G36*
G01D02*
X3519823Y-1079867D01*
X3518672Y-1080303D01*
X3517904Y-1080085D01*
G37*
G36*
G01X3519823Y-1079867D02*
X3520207Y-1080303D01*
X3518672D01*
X3519823Y-1079867D01*
G37*
G36*
G01X3519056Y-1080521D02*
X3518672Y-1080303D01*
X3520207D01*
X3519056Y-1080521D01*
G37*
G36*
G01X3520207Y-1080303D02*
X3520399Y-1080738D01*
X3519056Y-1080521D01*
X3520207Y-1080303D01*
G37*
G36*
G01X3519440Y-1080956D02*
X3519056Y-1080521D01*
X3520399Y-1080738D01*
X3519440Y-1080956D01*
G37*
G36*
G01X3517137Y-1080303D02*
X3516561Y-1080738D01*
X3516177Y-1080303D01*
X3517137D01*
G37*
G36*
G01X3516177Y-1081174D02*
Y-1080303D01*
X3516561Y-1080738D01*
X3516177Y-1081174D01*
G37*
G36*
G01X3519440Y-1080956D02*
X3520399Y-1080738D01*
X3519631Y-1081827D01*
X3519440Y-1080956D01*
G37*
G36*
G01X3520399Y-1080738D02*
X3520591Y-1081827D01*
X3519631D01*
X3520399Y-1080738D01*
G37*
G36*
G01X3519631Y-1086183D02*
Y-1081827D01*
X3520591D01*
X3519631Y-1086183D01*
G37*
G36*
G01X3520591Y-1081827D02*
Y-1086183D01*
X3519631D01*
X3520591Y-1081827D01*
G37*
G36*
G01X3522126Y-1079214D02*
X3525197Y-1086183D01*
X3525773Y-1084877D01*
X3523278Y-1079214D01*
X3522126D01*
G37*
G36*
G01X3527117D02*
X3523278Y-1089668D01*
X3524430D01*
X3528268Y-1079214D01*
X3527117D01*
G37*
G36*
G01X3505954Y-1103110D02*
X3506530Y-1103982D01*
X3504994Y-1103764D01*
X3505954Y-1103110D01*
G37*
G36*
G01X3505186Y-1104417D02*
X3504994Y-1103764D01*
X3506530Y-1103982D01*
X3505186Y-1104417D01*
G37*
G36*
G01X3506530Y-1103982D02*
Y-1104417D01*
X3505186D01*
X3506530Y-1103982D01*
G37*
G36*
G01X3510176Y-1105288D02*
X3510944Y-1105071D01*
X3511712D01*
X3510176Y-1105288D01*
G37*
G36*
G01X3511712Y-1105071D02*
X3512287Y-1105288D01*
X3510176D01*
X3511712Y-1105071D01*
G37*
G36*
G01X3509600Y-1105724D02*
X3510176Y-1105288D01*
X3512287D01*
X3509600Y-1105724D01*
G37*
G36*
G01X3512287Y-1105288D02*
X3512863Y-1105724D01*
X3509600D01*
X3512287Y-1105288D01*
G37*
G36*
G01X3512863Y-1105724D02*
X3510944Y-1105942D01*
X3509600Y-1105724D01*
X3512863D01*
G37*
G36*
G01X3509217Y-1106159D02*
X3509600Y-1105724D01*
X3510944Y-1105942D01*
X3509217Y-1106159D01*
G37*
G36*
G01X3510944Y-1105942D02*
X3510176Y-1106159D01*
X3509217D01*
X3510944Y-1105942D01*
G37*
G36*
G01D02*
X3512863Y-1105724D01*
X3511712Y-1106159D01*
X3510944Y-1105942D01*
G37*
G36*
G01X3512863Y-1105724D02*
X3513247Y-1106159D01*
X3511712D01*
X3512863Y-1105724D01*
G37*
G36*
G01X3512095Y-1106377D02*
X3511712Y-1106159D01*
X3513247D01*
X3512095Y-1106377D01*
G37*
G36*
G01X3513247Y-1106159D02*
X3513439Y-1106595D01*
X3512095Y-1106377D01*
X3513247Y-1106159D01*
G37*
G36*
G01X3512480Y-1106813D02*
X3512095Y-1106377D01*
X3513439Y-1106595D01*
X3512480Y-1106813D01*
G37*
G36*
G01X3510176Y-1106159D02*
X3509600Y-1106595D01*
X3509217Y-1106159D01*
X3510176D01*
G37*
G36*
G01X3530841Y-1060816D02*
X3533150Y-1052154D01*
X3534017D01*
X3531707Y-1060816D01*
X3530841D01*
G37*
G36*
G01X3535748D02*
X3536615D01*
X3534305Y-1052154D01*
X3533439D01*
X3535748Y-1060816D01*
G37*
G36*
G01X3531995Y-1057867D02*
Y-1058604D01*
X3535460D01*
Y-1057867D01*
X3531995D01*
G37*
G36*
G01X3538636Y-1062290D02*
X3539502Y-1061921D01*
X3538347Y-1062658D01*
X3538636Y-1062290D01*
G37*
G36*
G01X3539502Y-1061921D02*
X3539213Y-1062658D01*
X3538347D01*
X3539502Y-1061921D01*
G37*
G36*
G01X3537769Y-1063027D02*
X3538347Y-1062658D01*
X3539213D01*
X3537769Y-1063027D01*
G37*
G36*
G01X3539213Y-1062658D02*
X3538780Y-1063211D01*
X3537769Y-1063027D01*
X3539213Y-1062658D01*
G37*
G36*
G01X3538491Y-1063395D02*
X3537769Y-1063764D01*
X3538780Y-1063211D01*
X3538491Y-1063395D01*
G37*
G36*
G01X3537769Y-1063764D02*
Y-1063027D01*
X3538780Y-1063211D01*
X3537769Y-1063764D01*
G37*
G36*
G01X3506011Y-1052154D02*
Y-1060816D01*
X3506733D01*
Y-1052154D01*
X3506011D01*
G37*
G36*
G01X3507888D02*
Y-1060816D01*
X3508609D01*
Y-1052154D01*
X3507888D01*
G37*
G36*
G01X3509764D02*
Y-1053075D01*
X3510486D01*
Y-1052154D01*
X3509764D01*
G37*
G36*
G01Y-1054918D02*
Y-1060816D01*
X3510486D01*
Y-1054918D01*
X3509764D01*
G37*
G36*
G01X3512363Y-1055103D02*
X3513373Y-1054918D01*
X3514239D01*
X3512363Y-1055103D01*
G37*
G36*
G01X3514239Y-1054918D02*
X3515106Y-1055103D01*
X3512363D01*
X3514239Y-1054918D01*
G37*
G36*
G01X3512074Y-1055287D02*
X3512363Y-1055103D01*
X3515106D01*
X3512074Y-1055287D01*
G37*
G36*
G01X3515106Y-1055103D02*
X3515394Y-1055287D01*
X3512074D01*
X3515106Y-1055103D01*
G37*
G36*
G01X3511785Y-1055655D02*
X3512074Y-1055287D01*
X3515394D01*
X3511785Y-1055655D01*
G37*
G36*
G01D02*
X3515394Y-1055287D01*
X3513373Y-1055655D01*
X3511785D01*
G37*
G36*
G01X3513373D02*
X3515394Y-1055287D01*
X3514239Y-1055655D01*
X3513373D01*
G37*
G36*
G01X3514239D02*
X3515394Y-1055287D01*
X3514817Y-1055840D01*
X3514239Y-1055655D01*
G37*
G36*
G01X3515394Y-1055287D02*
X3515827Y-1055840D01*
X3514817D01*
X3515394Y-1055287D01*
G37*
G36*
G01X3512796Y-1055840D02*
X3511641Y-1056024D01*
X3513373Y-1055655D01*
X3512796Y-1055840D01*
G37*
G36*
G01X3511641Y-1056024D02*
X3511785Y-1055655D01*
X3513373D01*
X3511641Y-1056024D01*
G37*
G36*
G01X3512796Y-1055840D02*
X3512507Y-1056024D01*
X3511641D01*
X3512796Y-1055840D01*
G37*
G36*
G01X3515106Y-1056024D02*
X3514817Y-1055840D01*
X3515827D01*
X3515106Y-1056024D01*
G37*
G36*
G01X3511641Y-1056393D02*
Y-1056024D01*
X3512507D01*
X3511641Y-1056393D01*
G37*
G36*
G01X3512507Y-1056024D02*
X3512363Y-1056393D01*
X3511641D01*
X3512507Y-1056024D01*
G37*
G36*
G01X3515106D02*
X3515827Y-1055840D01*
X3515250Y-1056393D01*
X3515106Y-1056024D01*
G37*
G36*
G01X3515827Y-1055840D02*
X3515972Y-1056393D01*
X3515250D01*
X3515827Y-1055840D01*
G37*
G36*
G01X3515972Y-1059341D02*
X3515250Y-1059710D01*
X3515972Y-1056393D01*
Y-1059341D01*
G37*
G36*
G01X3515250Y-1059710D02*
Y-1056393D01*
X3515972D01*
X3515250Y-1059710D01*
G37*
G36*
G01X3515972Y-1059341D02*
X3516116Y-1060262D01*
X3515250Y-1059710D01*
X3515972Y-1059341D01*
G37*
G36*
G01X3515394Y-1060447D02*
X3515250Y-1059710D01*
X3516116Y-1060262D01*
X3515394Y-1060447D01*
G37*
G36*
G01D02*
X3516116Y-1060262D01*
X3515539Y-1060816D01*
X3515394Y-1060447D01*
G37*
G36*
G01X3516116Y-1060262D02*
X3516261Y-1060816D01*
X3515539D01*
X3516116Y-1060262D01*
G37*
G36*
G01X3512796Y-1057130D02*
X3513662Y-1056945D01*
X3515394D01*
X3512796Y-1057130D01*
G37*
G36*
G01D02*
X3515394Y-1056945D01*
X3512218Y-1057498D01*
X3512796Y-1057130D01*
G37*
G36*
G01X3512218Y-1057498D02*
X3515394Y-1056945D01*
X3513662Y-1057682D01*
X3512218Y-1057498D01*
G37*
G36*
G01X3515394Y-1056945D02*
Y-1057682D01*
X3513662D01*
X3515394Y-1056945D01*
G37*
G36*
G01X3511930Y-1057867D02*
X3512218Y-1057498D01*
X3513662Y-1057682D01*
X3511930Y-1057867D01*
G37*
G36*
G01X3513662Y-1057682D02*
X3513085Y-1057867D01*
X3511930D01*
X3513662Y-1057682D01*
G37*
G36*
G01X3512507Y-1058420D02*
X3511641Y-1058604D01*
X3512796Y-1058051D01*
X3512507Y-1058420D01*
G37*
G36*
G01X3512796Y-1058051D02*
X3511641Y-1058604D01*
X3513085Y-1057867D01*
X3512796Y-1058051D01*
G37*
G36*
G01X3511641Y-1058604D02*
X3511930Y-1057867D01*
X3513085D01*
X3511641Y-1058604D01*
G37*
G36*
G01X3512507Y-1058420D02*
X3512363Y-1058973D01*
X3511641Y-1058604D01*
X3512507Y-1058420D01*
G37*
G36*
G01X3511641Y-1059157D02*
Y-1058604D01*
X3512363Y-1058973D01*
X3511641Y-1059157D01*
G37*
G36*
G01X3512363Y-1058973D02*
Y-1059341D01*
X3511641Y-1059157D01*
X3512363Y-1058973D01*
G37*
G36*
G01X3514672Y-1059710D02*
X3515106Y-1059157D01*
X3515394Y-1059710D01*
X3514672D01*
G37*
G36*
G01X3515394Y-1058604D02*
Y-1059710D01*
X3515106Y-1059157D01*
X3515394Y-1058604D01*
G37*
G36*
G01X3512507Y-1059710D02*
X3511785Y-1059894D01*
X3512363Y-1059341D01*
X3512507Y-1059710D01*
G37*
G36*
G01X3511785Y-1059894D02*
X3511641Y-1059157D01*
X3512363Y-1059341D01*
X3511785Y-1059894D01*
G37*
G36*
G01X3512507Y-1059710D02*
X3512796Y-1059894D01*
X3511785D01*
X3512507Y-1059710D01*
G37*
G36*
G01X3511930Y-1060078D02*
X3511785Y-1059894D01*
X3512796D01*
X3511930Y-1060078D01*
G37*
G36*
G01X3512796Y-1059894D02*
X3513085Y-1060078D01*
X3511930D01*
X3512796Y-1059894D01*
G37*
G36*
G01X3513951Y-1060078D02*
X3514672Y-1059710D01*
X3515394D01*
X3513951Y-1060078D01*
G37*
G36*
G01X3515394Y-1059710D02*
X3515106Y-1060262D01*
X3513951Y-1060078D01*
X3515394Y-1059710D01*
G37*
G36*
G01X3515106Y-1060262D02*
X3512218Y-1060447D01*
X3513951Y-1060078D01*
X3515106Y-1060262D01*
G37*
G36*
G01X3513951Y-1060078D02*
X3512218Y-1060447D01*
X3513085Y-1060078D01*
X3513951D01*
G37*
G36*
G01X3512218Y-1060447D02*
X3511930Y-1060078D01*
X3513085D01*
X3512218Y-1060447D01*
G37*
G36*
G01D02*
X3515106Y-1060262D01*
X3512507Y-1060631D01*
X3512218Y-1060447D01*
G37*
G36*
G01X3515106Y-1060262D02*
X3514672Y-1060631D01*
X3512507D01*
X3515106Y-1060262D01*
G37*
G36*
G01X3513085Y-1060816D02*
X3512507Y-1060631D01*
X3514672D01*
X3513085Y-1060816D01*
G37*
G36*
G01X3514672Y-1060631D02*
X3513951Y-1060816D01*
X3513085D01*
X3514672Y-1060631D01*
G37*
G36*
G01X3518426Y-1055103D02*
X3518859Y-1054918D01*
X3519436D01*
X3518426Y-1055103D01*
G37*
G36*
G01X3519436Y-1054918D02*
X3519869Y-1055103D01*
X3518426D01*
X3519436Y-1054918D01*
G37*
G36*
G01X3520735Y-1055103D02*
X3521169Y-1054918D01*
X3521746D01*
X3520735Y-1055103D01*
G37*
G36*
G01X3521746Y-1054918D02*
X3522179Y-1055103D01*
X3520735D01*
X3521746Y-1054918D01*
G37*
G36*
G01X3518137Y-1055471D02*
X3518426Y-1055103D01*
X3519869D01*
X3518137Y-1055471D01*
G37*
G36*
G01X3519869Y-1055103D02*
X3520158Y-1055471D01*
X3518137D01*
X3519869Y-1055103D01*
G37*
G36*
G01X3520447Y-1055471D02*
X3520735Y-1055103D01*
X3522179D01*
X3520447Y-1055471D01*
G37*
G36*
G01X3522179Y-1055103D02*
X3522468Y-1055471D01*
X3520447D01*
X3522179Y-1055103D01*
G37*
G36*
G01X3518859Y-1055655D02*
X3520158Y-1055471D01*
X3519148Y-1055655D01*
X3518859D01*
G37*
G36*
G01X3520158Y-1055471D02*
X3520302Y-1055655D01*
X3519148D01*
X3520158Y-1055471D01*
G37*
G36*
G01X3520302Y-1055655D02*
X3520447Y-1055471D01*
X3522468D01*
X3520302Y-1055655D01*
G37*
G36*
G01X3521024D02*
X3519436Y-1055840D01*
X3520302Y-1055655D01*
X3521024D01*
G37*
G36*
G01X3519436Y-1055840D02*
X3519148Y-1055655D01*
X3520302D01*
X3519436Y-1055840D01*
G37*
G36*
G01X3521024Y-1055655D02*
X3520735Y-1055840D01*
X3519436D01*
X3521024Y-1055655D01*
G37*
G36*
G01X3520302D02*
X3522468Y-1055471D01*
X3521024Y-1055655D01*
X3520302D01*
G37*
G36*
G01X3521024D02*
X3522468Y-1055471D01*
X3521457Y-1055655D01*
X3521024D01*
G37*
G36*
G01X3521457D02*
X3522468Y-1055471D01*
X3521746Y-1055840D01*
X3521457Y-1055655D01*
G37*
G36*
G01X3522468Y-1055471D02*
X3522612Y-1055840D01*
X3521746D01*
X3522468Y-1055471D01*
G37*
G36*
G01X3519580Y-1056024D02*
X3519436Y-1055840D01*
X3520735D01*
X3519580Y-1056024D01*
G37*
G36*
G01X3520735Y-1055840D02*
X3520591Y-1056024D01*
X3519580D01*
X3520735Y-1055840D01*
G37*
G36*
G01X3521890Y-1056024D02*
X3521746Y-1055840D01*
X3522612D01*
X3521890Y-1056024D01*
G37*
G36*
G01X3519725Y-1056393D02*
X3519580Y-1056024D01*
X3520591D01*
X3519725Y-1056393D01*
G37*
G36*
G01X3520591Y-1056024D02*
X3520447Y-1056393D01*
X3519725D01*
X3520591Y-1056024D01*
G37*
G36*
G01X3521890D02*
X3522612Y-1055840D01*
X3522035Y-1056393D01*
X3521890Y-1056024D01*
G37*
G36*
G01X3522612Y-1055840D02*
X3522756Y-1056393D01*
X3522035D01*
X3522612Y-1055840D01*
G37*
G36*
G01X3520158Y-1055471D02*
X3518859Y-1055655D01*
X3518137Y-1055471D01*
X3520158D01*
G37*
G36*
G01X3518859Y-1055655D02*
X3518426Y-1055840D01*
X3518137Y-1055471D01*
X3518859Y-1055655D01*
G37*
G36*
G01X3518426Y-1055840D02*
X3518137Y-1056208D01*
Y-1055471D01*
X3518426Y-1055840D01*
G37*
G36*
G01X3518137Y-1056208D02*
X3517415Y-1060816D01*
X3518137Y-1055471D01*
Y-1056208D01*
G37*
G36*
G01Y-1055471D02*
X3517415Y-1060816D01*
X3518137Y-1054918D01*
Y-1055471D01*
G37*
G36*
G01X3517415Y-1060816D02*
Y-1054918D01*
X3518137D01*
X3517415Y-1060816D01*
G37*
G36*
G01X3518137Y-1056208D02*
Y-1060816D01*
X3517415D01*
X3518137Y-1056208D01*
G37*
G36*
G01X3519725Y-1060816D02*
Y-1056393D01*
X3520447D01*
X3519725Y-1060816D01*
G37*
G36*
G01X3520447Y-1056393D02*
Y-1060816D01*
X3519725D01*
X3520447Y-1056393D01*
G37*
G36*
G01X3522035Y-1060816D02*
Y-1056393D01*
X3522756D01*
X3522035Y-1060816D01*
G37*
G36*
G01X3522756Y-1056393D02*
Y-1060816D01*
X3522035D01*
X3522756Y-1056393D01*
G37*
G36*
G01X3531995Y-1033151D02*
Y-1033888D01*
X3535460D01*
Y-1033151D01*
X3531995D01*
G37*
G36*
G01X3530841Y-1036100D02*
X3533150Y-1027438D01*
X3534017D01*
X3531707Y-1036100D01*
X3530841D01*
G37*
G36*
G01X3535748D02*
X3536615D01*
X3534305Y-1027438D01*
X3533439D01*
X3535748Y-1036100D01*
G37*
G36*
G01X3538636Y-1037574D02*
X3539502Y-1037205D01*
X3538347Y-1037942D01*
X3538636Y-1037574D01*
G37*
G36*
G01X3539502Y-1037205D02*
X3539213Y-1037942D01*
X3538347D01*
X3539502Y-1037205D01*
G37*
G36*
G01X3537769Y-1038311D02*
X3538347Y-1037942D01*
X3539213D01*
X3537769Y-1038311D01*
G37*
G36*
G01X3539213Y-1037942D02*
X3538780Y-1038495D01*
X3537769Y-1038311D01*
X3539213Y-1037942D01*
G37*
G36*
G01X3538491Y-1038680D02*
X3537769Y-1039048D01*
X3538780Y-1038495D01*
X3538491Y-1038680D01*
G37*
G36*
G01X3537769Y-1039048D02*
Y-1038311D01*
X3538780Y-1038495D01*
X3537769Y-1039048D01*
G37*
G36*
G01X3509764Y-1027438D02*
Y-1028360D01*
X3510486D01*
Y-1027438D01*
X3509764D01*
G37*
G36*
G01X3512363Y-1030387D02*
X3513373Y-1030203D01*
X3514239D01*
X3512363Y-1030387D01*
G37*
G36*
G01X3514239Y-1030203D02*
X3515106Y-1030387D01*
X3512363D01*
X3514239Y-1030203D01*
G37*
G36*
G01X3512074Y-1030571D02*
X3512363Y-1030387D01*
X3515106D01*
X3512074Y-1030571D01*
G37*
G36*
G01X3515106Y-1030387D02*
X3515394Y-1030571D01*
X3512074D01*
X3515106Y-1030387D01*
G37*
G36*
G01X3511785Y-1030940D02*
X3512074Y-1030571D01*
X3515394D01*
X3511785Y-1030940D01*
G37*
G36*
G01D02*
X3515394Y-1030571D01*
X3513373Y-1030940D01*
X3511785D01*
G37*
G36*
G01X3513373D02*
X3515394Y-1030571D01*
X3514239Y-1030940D01*
X3513373D01*
G37*
G36*
G01X3514239D02*
X3515394Y-1030571D01*
X3514817Y-1031124D01*
X3514239Y-1030940D01*
G37*
G36*
G01X3515394Y-1030571D02*
X3515827Y-1031124D01*
X3514817D01*
X3515394Y-1030571D01*
G37*
G36*
G01X3512796Y-1031124D02*
X3511641Y-1031308D01*
X3513373Y-1030940D01*
X3512796Y-1031124D01*
G37*
G36*
G01X3511641Y-1031308D02*
X3511785Y-1030940D01*
X3513373D01*
X3511641Y-1031308D01*
G37*
G36*
G01X3512796Y-1031124D02*
X3512507Y-1031308D01*
X3511641D01*
X3512796Y-1031124D01*
G37*
G36*
G01X3515106Y-1031308D02*
X3514817Y-1031124D01*
X3515827D01*
X3515106Y-1031308D01*
G37*
G36*
G01X3511641Y-1031677D02*
Y-1031308D01*
X3512507D01*
X3511641Y-1031677D01*
G37*
G36*
G01X3512507Y-1031308D02*
X3512363Y-1031677D01*
X3511641D01*
X3512507Y-1031308D01*
G37*
G36*
G01X3515106D02*
X3515827Y-1031124D01*
X3515250Y-1031677D01*
X3515106Y-1031308D01*
G37*
G36*
G01X3515827Y-1031124D02*
X3515972Y-1031677D01*
X3515250D01*
X3515827Y-1031124D01*
G37*
G36*
G01X3512796Y-1032414D02*
X3513662Y-1032230D01*
X3515394D01*
X3512796Y-1032414D01*
G37*
G36*
G01D02*
X3515394Y-1032230D01*
X3512218Y-1032782D01*
X3512796Y-1032414D01*
G37*
G36*
G01X3512218Y-1032782D02*
X3515394Y-1032230D01*
X3513662Y-1032967D01*
X3512218Y-1032782D01*
G37*
G36*
G01X3515394Y-1032230D02*
Y-1032967D01*
X3513662D01*
X3515394Y-1032230D01*
G37*
G36*
G01X3511930Y-1033151D02*
X3512218Y-1032782D01*
X3513662Y-1032967D01*
X3511930Y-1033151D01*
G37*
G36*
G01X3513662Y-1032967D02*
X3513085Y-1033151D01*
X3511930D01*
X3513662Y-1032967D01*
G37*
G36*
G01X3512507Y-1033704D02*
X3511641Y-1033888D01*
X3512796Y-1033335D01*
X3512507Y-1033704D01*
G37*
G36*
G01X3512796Y-1033335D02*
X3511641Y-1033888D01*
X3513085Y-1033151D01*
X3512796Y-1033335D01*
G37*
G36*
G01X3511641Y-1033888D02*
X3511930Y-1033151D01*
X3513085D01*
X3511641Y-1033888D01*
G37*
G36*
G01X3512507Y-1033704D02*
X3512363Y-1034257D01*
X3511641Y-1033888D01*
X3512507Y-1033704D01*
G37*
G36*
G01X3511641Y-1034441D02*
Y-1033888D01*
X3512363Y-1034257D01*
X3511641Y-1034441D01*
G37*
G36*
G01X3518426Y-1030387D02*
X3518859Y-1030203D01*
X3519436D01*
X3518426Y-1030387D01*
G37*
G36*
G01X3519436Y-1030203D02*
X3519869Y-1030387D01*
X3518426D01*
X3519436Y-1030203D01*
G37*
G36*
G01X3520735Y-1030387D02*
X3521169Y-1030203D01*
X3521746D01*
X3520735Y-1030387D01*
G37*
G36*
G01X3521746Y-1030203D02*
X3522179Y-1030387D01*
X3520735D01*
X3521746Y-1030203D01*
G37*
G36*
G01X3518137Y-1030755D02*
X3518426Y-1030387D01*
X3519869D01*
X3518137Y-1030755D01*
G37*
G36*
G01X3519869Y-1030387D02*
X3520158Y-1030755D01*
X3518137D01*
X3519869Y-1030387D01*
G37*
G36*
G01X3520447Y-1030755D02*
X3520735Y-1030387D01*
X3522179D01*
X3520447Y-1030755D01*
G37*
G36*
G01X3522179Y-1030387D02*
X3522468Y-1030755D01*
X3520447D01*
X3522179Y-1030387D01*
G37*
G36*
G01X3518859Y-1030940D02*
X3520158Y-1030755D01*
X3519148Y-1030940D01*
X3518859D01*
G37*
G36*
G01X3520158Y-1030755D02*
X3520302Y-1030940D01*
X3519148D01*
X3520158Y-1030755D01*
G37*
G36*
G01X3520302Y-1030940D02*
X3520447Y-1030755D01*
X3522468D01*
X3520302Y-1030940D01*
G37*
G36*
G01X3521024D02*
X3519436Y-1031124D01*
X3520302Y-1030940D01*
X3521024D01*
G37*
G36*
G01X3519436Y-1031124D02*
X3519148Y-1030940D01*
X3520302D01*
X3519436Y-1031124D01*
G37*
G36*
G01X3521024Y-1030940D02*
X3520735Y-1031124D01*
X3519436D01*
X3521024Y-1030940D01*
G37*
G36*
G01X3520302D02*
X3522468Y-1030755D01*
X3521024Y-1030940D01*
X3520302D01*
G37*
G36*
G01X3521024D02*
X3522468Y-1030755D01*
X3521457Y-1030940D01*
X3521024D01*
G37*
G36*
G01X3521457D02*
X3522468Y-1030755D01*
X3521746Y-1031124D01*
X3521457Y-1030940D01*
G37*
G36*
G01X3522468Y-1030755D02*
X3522612Y-1031124D01*
X3521746D01*
X3522468Y-1030755D01*
G37*
G36*
G01X3519580Y-1031308D02*
X3519436Y-1031124D01*
X3520735D01*
X3519580Y-1031308D01*
G37*
G36*
G01X3520735Y-1031124D02*
X3520591Y-1031308D01*
X3519580D01*
X3520735Y-1031124D01*
G37*
G36*
G01X3521890Y-1031308D02*
X3521746Y-1031124D01*
X3522612D01*
X3521890Y-1031308D01*
G37*
G36*
G01X3519725Y-1031677D02*
X3519580Y-1031308D01*
X3520591D01*
X3519725Y-1031677D01*
G37*
G36*
G01X3520591Y-1031308D02*
X3520447Y-1031677D01*
X3519725D01*
X3520591Y-1031308D01*
G37*
G36*
G01X3521890D02*
X3522612Y-1031124D01*
X3522035Y-1031677D01*
X3521890Y-1031308D01*
G37*
G36*
G01X3522612Y-1031124D02*
X3522756Y-1031677D01*
X3522035D01*
X3522612Y-1031124D01*
G37*
G36*
G01X3520158Y-1030755D02*
X3518859Y-1030940D01*
X3518137Y-1030755D01*
X3520158D01*
G37*
G36*
G01X3518859Y-1030940D02*
X3518426Y-1031124D01*
X3518137Y-1030755D01*
X3518859Y-1030940D01*
G37*
G36*
G01X3518426Y-1031124D02*
X3518137Y-1031492D01*
Y-1030755D01*
X3518426Y-1031124D01*
G37*
G36*
G01X3506011Y-1027438D02*
Y-1036100D01*
X3506733D01*
Y-1027438D01*
X3506011D01*
G37*
G36*
G01X3507888D02*
Y-1036100D01*
X3508609D01*
Y-1027438D01*
X3507888D01*
G37*
G36*
G01X3509764Y-1030203D02*
Y-1036100D01*
X3510486D01*
Y-1030203D01*
X3509764D01*
G37*
G36*
G01X3515972Y-1034625D02*
X3515250Y-1034994D01*
X3515972Y-1031677D01*
Y-1034625D01*
G37*
G36*
G01X3515250Y-1034994D02*
Y-1031677D01*
X3515972D01*
X3515250Y-1034994D01*
G37*
G36*
G01X3515972Y-1034625D02*
X3516116Y-1035547D01*
X3515250Y-1034994D01*
X3515972Y-1034625D01*
G37*
G36*
G01X3515394Y-1035731D02*
X3515250Y-1034994D01*
X3516116Y-1035547D01*
X3515394Y-1035731D01*
G37*
G36*
G01D02*
X3516116Y-1035547D01*
X3515539Y-1036100D01*
X3515394Y-1035731D01*
G37*
G36*
G01X3516116Y-1035547D02*
X3516261Y-1036100D01*
X3515539D01*
X3516116Y-1035547D01*
G37*
G36*
G01X3512363Y-1034257D02*
Y-1034625D01*
X3511641Y-1034441D01*
X3512363Y-1034257D01*
G37*
G36*
G01X3514672Y-1034994D02*
X3515106Y-1034441D01*
X3515394Y-1034994D01*
X3514672D01*
G37*
G36*
G01X3515394Y-1033888D02*
Y-1034994D01*
X3515106Y-1034441D01*
X3515394Y-1033888D01*
G37*
G36*
G01X3512507Y-1034994D02*
X3511785Y-1035178D01*
X3512363Y-1034625D01*
X3512507Y-1034994D01*
G37*
G36*
G01X3511785Y-1035178D02*
X3511641Y-1034441D01*
X3512363Y-1034625D01*
X3511785Y-1035178D01*
G37*
G36*
G01X3512507Y-1034994D02*
X3512796Y-1035178D01*
X3511785D01*
X3512507Y-1034994D01*
G37*
G36*
G01X3511930Y-1035362D02*
X3511785Y-1035178D01*
X3512796D01*
X3511930Y-1035362D01*
G37*
G36*
G01X3512796Y-1035178D02*
X3513085Y-1035362D01*
X3511930D01*
X3512796Y-1035178D01*
G37*
G36*
G01X3513951Y-1035362D02*
X3514672Y-1034994D01*
X3515394D01*
X3513951Y-1035362D01*
G37*
G36*
G01X3515394Y-1034994D02*
X3515106Y-1035547D01*
X3513951Y-1035362D01*
X3515394Y-1034994D01*
G37*
G36*
G01X3515106Y-1035547D02*
X3512218Y-1035731D01*
X3513951Y-1035362D01*
X3515106Y-1035547D01*
G37*
G36*
G01X3513951Y-1035362D02*
X3512218Y-1035731D01*
X3513085Y-1035362D01*
X3513951D01*
G37*
G36*
G01X3512218Y-1035731D02*
X3511930Y-1035362D01*
X3513085D01*
X3512218Y-1035731D01*
G37*
G36*
G01D02*
X3515106Y-1035547D01*
X3512507Y-1035916D01*
X3512218Y-1035731D01*
G37*
G36*
G01X3515106Y-1035547D02*
X3514672Y-1035916D01*
X3512507D01*
X3515106Y-1035547D01*
G37*
G36*
G01X3513085Y-1036100D02*
X3512507Y-1035916D01*
X3514672D01*
X3513085Y-1036100D01*
G37*
G36*
G01X3514672Y-1035916D02*
X3513951Y-1036100D01*
X3513085D01*
X3514672Y-1035916D01*
G37*
G36*
G01X3518137Y-1031492D02*
X3517415Y-1036100D01*
X3518137Y-1030755D01*
Y-1031492D01*
G37*
G36*
G01Y-1030755D02*
X3517415Y-1036100D01*
X3518137Y-1030203D01*
Y-1030755D01*
G37*
G36*
G01X3517415Y-1036100D02*
Y-1030203D01*
X3518137D01*
X3517415Y-1036100D01*
G37*
G36*
G01X3518137Y-1031492D02*
Y-1036100D01*
X3517415D01*
X3518137Y-1031492D01*
G37*
G36*
G01X3519725Y-1036100D02*
Y-1031677D01*
X3520447D01*
X3519725Y-1036100D01*
G37*
G36*
G01X3520447Y-1031677D02*
Y-1036100D01*
X3519725D01*
X3520447Y-1031677D01*
G37*
G36*
G01X3522035Y-1036100D02*
Y-1031677D01*
X3522756D01*
X3522035Y-1036100D01*
G37*
G36*
G01X3522756Y-1031677D02*
Y-1036100D01*
X3522035D01*
X3522756Y-1031677D01*
G37*
G36*
G01X3537072Y-983071D02*
Y-985165D01*
X3547981D01*
Y-983071D01*
X3537072D01*
G37*
G36*
G01X3533054D02*
Y-1002756D01*
X3534776D01*
Y-983071D01*
X3533054D01*
G37*
G36*
G01X3512384Y-983490D02*
X3514107Y-983071D01*
X3515255D01*
X3512384Y-983490D01*
G37*
G36*
G01X3515255Y-983071D02*
X3518126Y-983490D01*
X3512384D01*
X3515255Y-983071D01*
G37*
G36*
G01X3511236Y-984746D02*
X3512384Y-983490D01*
X3518126D01*
X3511236Y-984746D01*
G37*
G36*
G01X3518126Y-983490D02*
X3519274Y-984746D01*
X3511236D01*
X3518126Y-983490D01*
G37*
G36*
G01X3510662Y-985584D02*
X3511236Y-984746D01*
X3519274D01*
X3510662Y-985584D01*
G37*
G36*
G01D02*
X3519274Y-984746D01*
X3514107Y-985584D01*
X3510662D01*
G37*
G36*
G01X3514107D02*
X3519274Y-984746D01*
X3516404Y-985584D01*
X3514107D01*
G37*
G36*
G01X3519274Y-984746D02*
X3519848Y-985584D01*
X3516404D01*
X3519274Y-984746D01*
G37*
G36*
G01X3517552Y-986003D02*
X3516404Y-985584D01*
X3519848D01*
X3517552Y-986003D01*
G37*
G36*
G01X3512097Y-986840D02*
X3509801Y-987259D01*
X3512959Y-986003D01*
X3512097Y-986840D01*
G37*
G36*
G01X3514107Y-985584D02*
X3512959Y-986003D01*
X3510662Y-985584D01*
X3514107D01*
G37*
G36*
G01X3509801Y-987259D02*
X3510662Y-985584D01*
X3512959Y-986003D01*
X3509801Y-987259D01*
G37*
G36*
G01X3517552Y-986003D02*
X3519848Y-985584D01*
X3518413Y-986840D01*
X3517552Y-986003D01*
G37*
G36*
G01X3519848Y-985584D02*
X3520709Y-987259D01*
X3518413Y-986840D01*
X3519848Y-985584D01*
G37*
G36*
G01X3512097Y-986840D02*
X3511523Y-988097D01*
X3509801Y-987259D01*
X3512097Y-986840D01*
G37*
G36*
G01X3518700Y-988097D02*
X3518413Y-986840D01*
X3520709Y-987259D01*
X3518700Y-988097D01*
G37*
G36*
G01X3520709Y-987259D02*
Y-988097D01*
X3518700D01*
X3520709Y-987259D01*
G37*
G36*
G01X3509514Y-989772D02*
X3509801Y-987259D01*
X3511523Y-988097D01*
X3509514Y-989772D01*
G37*
G36*
G01X3511523Y-988097D02*
X3511236Y-989772D01*
X3509514D01*
X3511523Y-988097D01*
G37*
G36*
G01X3516404Y-994379D02*
Y-991866D01*
X3520709D01*
X3516404Y-994379D01*
G37*
G36*
G01X3509514Y-996054D02*
Y-989772D01*
X3511236D01*
X3509514Y-996054D01*
G37*
G36*
G01X3511236Y-989772D02*
Y-996054D01*
X3509514D01*
X3511236Y-989772D01*
G37*
G36*
G01X3511523Y-997730D02*
X3509801Y-998567D01*
X3511236Y-996054D01*
X3511523Y-997730D01*
G37*
G36*
G01X3509801Y-998567D02*
X3509514Y-996054D01*
X3511236D01*
X3509801Y-998567D01*
G37*
G36*
G01X3516404Y-994379D02*
X3520709Y-991866D01*
X3518987Y-994379D01*
X3516404D01*
G37*
G36*
G01X3518987D02*
X3520709Y-991866D01*
X3518987Y-997730D01*
Y-994379D01*
G37*
G36*
G01X3520709Y-991866D02*
Y-998567D01*
X3518987Y-997730D01*
X3520709Y-991866D01*
G37*
G36*
G01X3511523Y-997730D02*
X3512097Y-998986D01*
X3509801Y-998567D01*
X3511523Y-997730D01*
G37*
G36*
G01X3518413Y-998986D02*
X3518987Y-997730D01*
X3520709Y-998567D01*
X3518413Y-998986D01*
G37*
G36*
G01X3512959Y-999824D02*
X3510662Y-1000243D01*
X3512097Y-998986D01*
X3512959Y-999824D01*
G37*
G36*
G01X3510662Y-1000243D02*
X3509801Y-998567D01*
X3512097Y-998986D01*
X3510662Y-1000243D01*
G37*
G36*
G01X3512959Y-999824D02*
X3514107Y-1000243D01*
X3510662D01*
X3512959Y-999824D01*
G37*
G36*
G01X3518413Y-998986D02*
X3520709Y-998567D01*
X3517552Y-999824D01*
X3518413Y-998986D01*
G37*
G36*
G01X3516404Y-1000243D02*
X3517552Y-999824D01*
X3519848Y-1000243D01*
X3516404D01*
G37*
G36*
G01X3520709Y-998567D02*
X3519848Y-1000243D01*
X3517552Y-999824D01*
X3520709Y-998567D01*
G37*
G36*
G01X3525016Y-991029D02*
Y-993542D01*
X3533054D01*
Y-991029D01*
X3525016D01*
G37*
G36*
G01X3504920Y-983071D02*
Y-1002756D01*
X3506643D01*
Y-983071D01*
X3504920D01*
G37*
G36*
G01X3519848Y-1000243D02*
X3511236Y-1001080D01*
X3516404Y-1000243D01*
X3519848D01*
G37*
G36*
G01X3516404D02*
X3511236Y-1001080D01*
X3514107Y-1000243D01*
X3516404D01*
G37*
G36*
G01X3511236Y-1001080D02*
X3510662Y-1000243D01*
X3514107D01*
X3511236Y-1001080D01*
G37*
G36*
G01X3519848Y-1000243D02*
X3519274Y-1001080D01*
X3511236D01*
X3519848Y-1000243D01*
G37*
G36*
G01X3512384Y-1002337D02*
X3511236Y-1001080D01*
X3519274D01*
X3512384Y-1002337D01*
G37*
G36*
G01X3519274Y-1001080D02*
X3518126Y-1002337D01*
X3512384D01*
X3519274Y-1001080D01*
G37*
G36*
G01X3514107Y-1002756D02*
X3512384Y-1002337D01*
X3518126D01*
X3514107Y-1002756D01*
G37*
G36*
G01X3518126Y-1002337D02*
X3516404Y-1002756D01*
X3514107D01*
X3518126Y-1002337D01*
G37*
G36*
G01X3523293Y-983071D02*
Y-1002756D01*
X3525016D01*
Y-983071D01*
X3523293D01*
G37*
G36*
G01X3536565Y31381D02*
X3542421Y22758D01*
X3545202Y25545D01*
X3536565Y31381D01*
G37*
G36*
G01X3531396Y40524D02*
X3540496Y35439D01*
X3541733Y39177D01*
X3531396Y40524D01*
G37*
G36*
G01X3515939Y160049D02*
X3526112Y162321D01*
X3524544Y165932D01*
X3515939Y160049D01*
G37*
G36*
G01X3520562Y167845D02*
X3529374Y173414D01*
X3526680Y176285D01*
X3520562Y167845D01*
G37*
G36*
G01X3516211Y824675D02*
X3526565Y825877D01*
X3525381Y829632D01*
X3516211Y824675D01*
G37*
G36*
G01X3519672Y834077D02*
X3528014Y840326D01*
X3525101Y842975D01*
X3519672Y834077D01*
G37*
G36*
G01X3538582Y-1109862D02*
X3539350Y-1109426D01*
X3538774Y-1110297D01*
X3538582Y-1109862D01*
G37*
G36*
G01X3539350Y-1109426D02*
X3539733Y-1110297D01*
X3538774D01*
X3539350Y-1109426D01*
G37*
G36*
G01X3538582Y-1110733D02*
X3538774Y-1110297D01*
X3539733D01*
X3538582Y-1110733D01*
G37*
G36*
G01X3539733Y-1110297D02*
Y-1110733D01*
X3538582D01*
X3539733Y-1110297D01*
G37*
G36*
G01X3541269Y-1105071D02*
Y-1112040D01*
X3542228D01*
Y-1105071D01*
X3541269D01*
G37*
G36*
G01X3545107Y-1107031D02*
X3543956Y-1107249D01*
X3545683Y-1106377D01*
X3545107Y-1107031D01*
G37*
G36*
G01X3543956Y-1107249D02*
X3544340Y-1106377D01*
X3545683D01*
X3543956Y-1107249D01*
G37*
G36*
G01X3548946D02*
X3548562Y-1106595D01*
X3549714Y-1106813D01*
X3548946Y-1107249D01*
G37*
G36*
G01X3545107Y-1107031D02*
X3544915Y-1107466D01*
X3543956Y-1107249D01*
X3545107Y-1107031D01*
G37*
G36*
G01X3548946Y-1107249D02*
X3549714Y-1106813D01*
X3548946Y-1107684D01*
Y-1107249D01*
G37*
G36*
G01X3549714Y-1106813D02*
X3549906Y-1107684D01*
X3548946D01*
X3549714Y-1106813D01*
G37*
G36*
G01X3544723Y-1108120D02*
X3543764Y-1108555D01*
X3544915Y-1107466D01*
X3544723Y-1108120D01*
G37*
G36*
G01X3543764Y-1108555D02*
X3543956Y-1107249D01*
X3544915Y-1107466D01*
X3543764Y-1108555D01*
G37*
G36*
G01X3544723Y-1108120D02*
Y-1108991D01*
X3543764Y-1108555D01*
X3544723Y-1108120D01*
G37*
G36*
G01X3544915Y-1109644D02*
X3543956Y-1109862D01*
X3544723Y-1108991D01*
X3544915Y-1109644D01*
G37*
G36*
G01X3543956Y-1109862D02*
X3543764Y-1108555D01*
X3544723Y-1108991D01*
X3543956Y-1109862D01*
G37*
G36*
G01X3544915Y-1109644D02*
X3545107Y-1110080D01*
X3543956Y-1109862D01*
X3544915Y-1109644D01*
G37*
G36*
G01X3548754Y-1110515D02*
X3548946Y-1109862D01*
X3549906D01*
X3548754Y-1110515D01*
G37*
G36*
G01X3544340Y-1110733D02*
X3543956Y-1109862D01*
X3545107Y-1110080D01*
X3544340Y-1110733D01*
G37*
G36*
G01X3545107Y-1110080D02*
X3545683Y-1110733D01*
X3544340D01*
X3545107Y-1110080D01*
G37*
G36*
G01X3549906Y-1109862D02*
X3549714Y-1110733D01*
X3548754Y-1110515D01*
X3549906Y-1109862D01*
G37*
G36*
G01X3548178Y-1110951D02*
X3548754Y-1110515D01*
X3549714Y-1110733D01*
X3548178Y-1110951D01*
G37*
G36*
G01X3546067D02*
X3544723Y-1111169D01*
X3545683Y-1110733D01*
X3546067Y-1110951D01*
G37*
G36*
G01X3544723Y-1111169D02*
X3544340Y-1110733D01*
X3545683D01*
X3544723Y-1111169D01*
G37*
G36*
G01X3546067Y-1110951D02*
X3546835Y-1111169D01*
X3544723D01*
X3546067Y-1110951D01*
G37*
G36*
G01X3548178D02*
X3549714Y-1110733D01*
X3546835Y-1111169D01*
X3548178Y-1110951D01*
G37*
G36*
G01X3549714Y-1110733D02*
X3549138Y-1111386D01*
X3546835Y-1111169D01*
X3549714Y-1110733D01*
G37*
G36*
G01X3549138Y-1111386D02*
X3545299Y-1111604D01*
X3546835Y-1111169D01*
X3549138Y-1111386D01*
G37*
G36*
G01X3545299Y-1111604D02*
X3544723Y-1111169D01*
X3546835D01*
X3545299Y-1111604D01*
G37*
G36*
G01D02*
X3549138Y-1111386D01*
X3545875Y-1111822D01*
X3545299Y-1111604D01*
G37*
G36*
G01X3549138Y-1111386D02*
X3548370Y-1111822D01*
X3545875D01*
X3549138Y-1111386D01*
G37*
G36*
G01X3547026Y-1112040D02*
X3545875Y-1111822D01*
X3548370D01*
X3547026Y-1112040D01*
G37*
G36*
G01X3549906Y-1107684D02*
X3544723D01*
Y-1108555D01*
X3549906D01*
Y-1107684D01*
G37*
G36*
G01X3551441Y-1101804D02*
Y-1112040D01*
X3552401D01*
Y-1101804D01*
X3551441D01*
G37*
G36*
G01X3552401Y-1107031D02*
Y-1106159D01*
X3552785Y-1106595D01*
X3552401Y-1107031D01*
G37*
G36*
G01X3555663Y-1106813D02*
X3556623Y-1106595D01*
X3555855Y-1107684D01*
X3555663Y-1106813D01*
G37*
G36*
G01X3556623Y-1106595D02*
X3556815Y-1107684D01*
X3555855D01*
X3556623Y-1106595D01*
G37*
G36*
G01X3555855Y-1112040D02*
Y-1107684D01*
X3556815D01*
X3555855Y-1112040D01*
G37*
G36*
G01X3556815Y-1107684D02*
Y-1112040D01*
X3555855D01*
X3556815Y-1107684D01*
G37*
G36*
G01X3539016Y-1075947D02*
Y-1086183D01*
X3540168D01*
Y-1075947D01*
X3539016D01*
G37*
G36*
G01X3544390D02*
X3540168Y-1080956D01*
Y-1082699D01*
X3545926Y-1075947D01*
X3544390D01*
G37*
G36*
G01X3540936Y-1080085D02*
X3544390Y-1086183D01*
X3545926D01*
X3542471Y-1080085D01*
X3540936D01*
G37*
G36*
G01X3548421Y-1079432D02*
X3549764Y-1079214D01*
X3550916D01*
X3548421Y-1079432D01*
G37*
G36*
G01X3550916Y-1079214D02*
X3552067Y-1079432D01*
X3548421D01*
X3550916Y-1079214D01*
G37*
G36*
G01X3548037Y-1079649D02*
X3548421Y-1079432D01*
X3552067D01*
X3548037Y-1079649D01*
G37*
G36*
G01X3552067Y-1079432D02*
X3552451Y-1079649D01*
X3548037D01*
X3552067Y-1079432D01*
G37*
G36*
G01X3547653Y-1080085D02*
X3548037Y-1079649D01*
X3552451D01*
X3547653Y-1080085D01*
G37*
G36*
G01D02*
X3552451Y-1079649D01*
X3549764Y-1080085D01*
X3547653D01*
G37*
G36*
G01X3549764D02*
X3552451Y-1079649D01*
X3550916Y-1080085D01*
X3549764D01*
G37*
G36*
G01X3550916D02*
X3552451Y-1079649D01*
X3551683Y-1080303D01*
X3550916Y-1080085D01*
G37*
G36*
G01X3552451Y-1079649D02*
X3553027Y-1080303D01*
X3551683D01*
X3552451Y-1079649D01*
G37*
G36*
G01X3548996Y-1080303D02*
X3547461Y-1080521D01*
X3549764Y-1080085D01*
X3548996Y-1080303D01*
G37*
G36*
G01X3547461Y-1080521D02*
X3547653Y-1080085D01*
X3549764D01*
X3547461Y-1080521D01*
G37*
G36*
G01X3548996Y-1080303D02*
X3548613Y-1080521D01*
X3547461D01*
X3548996Y-1080303D01*
G37*
G36*
G01X3552067Y-1080521D02*
X3551683Y-1080303D01*
X3553027D01*
X3552067Y-1080521D01*
G37*
G36*
G01X3547461Y-1080956D02*
Y-1080521D01*
X3548613D01*
X3547461Y-1080956D01*
G37*
G36*
G01X3548613Y-1080521D02*
X3548421Y-1080956D01*
X3547461D01*
X3548613Y-1080521D01*
G37*
G36*
G01X3552067D02*
X3553027Y-1080303D01*
X3552259Y-1080956D01*
X3552067Y-1080521D01*
G37*
G36*
G01X3553027Y-1080303D02*
X3553219Y-1080956D01*
X3552259D01*
X3553027Y-1080303D01*
G37*
G36*
G01X3553219Y-1084441D02*
X3552259Y-1084877D01*
X3553219Y-1080956D01*
Y-1084441D01*
G37*
G36*
G01X3552259Y-1084877D02*
Y-1080956D01*
X3553219D01*
X3552259Y-1084877D01*
G37*
G36*
G01X3553219Y-1084441D02*
X3553411Y-1085530D01*
X3552259Y-1084877D01*
X3553219Y-1084441D01*
G37*
G36*
G01X3552451Y-1085748D02*
X3552259Y-1084877D01*
X3553411Y-1085530D01*
X3552451Y-1085748D01*
G37*
G36*
G01D02*
X3553411Y-1085530D01*
X3552643Y-1086183D01*
X3552451Y-1085748D01*
G37*
G36*
G01X3553411Y-1085530D02*
X3553603Y-1086183D01*
X3552643D01*
X3553411Y-1085530D01*
G37*
G36*
G01X3548996Y-1081827D02*
X3550148Y-1081610D01*
X3552451D01*
X3548996Y-1081827D01*
G37*
G36*
G01D02*
X3552451Y-1081610D01*
X3548229Y-1082263D01*
X3548996Y-1081827D01*
G37*
G36*
G01X3548229Y-1082263D02*
X3552451Y-1081610D01*
X3550148Y-1082481D01*
X3548229Y-1082263D01*
G37*
G36*
G01X3552451Y-1081610D02*
Y-1082481D01*
X3550148D01*
X3552451Y-1081610D01*
G37*
G36*
G01X3547845Y-1082699D02*
X3548229Y-1082263D01*
X3550148Y-1082481D01*
X3547845Y-1082699D01*
G37*
G36*
G01X3550148Y-1082481D02*
X3549380Y-1082699D01*
X3547845D01*
X3550148Y-1082481D01*
G37*
G36*
G01X3548613Y-1083352D02*
X3547461Y-1083570D01*
X3548996Y-1082916D01*
X3548613Y-1083352D01*
G37*
G36*
G01X3548996Y-1082916D02*
X3547461Y-1083570D01*
X3549380Y-1082699D01*
X3548996Y-1082916D01*
G37*
G36*
G01X3547461Y-1083570D02*
X3547845Y-1082699D01*
X3549380D01*
X3547461Y-1083570D01*
G37*
G36*
G01X3548613Y-1083352D02*
X3548421Y-1084005D01*
X3547461Y-1083570D01*
X3548613Y-1083352D01*
G37*
G36*
G01X3547461Y-1084223D02*
Y-1083570D01*
X3548421Y-1084005D01*
X3547461Y-1084223D01*
G37*
G36*
G01X3548421Y-1084005D02*
Y-1084441D01*
X3547461Y-1084223D01*
X3548421Y-1084005D01*
G37*
G36*
G01X3551492Y-1084877D02*
X3552067Y-1084223D01*
X3552451Y-1084877D01*
X3551492D01*
G37*
G36*
G01X3552451Y-1083570D02*
Y-1084877D01*
X3552067Y-1084223D01*
X3552451Y-1083570D01*
G37*
G36*
G01X3548613Y-1084877D02*
X3547653Y-1085094D01*
X3548421Y-1084441D01*
X3548613Y-1084877D01*
G37*
G36*
G01X3547653Y-1085094D02*
X3547461Y-1084223D01*
X3548421Y-1084441D01*
X3547653Y-1085094D01*
G37*
G36*
G01X3548613Y-1084877D02*
X3548996Y-1085094D01*
X3547653D01*
X3548613Y-1084877D01*
G37*
G36*
G01X3547845Y-1085312D02*
X3547653Y-1085094D01*
X3548996D01*
X3547845Y-1085312D01*
G37*
G36*
G01X3548996Y-1085094D02*
X3549380Y-1085312D01*
X3547845D01*
X3548996Y-1085094D01*
G37*
G36*
G01X3550532Y-1085312D02*
X3551492Y-1084877D01*
X3552451D01*
X3550532Y-1085312D01*
G37*
G36*
G01X3552451Y-1084877D02*
X3552067Y-1085530D01*
X3550532Y-1085312D01*
X3552451Y-1084877D01*
G37*
G36*
G01X3552067Y-1085530D02*
X3548229Y-1085748D01*
X3550532Y-1085312D01*
X3552067Y-1085530D01*
G37*
G36*
G01X3550532Y-1085312D02*
X3548229Y-1085748D01*
X3549380Y-1085312D01*
X3550532D01*
G37*
G36*
G01X3548229Y-1085748D02*
X3547845Y-1085312D01*
X3549380D01*
X3548229Y-1085748D01*
G37*
G36*
G01D02*
X3552067Y-1085530D01*
X3548613Y-1085966D01*
X3548229Y-1085748D01*
G37*
G36*
G01X3552067Y-1085530D02*
X3551492Y-1085966D01*
X3548613D01*
X3552067Y-1085530D01*
G37*
G36*
G01X3549380Y-1086183D02*
X3548613Y-1085966D01*
X3551492D01*
X3549380Y-1086183D01*
G37*
G36*
G01X3551492Y-1085966D02*
X3550532Y-1086183D01*
X3549380D01*
X3551492Y-1085966D01*
G37*
G36*
G01X3556674Y-1079432D02*
X3557442Y-1079214D01*
X3556290Y-1079649D01*
X3556674Y-1079432D01*
G37*
G36*
G01X3556290Y-1079649D02*
X3557442Y-1079214D01*
X3555906Y-1080085D01*
X3556290Y-1079649D01*
G37*
G36*
G01X3557442Y-1079214D02*
X3557825Y-1080085D01*
X3555906D01*
X3557442Y-1079214D01*
G37*
G36*
G01X3557825Y-1080085D02*
X3557057Y-1080303D01*
X3555906Y-1080085D01*
X3557825D01*
G37*
G36*
G01X3555522Y-1080738D02*
X3555906Y-1080085D01*
X3557057Y-1080303D01*
X3555522Y-1080738D01*
G37*
G36*
G01X3557057Y-1080303D02*
X3556674Y-1080738D01*
X3555522D01*
X3557057Y-1080303D01*
G37*
G36*
G01X3555330Y-1081392D02*
X3555522Y-1080738D01*
X3556674D01*
X3555330Y-1081392D01*
G37*
G36*
G01X3556674Y-1080738D02*
X3556290Y-1081392D01*
X3555330D01*
X3556674Y-1080738D01*
G37*
G36*
G01X3555139Y-1082263D02*
X3555330Y-1081392D01*
X3556290D01*
X3555139Y-1082263D01*
G37*
G36*
G01X3556290Y-1081392D02*
X3556098Y-1082263D01*
X3555139D01*
X3556290Y-1081392D01*
G37*
G36*
G01X3555139Y-1083134D02*
Y-1082263D01*
X3556098D01*
X3555139Y-1083134D01*
G37*
G36*
G01X3556098Y-1082263D02*
Y-1083134D01*
X3555139D01*
X3556098Y-1082263D01*
G37*
G36*
G01X3555330Y-1084005D02*
X3555139Y-1083134D01*
X3556098D01*
X3555330Y-1084005D01*
G37*
G36*
G01X3556098Y-1083134D02*
X3556290Y-1084005D01*
X3555330D01*
X3556098Y-1083134D01*
G37*
G36*
G01X3555522Y-1084659D02*
X3555330Y-1084005D01*
X3556290D01*
X3555522Y-1084659D01*
G37*
G36*
G01X3556290Y-1084005D02*
X3556674Y-1084659D01*
X3555522D01*
X3556290Y-1084005D01*
G37*
G36*
G01X3557057Y-1085094D02*
X3555906Y-1085312D01*
X3556674Y-1084659D01*
X3557057Y-1085094D01*
G37*
G36*
G01X3555906Y-1085312D02*
X3555522Y-1084659D01*
X3556674D01*
X3555906Y-1085312D01*
G37*
G36*
G01X3557057Y-1085094D02*
X3557825Y-1085312D01*
X3555906D01*
X3557057Y-1085094D01*
G37*
G36*
G01X3558593Y-1085312D02*
X3556290Y-1085748D01*
X3557825Y-1085312D01*
X3558593D01*
G37*
G36*
G01X3556290Y-1085748D02*
X3555906Y-1085312D01*
X3557825D01*
X3556290Y-1085748D01*
G37*
G36*
G01D02*
X3558593Y-1085312D01*
X3556674Y-1085966D01*
X3556290Y-1085748D01*
G37*
G36*
G01X3556674Y-1085966D02*
X3558593Y-1085312D01*
X3557442Y-1086183D01*
X3556674Y-1085966D01*
G37*
G36*
G01X3558593Y-1085312D02*
X3558977Y-1086183D01*
X3557442D01*
X3558593Y-1085312D01*
G37*
G36*
G01X3560128Y-1079649D02*
X3557825Y-1080085D01*
X3559745Y-1079432D01*
X3560128Y-1079649D01*
G37*
G36*
G01X3559745Y-1079432D02*
X3557825Y-1080085D01*
X3558977Y-1079214D01*
X3559745Y-1079432D01*
G37*
G36*
G01X3557825Y-1080085D02*
X3557442Y-1079214D01*
X3558977D01*
X3557825Y-1080085D01*
G37*
G36*
G01D02*
X3560128Y-1079649D01*
X3558593Y-1080085D01*
X3557825D01*
G37*
G36*
G01X3560128Y-1079649D02*
X3560513Y-1080085D01*
X3558593D01*
X3560128Y-1079649D01*
G37*
G36*
G01X3559361Y-1080303D02*
X3558593Y-1080085D01*
X3560513D01*
X3559361Y-1080303D01*
G37*
G36*
G01D02*
X3560513Y-1080085D01*
X3559745Y-1080738D01*
X3559361Y-1080303D01*
G37*
G36*
G01X3560513Y-1080085D02*
X3560896Y-1080738D01*
X3559745D01*
X3560513Y-1080085D01*
G37*
G36*
G01X3560128Y-1081392D02*
X3559745Y-1080738D01*
X3560896D01*
X3560128Y-1081392D01*
G37*
G36*
G01X3560896Y-1080738D02*
X3561088Y-1081392D01*
X3560128D01*
X3560896Y-1080738D01*
G37*
G36*
G01X3560320Y-1082263D02*
X3560128Y-1081392D01*
X3561088D01*
X3560320Y-1082263D01*
G37*
G36*
G01X3561088Y-1081392D02*
X3561280Y-1082263D01*
X3560320D01*
X3561088Y-1081392D01*
G37*
G36*
G01X3560320Y-1083134D02*
Y-1082263D01*
X3561280D01*
X3560320Y-1083134D01*
G37*
G36*
G01X3561280Y-1082263D02*
Y-1083134D01*
X3560320D01*
X3561280Y-1082263D01*
G37*
G36*
G01X3560128Y-1084005D02*
X3560320Y-1083134D01*
X3561280D01*
X3560128Y-1084005D01*
G37*
G36*
G01X3561280Y-1083134D02*
X3561088Y-1084005D01*
X3560128D01*
X3561280Y-1083134D01*
G37*
G36*
G01X3559745Y-1084659D02*
X3560128Y-1084005D01*
X3561088D01*
X3559745Y-1084659D01*
G37*
G36*
G01X3561088Y-1084005D02*
X3560896Y-1084659D01*
X3559745D01*
X3561088Y-1084005D01*
G37*
G36*
G01X3559361Y-1085094D02*
X3559745Y-1084659D01*
X3560896D01*
X3559361Y-1085094D01*
G37*
G36*
G01X3558593Y-1085312D02*
X3559361Y-1085094D01*
X3560513Y-1085312D01*
X3558593D01*
G37*
G36*
G01X3560896Y-1084659D02*
X3560513Y-1085312D01*
X3559361Y-1085094D01*
X3560896Y-1084659D01*
G37*
G36*
G01X3559745Y-1085966D02*
X3558977Y-1086183D01*
X3560128Y-1085748D01*
X3559745Y-1085966D01*
G37*
G36*
G01X3560128Y-1085748D02*
X3558977Y-1086183D01*
X3560513Y-1085312D01*
X3560128Y-1085748D01*
G37*
G36*
G01X3558977Y-1086183D02*
X3558593Y-1085312D01*
X3560513D01*
X3558977Y-1086183D01*
G37*
G36*
G01X3538582Y-1106377D02*
X3539350Y-1105942D01*
X3538774Y-1106813D01*
X3538582Y-1106377D01*
G37*
G36*
G01X3539350Y-1105942D02*
X3539733Y-1106813D01*
X3538774D01*
X3539350Y-1105942D01*
G37*
G36*
G01X3541269Y-1101804D02*
Y-1102893D01*
X3542228D01*
Y-1101804D01*
X3541269D01*
G37*
G36*
G01X3547026Y-1105071D02*
X3548178Y-1105288D01*
X3545875D01*
X3547026Y-1105071D01*
G37*
G36*
G01X3545299Y-1105506D02*
X3545875Y-1105288D01*
X3548178D01*
X3545299Y-1105506D01*
G37*
G36*
G01D02*
X3548178Y-1105288D01*
X3544723Y-1105942D01*
X3545299Y-1105506D01*
G37*
G36*
G01X3544723Y-1105942D02*
X3548178Y-1105288D01*
X3546835Y-1105942D01*
X3544723D01*
G37*
G36*
G01X3548178Y-1105288D02*
X3549138Y-1105942D01*
X3546835D01*
X3548178Y-1105288D01*
G37*
G36*
G01X3547986Y-1106159D02*
X3546835Y-1105942D01*
X3549138D01*
X3547986Y-1106159D01*
G37*
G36*
G01X3546067D02*
X3544340Y-1106377D01*
X3546835Y-1105942D01*
X3546067Y-1106159D01*
G37*
G36*
G01X3544340Y-1106377D02*
X3544723Y-1105942D01*
X3546835D01*
X3544340Y-1106377D01*
G37*
G36*
G01X3546067Y-1106159D02*
X3545683Y-1106377D01*
X3544340D01*
X3546067Y-1106159D01*
G37*
G36*
G01X3547986D02*
X3549138Y-1105942D01*
X3548562Y-1106595D01*
X3547986Y-1106159D01*
G37*
G36*
G01X3549138Y-1105942D02*
X3549714Y-1106813D01*
X3548562Y-1106595D01*
X3549138Y-1105942D01*
G37*
G36*
G01X3553360Y-1105288D02*
X3554128Y-1105071D01*
X3554896D01*
X3553360Y-1105288D01*
G37*
G36*
G01X3554896Y-1105071D02*
X3555472Y-1105288D01*
X3553360D01*
X3554896Y-1105071D01*
G37*
G36*
G01X3552785Y-1105724D02*
X3553360Y-1105288D01*
X3555472D01*
X3552785Y-1105724D01*
G37*
G36*
G01X3555472Y-1105288D02*
X3556047Y-1105724D01*
X3552785D01*
X3555472Y-1105288D01*
G37*
G36*
G01X3556047Y-1105724D02*
X3554128Y-1105942D01*
X3552785Y-1105724D01*
X3556047D01*
G37*
G36*
G01X3552401Y-1106159D02*
X3552785Y-1105724D01*
X3554128Y-1105942D01*
X3552401Y-1106159D01*
G37*
G36*
G01X3554128Y-1105942D02*
X3553360Y-1106159D01*
X3552401D01*
X3554128Y-1105942D01*
G37*
G36*
G01D02*
X3556047Y-1105724D01*
X3554896Y-1106159D01*
X3554128Y-1105942D01*
G37*
G36*
G01X3556047Y-1105724D02*
X3556431Y-1106159D01*
X3554896D01*
X3556047Y-1105724D01*
G37*
G36*
G01X3555280Y-1106377D02*
X3554896Y-1106159D01*
X3556431D01*
X3555280Y-1106377D01*
G37*
G36*
G01X3556431Y-1106159D02*
X3556623Y-1106595D01*
X3555280Y-1106377D01*
X3556431Y-1106159D01*
G37*
G36*
G01X3555663Y-1106813D02*
X3555280Y-1106377D01*
X3556623Y-1106595D01*
X3555663Y-1106813D01*
G37*
G36*
G01X3553360Y-1106159D02*
X3552785Y-1106595D01*
X3552401Y-1106159D01*
X3553360D01*
G37*
G36*
G01X3538924Y-1052154D02*
Y-1053075D01*
X3539502D01*
Y-1052154D01*
X3538924D01*
G37*
G36*
G01Y-1061184D02*
Y-1054918D01*
X3539646D01*
X3538924Y-1061184D01*
G37*
G36*
G01X3539646Y-1054918D02*
Y-1061184D01*
X3538924D01*
X3539646Y-1054918D01*
G37*
G36*
G01X3538780Y-1061921D02*
X3538924Y-1061184D01*
X3539646D01*
X3538780Y-1061921D01*
G37*
G36*
G01X3539646Y-1061184D02*
X3539502Y-1061921D01*
X3538780D01*
X3539646Y-1061184D01*
G37*
G36*
G01X3538636Y-1062290D02*
X3538780Y-1061921D01*
X3539502D01*
X3538636Y-1062290D01*
G37*
G36*
G01X3547730Y-1052154D02*
Y-1060816D01*
X3548596D01*
Y-1052154D01*
X3547730D01*
G37*
G36*
G01X3548596Y-1059710D02*
Y-1060816D01*
X3552927D01*
Y-1059710D01*
X3548596D01*
G37*
G36*
G01X3554082Y-1052154D02*
Y-1053075D01*
X3554804D01*
Y-1052154D01*
X3554082D01*
G37*
G36*
G01Y-1054918D02*
Y-1060816D01*
X3554804D01*
Y-1054918D01*
X3554082D01*
G37*
G36*
G01X3555958D02*
Y-1060816D01*
X3556680D01*
Y-1054918D01*
X3555958D01*
G37*
G36*
G01X3557402Y-1055103D02*
X3557980Y-1054918D01*
X3558557D01*
X3557402Y-1055103D01*
G37*
G36*
G01X3558557Y-1054918D02*
X3558990Y-1055103D01*
X3557402D01*
X3558557Y-1054918D01*
G37*
G36*
G01X3556969Y-1055471D02*
X3557402Y-1055103D01*
X3558990D01*
X3556969Y-1055471D01*
G37*
G36*
G01X3558990Y-1055103D02*
X3559423Y-1055471D01*
X3556969D01*
X3558990Y-1055103D01*
G37*
G36*
G01X3559423Y-1055471D02*
X3557980Y-1055655D01*
X3556969Y-1055471D01*
X3559423D01*
G37*
G36*
G01X3556680Y-1055840D02*
X3556969Y-1055471D01*
X3557980Y-1055655D01*
X3556680Y-1055840D01*
G37*
G36*
G01X3557980Y-1055655D02*
X3557402Y-1055840D01*
X3556680D01*
X3557980Y-1055655D01*
G37*
G36*
G01D02*
X3559423Y-1055471D01*
X3558557Y-1055840D01*
X3557980Y-1055655D01*
G37*
G36*
G01X3559423Y-1055471D02*
X3559712Y-1055840D01*
X3558557D01*
X3559423Y-1055471D01*
G37*
G36*
G01X3558846Y-1056024D02*
X3558557Y-1055840D01*
X3559712D01*
X3558846Y-1056024D01*
G37*
G36*
G01X3559712Y-1055840D02*
X3559856Y-1056208D01*
X3558846Y-1056024D01*
X3559712Y-1055840D01*
G37*
G36*
G01X3559134Y-1056393D02*
X3558846Y-1056024D01*
X3559856Y-1056208D01*
X3559134Y-1056393D01*
G37*
G36*
G01X3557402Y-1055840D02*
X3556969Y-1056208D01*
X3556680Y-1055840D01*
X3557402D01*
G37*
G36*
G01X3556680Y-1056577D02*
Y-1055840D01*
X3556969Y-1056208D01*
X3556680Y-1056577D01*
G37*
G36*
G01X3559134Y-1056393D02*
X3559856Y-1056208D01*
X3559279Y-1057130D01*
X3559134Y-1056393D01*
G37*
G36*
G01X3559856Y-1056208D02*
X3560000Y-1057130D01*
X3559279D01*
X3559856Y-1056208D01*
G37*
G36*
G01X3559279Y-1060816D02*
Y-1057130D01*
X3560000D01*
X3559279Y-1060816D01*
G37*
G36*
G01X3560000Y-1057130D02*
Y-1060816D01*
X3559279D01*
X3560000Y-1057130D01*
G37*
G36*
G01X3538924Y-1027438D02*
Y-1028360D01*
X3539502D01*
Y-1027438D01*
X3538924D01*
G37*
G36*
G01X3554082D02*
Y-1028360D01*
X3554804D01*
Y-1027438D01*
X3554082D01*
G37*
G36*
G01X3557402Y-1030387D02*
X3557980Y-1030203D01*
X3558557D01*
X3557402Y-1030387D01*
G37*
G36*
G01X3558557Y-1030203D02*
X3558990Y-1030387D01*
X3557402D01*
X3558557Y-1030203D01*
G37*
G36*
G01X3556969Y-1030755D02*
X3557402Y-1030387D01*
X3558990D01*
X3556969Y-1030755D01*
G37*
G36*
G01X3558990Y-1030387D02*
X3559423Y-1030755D01*
X3556969D01*
X3558990Y-1030387D01*
G37*
G36*
G01X3559423Y-1030755D02*
X3557980Y-1030940D01*
X3556969Y-1030755D01*
X3559423D01*
G37*
G36*
G01X3556680Y-1031124D02*
X3556969Y-1030755D01*
X3557980Y-1030940D01*
X3556680Y-1031124D01*
G37*
G36*
G01X3557980Y-1030940D02*
X3557402Y-1031124D01*
X3556680D01*
X3557980Y-1030940D01*
G37*
G36*
G01D02*
X3559423Y-1030755D01*
X3558557Y-1031124D01*
X3557980Y-1030940D01*
G37*
G36*
G01X3559423Y-1030755D02*
X3559712Y-1031124D01*
X3558557D01*
X3559423Y-1030755D01*
G37*
G36*
G01X3558846Y-1031308D02*
X3558557Y-1031124D01*
X3559712D01*
X3558846Y-1031308D01*
G37*
G36*
G01X3559712Y-1031124D02*
X3559856Y-1031492D01*
X3558846Y-1031308D01*
X3559712Y-1031124D01*
G37*
G36*
G01X3559134Y-1031677D02*
X3558846Y-1031308D01*
X3559856Y-1031492D01*
X3559134Y-1031677D01*
G37*
G36*
G01X3557402Y-1031124D02*
X3556969Y-1031492D01*
X3556680Y-1031124D01*
X3557402D01*
G37*
G36*
G01X3556680Y-1031861D02*
Y-1031124D01*
X3556969Y-1031492D01*
X3556680Y-1031861D01*
G37*
G36*
G01X3559134Y-1031677D02*
X3559856Y-1031492D01*
X3559279Y-1032414D01*
X3559134Y-1031677D01*
G37*
G36*
G01X3559856Y-1031492D02*
X3560000Y-1032414D01*
X3559279D01*
X3559856Y-1031492D01*
G37*
G36*
G01X3538924Y-1036468D02*
Y-1030203D01*
X3539646D01*
X3538924Y-1036468D01*
G37*
G36*
G01X3539646Y-1030203D02*
Y-1036468D01*
X3538924D01*
X3539646Y-1030203D01*
G37*
G36*
G01X3538780Y-1037205D02*
X3538924Y-1036468D01*
X3539646D01*
X3538780Y-1037205D01*
G37*
G36*
G01X3539646Y-1036468D02*
X3539502Y-1037205D01*
X3538780D01*
X3539646Y-1036468D01*
G37*
G36*
G01X3538636Y-1037574D02*
X3538780Y-1037205D01*
X3539502D01*
X3538636Y-1037574D01*
G37*
G36*
G01X3547730Y-1027438D02*
Y-1036100D01*
X3548596D01*
Y-1027438D01*
X3547730D01*
G37*
G36*
G01X3548596Y-1034994D02*
Y-1036100D01*
X3552927D01*
Y-1034994D01*
X3548596D01*
G37*
G36*
G01X3554082Y-1030203D02*
Y-1036100D01*
X3554804D01*
Y-1030203D01*
X3554082D01*
G37*
G36*
G01X3555958D02*
Y-1036100D01*
X3556680D01*
Y-1030203D01*
X3555958D01*
G37*
G36*
G01X3559279Y-1036100D02*
Y-1032414D01*
X3560000D01*
X3559279Y-1036100D01*
G37*
G36*
G01X3560000Y-1032414D02*
Y-1036100D01*
X3559279D01*
X3560000Y-1032414D01*
G37*
G36*
G01X3564057Y-983071D02*
Y-1002756D01*
X3565780D01*
Y-983071D01*
X3564057D01*
G37*
G36*
G01X3568651D02*
Y-1002756D01*
X3570373D01*
Y-983071D01*
X3568651D01*
G37*
G36*
G01X3570373D02*
X3576689Y-1002756D01*
X3578411D01*
X3572096Y-983071D01*
X3570373D01*
G37*
G36*
G01X3541666Y-985165D02*
Y-1002756D01*
X3543388D01*
Y-985165D01*
X3541666D01*
G37*
G36*
G01X3550278Y-983071D02*
Y-1002756D01*
X3552000D01*
Y-983071D01*
X3550278D01*
G37*
G36*
G01X3552000D02*
X3558316Y-1002756D01*
X3560039D01*
X3553723Y-983071D01*
X3552000D01*
G37*
G36*
G01X3560039D02*
Y-1002756D01*
X3561761D01*
Y-983071D01*
X3560039D01*
G37*
G36*
G01X3585301Y-983490D02*
X3587024Y-983071D01*
X3588172D01*
X3585301Y-983490D01*
G37*
G36*
G01X3588172Y-983071D02*
X3591043Y-983490D01*
X3585301D01*
X3588172Y-983071D01*
G37*
G36*
G01X3584153Y-984746D02*
X3585301Y-983490D01*
X3591043D01*
X3584153Y-984746D01*
G37*
G36*
G01X3591043Y-983490D02*
X3592191Y-984746D01*
X3584153D01*
X3591043Y-983490D01*
G37*
G36*
G01X3583578Y-985584D02*
X3584153Y-984746D01*
X3592191D01*
X3583578Y-985584D01*
G37*
G36*
G01D02*
X3592191Y-984746D01*
X3587024Y-985584D01*
X3583578D01*
G37*
G36*
G01X3587024D02*
X3592191Y-984746D01*
X3589320Y-985584D01*
X3587024D01*
G37*
G36*
G01X3592191Y-984746D02*
X3592765Y-985584D01*
X3589320D01*
X3592191Y-984746D01*
G37*
G36*
G01X3590469Y-986003D02*
X3589320Y-985584D01*
X3592765D01*
X3590469Y-986003D01*
G37*
G36*
G01X3585014Y-986840D02*
X3582717Y-987259D01*
X3585875Y-986003D01*
X3585014Y-986840D01*
G37*
G36*
G01X3587024Y-985584D02*
X3585875Y-986003D01*
X3583578Y-985584D01*
X3587024D01*
G37*
G36*
G01X3582717Y-987259D02*
X3583578Y-985584D01*
X3585875Y-986003D01*
X3582717Y-987259D01*
G37*
G36*
G01X3590469Y-986003D02*
X3592765Y-985584D01*
X3591330Y-986840D01*
X3590469Y-986003D01*
G37*
G36*
G01X3592765Y-985584D02*
X3593626Y-987259D01*
X3591330Y-986840D01*
X3592765Y-985584D01*
G37*
G36*
G01X3585014Y-986840D02*
X3584440Y-988097D01*
X3582717Y-987259D01*
X3585014Y-986840D01*
G37*
G36*
G01X3591617Y-988097D02*
X3591330Y-986840D01*
X3593626Y-987259D01*
X3591617Y-988097D01*
G37*
G36*
G01X3593626Y-987259D02*
Y-988097D01*
X3591617D01*
X3593626Y-987259D01*
G37*
G36*
G01X3582430Y-989772D02*
X3582717Y-987259D01*
X3584440Y-988097D01*
X3582430Y-989772D01*
G37*
G36*
G01X3584440Y-988097D02*
X3584153Y-989772D01*
X3582430D01*
X3584440Y-988097D01*
G37*
G36*
G01X3589320Y-994379D02*
Y-991866D01*
X3593626D01*
X3589320Y-994379D01*
G37*
G36*
G01X3582430Y-996054D02*
Y-989772D01*
X3584153D01*
X3582430Y-996054D01*
G37*
G36*
G01X3584153Y-989772D02*
Y-996054D01*
X3582430D01*
X3584153Y-989772D01*
G37*
G36*
G01X3584440Y-997730D02*
X3582717Y-998567D01*
X3584153Y-996054D01*
X3584440Y-997730D01*
G37*
G36*
G01X3582717Y-998567D02*
X3582430Y-996054D01*
X3584153D01*
X3582717Y-998567D01*
G37*
G36*
G01X3589320Y-994379D02*
X3593626Y-991866D01*
X3591904Y-994379D01*
X3589320D01*
G37*
G36*
G01X3591904D02*
X3593626Y-991866D01*
X3591904Y-997730D01*
Y-994379D01*
G37*
G36*
G01X3593626Y-991866D02*
Y-998567D01*
X3591904Y-997730D01*
X3593626Y-991866D01*
G37*
G36*
G01X3584440Y-997730D02*
X3585014Y-998986D01*
X3582717Y-998567D01*
X3584440Y-997730D01*
G37*
G36*
G01X3591330Y-998986D02*
X3591904Y-997730D01*
X3593626Y-998567D01*
X3591330Y-998986D01*
G37*
G36*
G01X3585875Y-999824D02*
X3583578Y-1000243D01*
X3585014Y-998986D01*
X3585875Y-999824D01*
G37*
G36*
G01X3583578Y-1000243D02*
X3582717Y-998567D01*
X3585014Y-998986D01*
X3583578Y-1000243D01*
G37*
G36*
G01X3585875Y-999824D02*
X3587024Y-1000243D01*
X3583578D01*
X3585875Y-999824D01*
G37*
G36*
G01X3591330Y-998986D02*
X3593626Y-998567D01*
X3590469Y-999824D01*
X3591330Y-998986D01*
G37*
G36*
G01X3589320Y-1000243D02*
X3590469Y-999824D01*
X3592765Y-1000243D01*
X3589320D01*
G37*
G36*
G01X3593626Y-998567D02*
X3592765Y-1000243D01*
X3590469Y-999824D01*
X3593626Y-998567D01*
G37*
G36*
G01X3578411Y-983071D02*
Y-1002756D01*
X3580133D01*
Y-983071D01*
X3578411D01*
G37*
G36*
G01X3592765Y-1000243D02*
X3584153Y-1001080D01*
X3589320Y-1000243D01*
X3592765D01*
G37*
G36*
G01X3589320D02*
X3584153Y-1001080D01*
X3587024Y-1000243D01*
X3589320D01*
G37*
G36*
G01X3584153Y-1001080D02*
X3583578Y-1000243D01*
X3587024D01*
X3584153Y-1001080D01*
G37*
G36*
G01X3592765Y-1000243D02*
X3592191Y-1001080D01*
X3584153D01*
X3592765Y-1000243D01*
G37*
G36*
G01X3585301Y-1002337D02*
X3584153Y-1001080D01*
X3592191D01*
X3585301Y-1002337D01*
G37*
G36*
G01X3592191Y-1001080D02*
X3591043Y-1002337D01*
X3585301D01*
X3592191Y-1001080D01*
G37*
G36*
G01X3587024Y-1002756D02*
X3585301Y-1002337D01*
X3591043D01*
X3587024Y-1002756D01*
G37*
G36*
G01X3591043Y-1002337D02*
X3589320Y-1002756D01*
X3587024D01*
X3591043Y-1002337D01*
G37*
G36*
G01X3641156Y-1083306D02*
X3631196Y-1096484D01*
X3637251Y-1083306D01*
X3641156D01*
G37*
G36*
G01X3646196Y-1088675D02*
X3639574Y-1102991D01*
X3642617Y-1088675D01*
X3646196D01*
G37*
G36*
G01X3639574Y-1102991D02*
X3646196Y-1088675D01*
X3643154Y-1102991D01*
X3639574D01*
G37*
G36*
G01X3630256Y-1083306D02*
X3627359Y-1088512D01*
X3619971Y-1096484D01*
X3630256Y-1083306D01*
G37*
G36*
G01D02*
X3619971Y-1096484D01*
X3626514Y-1083306D01*
X3630256D01*
G37*
G36*
G01X3627359Y-1088512D02*
X3630256Y-1083306D01*
X3631196Y-1096484D01*
X3627359Y-1088512D01*
G37*
G36*
G01X3619518Y-1083306D02*
X3619971Y-1096484D01*
X3616798Y-1102991D01*
X3619518Y-1083306D01*
G37*
G36*
G01D02*
X3616798Y-1102991D01*
X3615776Y-1083306D01*
X3619518D01*
G37*
G36*
G01X3616798Y-1102991D02*
X3619971Y-1096484D01*
X3627359Y-1088512D01*
X3616798Y-1102991D01*
G37*
G36*
G01D02*
X3627359Y-1088512D01*
X3620215Y-1102991D01*
X3616798D01*
G37*
G36*
G01X3631196Y-1096484D02*
X3628186Y-1102991D01*
X3627359Y-1088512D01*
X3631196Y-1096484D01*
G37*
G36*
G01X3628186Y-1102991D02*
X3631196Y-1096484D01*
X3641156Y-1083306D01*
X3628186Y-1102991D01*
G37*
G36*
G01D02*
X3641156Y-1083306D01*
X3631603Y-1102991D01*
X3628186D01*
G37*
G36*
G01X3670620Y-1107709D02*
X3669866Y-1108197D01*
X3665765Y-1108360D01*
X3670620Y-1107709D01*
G37*
G36*
G01X3671444Y-1106896D02*
X3670620Y-1107709D01*
X3665765Y-1108360D01*
X3671444Y-1106896D01*
G37*
G36*
G01X3672268Y-1106082D02*
X3671444Y-1106896D01*
X3665765Y-1108360D01*
X3672268Y-1106082D01*
G37*
G36*
G01X3667979Y-1105594D02*
X3672268Y-1106082D01*
X3665765Y-1108360D01*
X3667979Y-1105594D01*
G37*
G36*
G01X3667851Y-1105432D02*
X3667979Y-1105594D01*
X3665765Y-1108360D01*
X3667851Y-1105432D01*
G37*
G36*
G01X3667363D02*
X3667851D01*
X3665765Y-1108360D01*
X3667363Y-1105432D01*
G37*
G36*
G01X3666875D02*
X3667363D01*
X3665765Y-1108360D01*
X3666875Y-1105432D01*
G37*
G36*
G01D02*
X3665765Y-1108360D01*
X3666456Y-1105106D01*
X3666875Y-1105432D01*
G37*
G36*
G01X3666671Y-1108685D02*
X3665765Y-1108360D01*
X3669866Y-1108197D01*
X3666671Y-1108685D01*
G37*
G36*
G01D02*
X3669866Y-1108197D01*
X3668786Y-1108685D01*
X3666671D01*
G37*
G36*
G01X3668786D02*
X3667776Y-1108848D01*
X3666671Y-1108685D01*
X3668786D01*
G37*
G36*
G01X3672714Y-1088675D02*
X3673904Y-1097623D01*
X3671042Y-1102666D01*
X3672714Y-1088675D01*
G37*
G36*
G01D02*
X3671042Y-1102666D01*
X3668972Y-1088675D01*
X3672714D01*
G37*
G36*
G01X3671042Y-1102666D02*
X3673904Y-1097623D01*
X3682638Y-1088675D01*
X3671042Y-1102666D01*
G37*
G36*
G01D02*
X3682638Y-1088675D01*
X3674424Y-1102829D01*
X3671042Y-1102666D01*
G37*
G36*
G01X3674424Y-1102829D02*
X3670346Y-1103642D01*
X3671042Y-1102666D01*
X3674424Y-1102829D01*
G37*
G36*
G01X3669488Y-1104618D02*
X3670346Y-1103642D01*
X3674424Y-1102829D01*
X3669488Y-1104618D01*
G37*
G36*
G01X3669094Y-1104944D02*
X3669488Y-1104618D01*
X3674424Y-1102829D01*
X3669094Y-1104944D01*
G37*
G36*
G01D02*
X3674424Y-1102829D01*
X3672998Y-1104944D01*
X3669094D01*
G37*
G36*
G01X3672998D02*
X3668699Y-1105269D01*
X3669094Y-1104944D01*
X3672998D01*
G37*
G36*
G01X3668339Y-1105432D02*
X3668699Y-1105269D01*
X3672998Y-1104944D01*
X3668339Y-1105432D01*
G37*
G36*
G01X3667979Y-1105594D02*
X3668339Y-1105432D01*
X3672998Y-1104944D01*
X3667979Y-1105594D01*
G37*
G36*
G01D02*
X3672998Y-1104944D01*
X3672268Y-1106082D01*
X3667979Y-1105594D01*
G37*
G36*
G01X3647372Y-1083144D02*
X3642998Y-1086885D01*
X3643793Y-1083144D01*
X3647372D01*
G37*
G36*
G01X3642998Y-1086885D02*
X3647372Y-1083144D01*
X3646577Y-1086885D01*
X3642998D01*
G37*
G36*
G01X3659862Y-1088675D02*
X3657084Y-1094857D01*
X3652730Y-1096972D01*
X3659862Y-1088675D01*
G37*
G36*
G01D02*
X3652730Y-1096972D01*
X3656771Y-1088675D01*
X3659862D01*
G37*
G36*
G01X3657084Y-1094857D02*
X3659862Y-1088675D01*
X3660702Y-1096972D01*
X3657084Y-1094857D01*
G37*
G36*
G01X3668322Y-1088675D02*
X3660702Y-1096972D01*
X3664417Y-1088675D01*
X3668322D01*
G37*
G36*
G01X3652378D02*
X3652730Y-1096972D01*
X3649661Y-1102991D01*
X3652378Y-1088675D01*
G37*
G36*
G01D02*
X3649661Y-1102991D01*
X3648637Y-1088675D01*
X3652378D01*
G37*
G36*
G01X3649661Y-1102991D02*
X3652730Y-1096972D01*
X3657084Y-1094857D01*
X3649661Y-1102991D01*
G37*
G36*
G01D02*
X3657084Y-1094857D01*
X3652915Y-1102991D01*
X3649661D01*
G37*
G36*
G01X3660702Y-1096972D02*
X3657795Y-1102991D01*
X3657084Y-1094857D01*
X3660702Y-1096972D01*
G37*
G36*
G01X3657795Y-1102991D02*
X3660702Y-1096972D01*
X3668322Y-1088675D01*
X3657795Y-1102991D01*
G37*
G36*
G01D02*
X3668322Y-1088675D01*
X3661049Y-1102991D01*
X3657795D01*
G37*
G36*
G01X3707076Y-1088512D02*
X3707924Y-1088349D01*
X3709028Y-1088512D01*
X3707076D01*
G37*
G36*
G01X3709028D02*
X3706065Y-1088675D01*
X3707076Y-1088512D01*
X3709028D01*
G37*
G36*
G01X3706065Y-1088675D02*
X3709028Y-1088512D01*
X3710098Y-1088838D01*
X3706065Y-1088675D01*
G37*
G36*
G01X3710098Y-1088838D02*
X3705148Y-1089163D01*
X3706065Y-1088675D01*
X3710098Y-1088838D01*
G37*
G36*
G01X3705148Y-1089163D02*
X3710098Y-1088838D01*
X3710842Y-1089163D01*
X3705148D01*
G37*
G36*
G01X3710842D02*
X3704393Y-1089651D01*
X3705148Y-1089163D01*
X3710842D01*
G37*
G36*
G01X3704393Y-1089651D02*
X3710842Y-1089163D01*
X3711517Y-1089814D01*
X3704393Y-1089651D01*
G37*
G36*
G01X3707429Y-1091441D02*
X3706976Y-1091278D01*
X3711832Y-1090627D01*
X3707429Y-1091441D01*
G37*
G36*
G01X3711517Y-1089814D02*
X3711832Y-1090627D01*
X3706976Y-1091278D01*
X3711517Y-1089814D01*
G37*
G36*
G01D02*
X3706976Y-1091278D01*
X3706291Y-1091441D01*
X3711517Y-1089814D01*
G37*
G36*
G01X3704393Y-1089651D02*
X3711517Y-1089814D01*
X3706291Y-1091441D01*
X3704393Y-1089651D01*
G37*
G36*
G01D02*
X3706291Y-1091441D01*
X3705408Y-1091766D01*
X3704393Y-1089651D01*
G37*
G36*
G01D02*
X3705408Y-1091766D01*
X3704491Y-1092254D01*
X3704393Y-1089651D01*
G37*
G36*
G01D02*
X3704491Y-1092254D01*
X3703667Y-1093068D01*
X3704393Y-1089651D01*
G37*
G36*
G01D02*
X3703667Y-1093068D01*
X3697979Y-1102991D01*
X3704393Y-1089651D01*
G37*
G36*
G01X3704601Y-1088675D02*
X3704393Y-1089651D01*
X3697979Y-1102991D01*
X3704601Y-1088675D01*
G37*
G36*
G01D02*
X3697979Y-1102991D01*
X3701022Y-1088675D01*
X3704601D01*
G37*
G36*
G01X3697979Y-1102991D02*
X3703667Y-1093068D01*
X3701558Y-1102991D01*
X3697979D01*
G37*
G36*
G01X3711954Y-1093881D02*
X3706438Y-1102991D01*
X3708375Y-1093881D01*
X3711954D01*
G37*
G36*
G01X3706438Y-1102991D02*
X3711954Y-1093881D01*
X3710017Y-1102991D01*
X3706438D01*
G37*
G36*
G01X3682638Y-1088675D02*
X3673904Y-1097623D01*
X3678896Y-1088675D01*
X3682638D01*
G37*
G36*
G01X3691132Y-1088512D02*
X3691980Y-1088349D01*
X3693085Y-1088512D01*
X3691132D01*
G37*
G36*
G01X3693085D02*
X3690122Y-1088675D01*
X3691132Y-1088512D01*
X3693085D01*
G37*
G36*
G01X3690122Y-1088675D02*
X3693085Y-1088512D01*
X3694154Y-1088838D01*
X3690122Y-1088675D01*
G37*
G36*
G01X3694154Y-1088838D02*
X3689204Y-1089163D01*
X3690122Y-1088675D01*
X3694154Y-1088838D01*
G37*
G36*
G01X3689204Y-1089163D02*
X3694154Y-1088838D01*
X3694898Y-1089163D01*
X3689204D01*
G37*
G36*
G01X3694898D02*
X3688450Y-1089651D01*
X3689204Y-1089163D01*
X3694898D01*
G37*
G36*
G01X3688450Y-1089651D02*
X3694898Y-1089163D01*
X3695574Y-1089814D01*
X3688450Y-1089651D01*
G37*
G36*
G01X3691486Y-1091441D02*
X3691033Y-1091278D01*
X3695889Y-1090627D01*
X3691486Y-1091441D01*
G37*
G36*
G01X3691811D02*
X3691486D01*
X3695889Y-1090627D01*
X3691811Y-1091441D01*
G37*
G36*
G01D02*
X3695889Y-1090627D01*
X3696204Y-1091441D01*
X3691811D01*
G37*
G36*
G01X3696204D02*
X3692102Y-1091603D01*
X3691811Y-1091441D01*
X3696204D01*
G37*
G36*
G01X3692358Y-1091929D02*
X3692102Y-1091603D01*
X3696204Y-1091441D01*
X3692358Y-1091929D01*
G37*
G36*
G01X3692452Y-1092254D02*
X3692358Y-1091929D01*
X3696204Y-1091441D01*
X3692452Y-1092254D01*
G37*
G36*
G01D02*
X3696204Y-1091441D01*
X3696124Y-1092579D01*
X3692452Y-1092254D01*
G37*
G36*
G01X3696124Y-1092579D02*
X3692511Y-1092742D01*
X3692452Y-1092254D01*
X3696124Y-1092579D01*
G37*
G36*
G01X3692407Y-1093230D02*
X3692511Y-1092742D01*
X3696124Y-1092579D01*
X3692407Y-1093230D01*
G37*
G36*
G01X3692431Y-1093881D02*
X3692407Y-1093230D01*
X3696124Y-1092579D01*
X3692431Y-1093881D01*
G37*
G36*
G01D02*
X3696124Y-1092579D01*
X3696011Y-1093881D01*
X3692431D01*
G37*
G36*
G01X3695574Y-1089814D02*
X3695889Y-1090627D01*
X3691033Y-1091278D01*
X3695574Y-1089814D01*
G37*
G36*
G01D02*
X3691033Y-1091278D01*
X3690347Y-1091441D01*
X3695574Y-1089814D01*
G37*
G36*
G01X3688450Y-1089651D02*
X3695574Y-1089814D01*
X3690347Y-1091441D01*
X3688450Y-1089651D01*
G37*
G36*
G01D02*
X3690347Y-1091441D01*
X3689465Y-1091766D01*
X3688450Y-1089651D01*
G37*
G36*
G01D02*
X3689465Y-1091766D01*
X3688548Y-1092254D01*
X3688450Y-1089651D01*
G37*
G36*
G01D02*
X3688548Y-1092254D01*
X3687724Y-1093068D01*
X3688450Y-1089651D01*
G37*
G36*
G01D02*
X3687724Y-1093068D01*
X3682035Y-1102991D01*
X3688450Y-1089651D01*
G37*
G36*
G01X3688657Y-1088675D02*
X3688450Y-1089651D01*
X3682035Y-1102991D01*
X3688657Y-1088675D01*
G37*
G36*
G01D02*
X3682035Y-1102991D01*
X3685078Y-1088675D01*
X3688657D01*
G37*
G36*
G01X3682035Y-1102991D02*
X3687724Y-1093068D01*
X3685615Y-1102991D01*
X3682035D01*
G37*
G36*
G01X3696011Y-1093881D02*
X3690495Y-1102991D01*
X3692431Y-1093881D01*
X3696011D01*
G37*
G36*
G01X3690495Y-1102991D02*
X3696011Y-1093881D01*
X3694074Y-1102991D01*
X3690495D01*
G37*
G36*
G01X3707224Y-1027438D02*
Y-1036100D01*
X3708091D01*
Y-1027438D01*
X3707224D01*
G37*
G36*
G01X3701954Y-984593D02*
X3704538Y-984174D01*
X3702816Y-985431D01*
X3701954Y-984593D01*
G37*
G36*
G01X3704538Y-984174D02*
X3705400Y-985849D01*
X3702816Y-985431D01*
X3704538Y-984174D01*
G37*
G36*
G01X3703390Y-986268D02*
X3702816Y-985431D01*
X3705400Y-985849D01*
X3703390Y-986268D01*
G37*
G36*
G01D02*
X3705400Y-985849D01*
X3703677Y-987525D01*
X3703390Y-986268D01*
G37*
G36*
G01X3705400Y-985849D02*
X3705686Y-987525D01*
X3703677D01*
X3705400Y-985849D01*
G37*
G36*
G01X3703677Y-988362D02*
Y-987525D01*
X3705686D01*
X3703677Y-988362D01*
G37*
G36*
G01X3705686Y-987525D02*
Y-988362D01*
X3703677D01*
X3705686Y-987525D01*
G37*
G36*
G01X3703390Y-989619D02*
X3703677Y-988362D01*
X3705686D01*
X3703390Y-989619D01*
G37*
G36*
G01X3705686Y-988362D02*
X3705400Y-990038D01*
X3703390Y-989619D01*
X3705686Y-988362D01*
G37*
G36*
G01X3702816Y-990456D02*
X3703390Y-989619D01*
X3705400Y-990038D01*
X3702816Y-990456D01*
G37*
G36*
G01D02*
X3705400Y-990038D01*
X3701954Y-990875D01*
X3702816Y-990456D01*
G37*
G36*
G01X3705400Y-990038D02*
X3704538Y-991713D01*
X3701954Y-990875D01*
X3705400Y-990038D01*
G37*
G36*
G01X3704538Y-984174D02*
X3696787Y-984593D01*
X3703677Y-982918D01*
X3704538Y-984174D01*
G37*
G36*
G01X3703677Y-982918D02*
X3696787Y-984593D01*
X3701954Y-982499D01*
X3703677Y-982918D01*
G37*
G36*
G01X3696787Y-984593D02*
Y-982499D01*
X3701954D01*
X3696787Y-984593D01*
G37*
G36*
G01D02*
X3704538Y-984174D01*
X3701954Y-984593D01*
X3696787D01*
G37*
G36*
G01X3703677Y-992551D02*
X3696787Y-993388D01*
X3704538Y-991713D01*
X3703677Y-992551D01*
G37*
G36*
G01X3704538Y-991713D02*
X3696787Y-993388D01*
X3701954Y-990875D01*
X3704538Y-991713D01*
G37*
G36*
G01X3696787Y-993388D02*
Y-990875D01*
X3701954D01*
X3696787Y-993388D01*
G37*
G36*
G01X3703677Y-992551D02*
X3701954Y-993388D01*
X3696787D01*
X3703677Y-992551D01*
G37*
G36*
G01X3695065Y-982499D02*
Y-1002184D01*
X3696787D01*
Y-982499D01*
X3695065D01*
G37*
G36*
G01X3735385Y-1083144D02*
X3736396Y-1082981D01*
X3737826Y-1083144D01*
X3735385D01*
G37*
G36*
G01X3737826D02*
X3734375Y-1083306D01*
X3735385Y-1083144D01*
X3737826D01*
G37*
G36*
G01X3733364Y-1083469D02*
X3734375Y-1083306D01*
X3737826Y-1083144D01*
X3733364Y-1083469D01*
G37*
G36*
G01D02*
X3737826Y-1083144D01*
X3739221Y-1083469D01*
X3733364D01*
G37*
G36*
G01X3739221D02*
X3732481Y-1083794D01*
X3733364Y-1083469D01*
X3739221D01*
G37*
G36*
G01X3731599Y-1084120D02*
X3732481Y-1083794D01*
X3739221Y-1083469D01*
X3731599Y-1084120D01*
G37*
G36*
G01D02*
X3739221Y-1083469D01*
X3740221Y-1084120D01*
X3731599D01*
G37*
G36*
G01X3736483Y-1086397D02*
X3735704Y-1086234D01*
X3742153Y-1085747D01*
X3736483Y-1086397D01*
G37*
G36*
G01X3737262Y-1086560D02*
X3736483Y-1086397D01*
X3742153Y-1085747D01*
X3737262Y-1086560D01*
G37*
G36*
G01X3737878Y-1086723D02*
X3737262Y-1086560D01*
X3742153Y-1085747D01*
X3737878Y-1086723D01*
G37*
G36*
G01D02*
X3742153Y-1085747D01*
X3742562Y-1086885D01*
X3737878Y-1086723D01*
G37*
G36*
G01X3742562Y-1086885D02*
X3738425Y-1087211D01*
X3737878Y-1086723D01*
X3742562Y-1086885D01*
G37*
G36*
G01X3738810Y-1087699D02*
X3738425Y-1087211D01*
X3742562Y-1086885D01*
X3738810Y-1087699D01*
G37*
G36*
G01X3739194Y-1088187D02*
X3738810Y-1087699D01*
X3742562Y-1086885D01*
X3739194Y-1088187D01*
G37*
G36*
G01D02*
X3742562Y-1086885D01*
X3742936Y-1088187D01*
X3739194D01*
G37*
G36*
G01X3742936D02*
X3739381Y-1088838D01*
X3739194Y-1088187D01*
X3742936D01*
G37*
G36*
G01X3739568Y-1089488D02*
X3739381Y-1088838D01*
X3742936Y-1088187D01*
X3739568Y-1089488D01*
G37*
G36*
G01D02*
X3742936Y-1088187D01*
X3743147Y-1089488D01*
X3739568D01*
G37*
G36*
G01X3741660Y-1096484D02*
X3741325Y-1097297D01*
X3737548Y-1097460D01*
X3741660Y-1096484D01*
G37*
G36*
G01D02*
X3737548Y-1097460D01*
X3738081Y-1096484D01*
X3741660D01*
G37*
G36*
G01X3737085Y-1098111D02*
X3737548Y-1097460D01*
X3741325Y-1097297D01*
X3737085Y-1098111D01*
G37*
G36*
G01D02*
X3741325Y-1097297D01*
X3740826Y-1098111D01*
X3737085D01*
G37*
G36*
G01X3740826D02*
X3736621Y-1098762D01*
X3737085Y-1098111D01*
X3740826D01*
G37*
G36*
G01X3736621Y-1098762D02*
X3740826Y-1098111D01*
X3740526Y-1098762D01*
X3736621D01*
G37*
G36*
G01X3740526D02*
X3735867Y-1099249D01*
X3736621Y-1098762D01*
X3740526D01*
G37*
G36*
G01X3735867Y-1099249D02*
X3740526Y-1098762D01*
X3740062Y-1099412D01*
X3735867Y-1099249D01*
G37*
G36*
G01X3740062Y-1099412D02*
X3735146Y-1099575D01*
X3735867Y-1099249D01*
X3740062Y-1099412D01*
G37*
G36*
G01X3734427Y-1099900D02*
X3735146Y-1099575D01*
X3740062Y-1099412D01*
X3734427Y-1099900D01*
G37*
G36*
G01X3733579Y-1100063D02*
X3734427Y-1099900D01*
X3740062Y-1099412D01*
X3733579Y-1100063D01*
G37*
G36*
G01D02*
X3740062Y-1099412D01*
X3738972Y-1100714D01*
X3733579Y-1100063D01*
G37*
G36*
G01X3707755Y-1091441D02*
X3707429D01*
X3711832Y-1090627D01*
X3707755Y-1091441D01*
G37*
G36*
G01D02*
X3711832Y-1090627D01*
X3712147Y-1091441D01*
X3707755D01*
G37*
G36*
G01X3712147D02*
X3708046Y-1091603D01*
X3707755Y-1091441D01*
X3712147D01*
G37*
G36*
G01X3708302Y-1091929D02*
X3708046Y-1091603D01*
X3712147Y-1091441D01*
X3708302Y-1091929D01*
G37*
G36*
G01X3708395Y-1092254D02*
X3708302Y-1091929D01*
X3712147Y-1091441D01*
X3708395Y-1092254D01*
G37*
G36*
G01D02*
X3712147Y-1091441D01*
X3712068Y-1092579D01*
X3708395Y-1092254D01*
G37*
G36*
G01X3712068Y-1092579D02*
X3708454Y-1092742D01*
X3708395Y-1092254D01*
X3712068Y-1092579D01*
G37*
G36*
G01X3708350Y-1093230D02*
X3708454Y-1092742D01*
X3712068Y-1092579D01*
X3708350Y-1093230D01*
G37*
G36*
G01X3708375Y-1093881D02*
X3708350Y-1093230D01*
X3712068Y-1092579D01*
X3708375Y-1093881D01*
G37*
G36*
G01D02*
X3712068Y-1092579D01*
X3711954Y-1093881D01*
X3708375D01*
G37*
G36*
G01X3740221Y-1084120D02*
X3730681Y-1084608D01*
X3731599Y-1084120D01*
X3740221D01*
G37*
G36*
G01X3730681Y-1084608D02*
X3740221Y-1084120D01*
X3741222Y-1084770D01*
X3730681Y-1084608D01*
G37*
G36*
G01X3741222Y-1084770D02*
X3729893Y-1085258D01*
X3730681Y-1084608D01*
X3741222Y-1084770D01*
G37*
G36*
G01X3729138Y-1085747D02*
X3729893Y-1085258D01*
X3741222Y-1084770D01*
X3729138Y-1085747D01*
G37*
G36*
G01D02*
X3741222Y-1084770D01*
X3742153Y-1085747D01*
X3729138D01*
G37*
G36*
G01X3735704Y-1086234D02*
X3734531Y-1086397D01*
X3728315Y-1086560D01*
X3735704Y-1086234D01*
G37*
G36*
G01X3742153Y-1085747D02*
X3735704Y-1086234D01*
X3728315Y-1086560D01*
X3742153Y-1085747D01*
G37*
G36*
G01D02*
X3728315Y-1086560D01*
X3729138Y-1085747D01*
X3742153D01*
G37*
G36*
G01X3728315Y-1086560D02*
X3734531Y-1086397D01*
X3733323Y-1086723D01*
X3728315Y-1086560D01*
G37*
G36*
G01X3733323Y-1086723D02*
X3727688Y-1087211D01*
X3728315Y-1086560D01*
X3733323Y-1086723D01*
G37*
G36*
G01X3727688Y-1087211D02*
X3733323Y-1086723D01*
X3732209Y-1087373D01*
X3727688Y-1087211D01*
G37*
G36*
G01X3732209Y-1087373D02*
X3731257Y-1088024D01*
X3727155Y-1088187D01*
X3732209Y-1087373D01*
G37*
G36*
G01D02*
X3727155Y-1088187D01*
X3727688Y-1087211D01*
X3732209Y-1087373D01*
G37*
G36*
G01X3726657Y-1089000D02*
X3727155Y-1088187D01*
X3731257Y-1088024D01*
X3726657Y-1089000D01*
G37*
G36*
G01D02*
X3731257Y-1088024D01*
X3730399Y-1089000D01*
X3726657D01*
G37*
G36*
G01X3730399D02*
X3726124Y-1089977D01*
X3726657Y-1089000D01*
X3730399D01*
G37*
G36*
G01X3726124Y-1089977D02*
X3730399Y-1089000D01*
X3729634Y-1090302D01*
X3726124Y-1089977D01*
G37*
G36*
G01X3729634Y-1090302D02*
X3725754Y-1090953D01*
X3726124Y-1089977D01*
X3729634Y-1090302D01*
G37*
G36*
G01X3725754Y-1090953D02*
X3729634Y-1090302D01*
X3729032Y-1091603D01*
X3725754Y-1090953D01*
G37*
G36*
G01X3729032Y-1091603D02*
X3725349Y-1092092D01*
X3725754Y-1090953D01*
X3729032Y-1091603D01*
G37*
G36*
G01X3725107Y-1093230D02*
X3725349Y-1092092D01*
X3729032Y-1091603D01*
X3725107Y-1093230D01*
G37*
G36*
G01D02*
X3729032Y-1091603D01*
X3728686Y-1093230D01*
X3725107D01*
G37*
G36*
G01X3728686D02*
X3724865Y-1094369D01*
X3725107Y-1093230D01*
X3728686D01*
G37*
G36*
G01X3724865Y-1094369D02*
X3728686Y-1093230D01*
X3728375Y-1094694D01*
X3724865Y-1094369D01*
G37*
G36*
G01X3728375Y-1094694D02*
X3724786Y-1095508D01*
X3724865Y-1094369D01*
X3728375Y-1094694D01*
G37*
G36*
G01X3724786Y-1095508D02*
X3728375Y-1094694D01*
X3728389Y-1096158D01*
X3724786Y-1095508D01*
G37*
G36*
G01X3728389Y-1096158D02*
X3724741Y-1096484D01*
X3724786Y-1095508D01*
X3728389Y-1096158D01*
G37*
G36*
G01X3724741Y-1096484D02*
X3728389Y-1096158D01*
X3728635Y-1097297D01*
X3724741Y-1096484D01*
G37*
G36*
G01X3728635Y-1097297D02*
X3724696Y-1097460D01*
X3724741Y-1096484D01*
X3728635Y-1097297D01*
G37*
G36*
G01X3725011Y-1098273D02*
X3724696Y-1097460D01*
X3728635Y-1097297D01*
X3725011Y-1098273D01*
G37*
G36*
G01D02*
X3728635Y-1097297D01*
X3729078Y-1098273D01*
X3725011D01*
G37*
G36*
G01X3729078D02*
X3729719Y-1099087D01*
X3725129Y-1099249D01*
X3729078Y-1098273D01*
G37*
G36*
G01D02*
X3725129Y-1099249D01*
X3725011Y-1098273D01*
X3729078D01*
G37*
G36*
G01X3725129Y-1099249D02*
X3729719Y-1099087D01*
X3730557Y-1099738D01*
X3725129Y-1099249D01*
G37*
G36*
G01X3730557Y-1099738D02*
X3725479Y-1099900D01*
X3725129Y-1099249D01*
X3730557Y-1099738D01*
G37*
G36*
G01X3725479Y-1099900D02*
X3730557Y-1099738D01*
X3731464Y-1100063D01*
X3725479Y-1099900D01*
G37*
G36*
G01X3732765Y-1100063D02*
X3733579D01*
X3725957Y-1100714D01*
X3732765Y-1100063D01*
G37*
G36*
G01X3731464D02*
X3732765D01*
X3725957Y-1100714D01*
X3731464Y-1100063D01*
G37*
G36*
G01D02*
X3725957Y-1100714D01*
X3725479Y-1099900D01*
X3731464Y-1100063D01*
G37*
G36*
G01X3738972Y-1100714D02*
X3725957D01*
X3733579Y-1100063D01*
X3738972Y-1100714D01*
G37*
G36*
G01D02*
X3726504Y-1101202D01*
X3725957Y-1100714D01*
X3738972D01*
G37*
G36*
G01X3726504Y-1101202D02*
X3738972Y-1100714D01*
X3737788Y-1101690D01*
X3726504Y-1101202D01*
G37*
G36*
G01X3737788Y-1101690D02*
X3727016Y-1101853D01*
X3726504Y-1101202D01*
X3737788Y-1101690D01*
G37*
G36*
G01X3727563Y-1102341D02*
X3727016Y-1101853D01*
X3737788Y-1101690D01*
X3727563Y-1102341D01*
G37*
G36*
G01D02*
X3737788Y-1101690D01*
X3736511Y-1102341D01*
X3727563D01*
G37*
G36*
G01X3736511D02*
X3728307Y-1102666D01*
X3727563Y-1102341D01*
X3736511D01*
G37*
G36*
G01X3729215Y-1102991D02*
X3728307Y-1102666D01*
X3736511Y-1102341D01*
X3729215Y-1102991D01*
G37*
G36*
G01X3730028D02*
X3729215D01*
X3736511Y-1102341D01*
X3730028Y-1102991D01*
G37*
G36*
G01D02*
X3736511Y-1102341D01*
X3735071Y-1102991D01*
X3730028D01*
G37*
G36*
G01X3735071D02*
X3731132Y-1103154D01*
X3730028Y-1102991D01*
X3735071D01*
G37*
G36*
G01X3731132Y-1103154D02*
X3735071Y-1102991D01*
X3733572Y-1103154D01*
X3731132D01*
G37*
G36*
G01X3733572D02*
X3732074Y-1103317D01*
X3731132Y-1103154D01*
X3733572D01*
G37*
G36*
G01X3708091Y-1027438D02*
Y-1028544D01*
X3712421D01*
Y-1027438D01*
X3708091D01*
G37*
G36*
G01Y-1030940D02*
Y-1032045D01*
X3711844D01*
Y-1030940D01*
X3708091D01*
G37*
G36*
G01X3718340Y-1028175D02*
X3714442Y-1028360D01*
X3717907Y-1027623D01*
X3718340Y-1028175D01*
G37*
G36*
G01X3717907Y-1027623D02*
X3714442Y-1028360D01*
X3717041Y-1027438D01*
X3717907Y-1027623D01*
G37*
G36*
G01X3714442Y-1028360D02*
Y-1027438D01*
X3717041D01*
X3714442Y-1028360D01*
G37*
G36*
G01D02*
X3718340Y-1028175D01*
X3717041Y-1028360D01*
X3714442D01*
G37*
G36*
G01X3717041D02*
X3718340Y-1028175D01*
X3717474Y-1028728D01*
X3717041Y-1028360D01*
G37*
G36*
G01X3718340Y-1028175D02*
X3718773Y-1028912D01*
X3717474Y-1028728D01*
X3718340Y-1028175D01*
G37*
G36*
G01X3717763Y-1029097D02*
X3717474Y-1028728D01*
X3718773Y-1028912D01*
X3717763Y-1029097D01*
G37*
G36*
G01D02*
X3718773Y-1028912D01*
X3717907Y-1029650D01*
X3717763Y-1029097D01*
G37*
G36*
G01X3718773Y-1028912D02*
X3718917Y-1029650D01*
X3717907D01*
X3718773Y-1028912D01*
G37*
G36*
G01X3717907Y-1030018D02*
Y-1029650D01*
X3718917D01*
X3717907Y-1030018D01*
G37*
G36*
G01X3718917Y-1029650D02*
Y-1030018D01*
X3717907D01*
X3718917Y-1029650D01*
G37*
G36*
G01X3717763Y-1030571D02*
X3717907Y-1030018D01*
X3718917D01*
X3717763Y-1030571D01*
G37*
G36*
G01X3718917Y-1030018D02*
X3718773Y-1030755D01*
X3717763Y-1030571D01*
X3718917Y-1030018D01*
G37*
G36*
G01X3717474Y-1030940D02*
X3717763Y-1030571D01*
X3718773Y-1030755D01*
X3717474Y-1030940D01*
G37*
G36*
G01D02*
X3718773Y-1030755D01*
X3717041Y-1031124D01*
X3717474Y-1030940D01*
G37*
G36*
G01X3718773Y-1030755D02*
X3718340Y-1031492D01*
X3717041Y-1031124D01*
X3718773Y-1030755D01*
G37*
G36*
G01X3717907Y-1031861D02*
X3714442Y-1032230D01*
X3718340Y-1031492D01*
X3717907Y-1031861D01*
G37*
G36*
G01X3718340Y-1031492D02*
X3714442Y-1032230D01*
X3717041Y-1031124D01*
X3718340Y-1031492D01*
G37*
G36*
G01X3714442Y-1032230D02*
Y-1031124D01*
X3717041D01*
X3714442Y-1032230D01*
G37*
G36*
G01X3717907Y-1031861D02*
X3717041Y-1032230D01*
X3714442D01*
X3717907Y-1031861D01*
G37*
G36*
G01X3721660Y-1027623D02*
X3722670Y-1027438D01*
X3723104D01*
X3721660Y-1027623D01*
G37*
G36*
G01X3723104Y-1027438D02*
X3724114Y-1027623D01*
X3721660D01*
X3723104Y-1027438D01*
G37*
G36*
G01X3721083Y-1027991D02*
X3721660Y-1027623D01*
X3724114D01*
X3721083Y-1027991D01*
G37*
G36*
G01X3724114Y-1027623D02*
X3724692Y-1027991D01*
X3721083D01*
X3724114Y-1027623D01*
G37*
G36*
G01X3720794Y-1028360D02*
X3721083Y-1027991D01*
X3724692D01*
X3720794Y-1028360D01*
G37*
G36*
G01D02*
X3724692Y-1027991D01*
X3722526Y-1028360D01*
X3720794D01*
G37*
G36*
G01X3722526D02*
X3724692Y-1027991D01*
X3723104Y-1028360D01*
X3722526D01*
G37*
G36*
G01X3724692Y-1027991D02*
X3724980Y-1028360D01*
X3723104D01*
X3724692Y-1027991D01*
G37*
G36*
G01X3723825Y-1028544D02*
X3723104Y-1028360D01*
X3724980D01*
X3723825Y-1028544D01*
G37*
G36*
G01X3721804D02*
X3720505Y-1028728D01*
X3722526Y-1028360D01*
X3721804Y-1028544D01*
G37*
G36*
G01X3720505Y-1028728D02*
X3720794Y-1028360D01*
X3722526D01*
X3720505Y-1028728D01*
G37*
G36*
G01X3724980Y-1028360D02*
X3725269Y-1028728D01*
X3723825Y-1028544D01*
X3724980Y-1028360D01*
G37*
G36*
G01X3721804Y-1028544D02*
X3721371Y-1028912D01*
X3720505Y-1028728D01*
X3721804Y-1028544D01*
G37*
G36*
G01X3724258Y-1028912D02*
X3723825Y-1028544D01*
X3725269Y-1028728D01*
X3724258Y-1028912D01*
G37*
G36*
G01X3720361Y-1029465D02*
X3720505Y-1028728D01*
X3721371Y-1028912D01*
X3720361Y-1029465D01*
G37*
G36*
G01X3721371Y-1028912D02*
X3721083Y-1029465D01*
X3720361D01*
X3721371Y-1028912D01*
G37*
G36*
G01X3724258D02*
X3725269Y-1028728D01*
X3724547Y-1029465D01*
X3724258Y-1028912D01*
G37*
G36*
G01X3725269Y-1028728D02*
X3725413Y-1029465D01*
X3724547D01*
X3725269Y-1028728D01*
G37*
G36*
G01X3724547Y-1029834D02*
Y-1029465D01*
X3725413D01*
X3724547Y-1029834D01*
G37*
G36*
G01X3725413Y-1029465D02*
Y-1029834D01*
X3724547D01*
X3725413Y-1029465D01*
G37*
G36*
G01X3724258Y-1030571D02*
X3724547Y-1029834D01*
X3725413D01*
X3724258Y-1030571D01*
G37*
G36*
G01X3725413Y-1029834D02*
X3725269Y-1030571D01*
X3724258D01*
X3725413Y-1029834D01*
G37*
G36*
G01X3723970Y-1030940D02*
X3724258Y-1030571D01*
X3725269D01*
X3723970Y-1030940D01*
G37*
G36*
G01X3725269Y-1030571D02*
X3724980Y-1031124D01*
X3723970Y-1030940D01*
X3725269Y-1030571D01*
G37*
G36*
G01X3728012Y-1027623D02*
X3729022Y-1027438D01*
X3729455D01*
X3728012Y-1027623D01*
G37*
G36*
G01X3729455Y-1027438D02*
X3730466Y-1027623D01*
X3728012D01*
X3729455Y-1027438D01*
G37*
G36*
G01X3727434Y-1027991D02*
X3728012Y-1027623D01*
X3730466D01*
X3727434Y-1027991D01*
G37*
G36*
G01X3730466Y-1027623D02*
X3731043Y-1027991D01*
X3727434D01*
X3730466Y-1027623D01*
G37*
G36*
G01X3727146Y-1028360D02*
X3727434Y-1027991D01*
X3731043D01*
X3727146Y-1028360D01*
G37*
G36*
G01D02*
X3731043Y-1027991D01*
X3728878Y-1028360D01*
X3727146D01*
G37*
G36*
G01X3728878D02*
X3731043Y-1027991D01*
X3729455Y-1028360D01*
X3728878D01*
G37*
G36*
G01X3731043Y-1027991D02*
X3731332Y-1028360D01*
X3729455D01*
X3731043Y-1027991D01*
G37*
G36*
G01X3730177Y-1028544D02*
X3729455Y-1028360D01*
X3731332D01*
X3730177Y-1028544D01*
G37*
G36*
G01X3728156D02*
X3726857Y-1028728D01*
X3728878Y-1028360D01*
X3728156Y-1028544D01*
G37*
G36*
G01X3726857Y-1028728D02*
X3727146Y-1028360D01*
X3728878D01*
X3726857Y-1028728D01*
G37*
G36*
G01X3731332Y-1028360D02*
X3731620Y-1028728D01*
X3730177Y-1028544D01*
X3731332Y-1028360D01*
G37*
G36*
G01X3728156Y-1028544D02*
X3727723Y-1028912D01*
X3726857Y-1028728D01*
X3728156Y-1028544D01*
G37*
G36*
G01X3730610Y-1028912D02*
X3730177Y-1028544D01*
X3731620Y-1028728D01*
X3730610Y-1028912D01*
G37*
G36*
G01X3726712Y-1029465D02*
X3726857Y-1028728D01*
X3727723Y-1028912D01*
X3726712Y-1029465D01*
G37*
G36*
G01X3727723Y-1028912D02*
X3727434Y-1029465D01*
X3726712D01*
X3727723Y-1028912D01*
G37*
G36*
G01X3730610D02*
X3731620Y-1028728D01*
X3730899Y-1029465D01*
X3730610Y-1028912D01*
G37*
G36*
G01X3731620Y-1028728D02*
X3731765Y-1029465D01*
X3730899D01*
X3731620Y-1028728D01*
G37*
G36*
G01X3730899Y-1029834D02*
Y-1029465D01*
X3731765D01*
X3730899Y-1029834D01*
G37*
G36*
G01X3731765Y-1029465D02*
Y-1029834D01*
X3730899D01*
X3731765Y-1029465D01*
G37*
G36*
G01X3730610Y-1030571D02*
X3730899Y-1029834D01*
X3731765D01*
X3730610Y-1030571D01*
G37*
G36*
G01X3731765Y-1029834D02*
X3731620Y-1030571D01*
X3730610D01*
X3731765Y-1029834D01*
G37*
G36*
G01X3730322Y-1030940D02*
X3730610Y-1030571D01*
X3731620D01*
X3730322Y-1030940D01*
G37*
G36*
G01X3731620Y-1030571D02*
X3731332Y-1031124D01*
X3730322Y-1030940D01*
X3731620Y-1030571D01*
G37*
G36*
G01X3713576Y-1027438D02*
Y-1036100D01*
X3714442D01*
Y-1027438D01*
X3713576D01*
G37*
G36*
G01X3716752Y-1031677D02*
X3718051Y-1036100D01*
X3719061D01*
X3717763Y-1031677D01*
X3716752D01*
G37*
G36*
G01X3720217Y-1035178D02*
X3723970Y-1030940D01*
X3724980Y-1031124D01*
X3720217Y-1035178D01*
G37*
G36*
G01X3724980Y-1031124D02*
X3721371Y-1035178D01*
X3720217D01*
X3724980Y-1031124D01*
G37*
G36*
G01X3725413Y-1035178D02*
X3720217Y-1036100D01*
X3721371Y-1035178D01*
X3725413D01*
G37*
G36*
G01X3720217Y-1036100D02*
Y-1035178D01*
X3721371D01*
X3720217Y-1036100D01*
G37*
G36*
G01X3725413Y-1035178D02*
Y-1036100D01*
X3720217D01*
X3725413Y-1035178D01*
G37*
G36*
G01X3726568D02*
X3730322Y-1030940D01*
X3731332Y-1031124D01*
X3726568Y-1035178D01*
G37*
G36*
G01X3731332Y-1031124D02*
X3727723Y-1035178D01*
X3726568D01*
X3731332Y-1031124D01*
G37*
G36*
G01X3731765Y-1035178D02*
X3726568Y-1036100D01*
X3727723Y-1035178D01*
X3731765D01*
G37*
G36*
G01X3726568Y-1036100D02*
Y-1035178D01*
X3727723D01*
X3726568Y-1036100D01*
G37*
G36*
G01X3731765Y-1035178D02*
Y-1036100D01*
X3726568D01*
X3731765Y-1035178D01*
G37*
G36*
G01X3709418Y-982499D02*
Y-985012D01*
X3718030D01*
Y-982499D01*
X3709418D01*
G37*
G36*
G01Y-990456D02*
Y-992969D01*
X3716882D01*
Y-990456D01*
X3709418D01*
G37*
G36*
G01X3729801Y-984174D02*
X3722050Y-984593D01*
X3728939Y-982918D01*
X3729801Y-984174D01*
G37*
G36*
G01X3728939Y-982918D02*
X3722050Y-984593D01*
X3727217Y-982499D01*
X3728939Y-982918D01*
G37*
G36*
G01X3722050Y-984593D02*
Y-982499D01*
X3727217D01*
X3722050Y-984593D01*
G37*
G36*
G01D02*
X3729801Y-984174D01*
X3727217Y-984593D01*
X3722050D01*
G37*
G36*
G01X3727217D02*
X3729801Y-984174D01*
X3728078Y-985431D01*
X3727217Y-984593D01*
G37*
G36*
G01X3729801Y-984174D02*
X3730662Y-985849D01*
X3728078Y-985431D01*
X3729801Y-984174D01*
G37*
G36*
G01X3728652Y-986268D02*
X3728078Y-985431D01*
X3730662Y-985849D01*
X3728652Y-986268D01*
G37*
G36*
G01D02*
X3730662Y-985849D01*
X3728939Y-987525D01*
X3728652Y-986268D01*
G37*
G36*
G01X3730662Y-985849D02*
X3730949Y-987525D01*
X3728939D01*
X3730662Y-985849D01*
G37*
G36*
G01X3728939Y-988362D02*
Y-987525D01*
X3730949D01*
X3728939Y-988362D01*
G37*
G36*
G01X3730949Y-987525D02*
Y-988362D01*
X3728939D01*
X3730949Y-987525D01*
G37*
G36*
G01X3728652Y-989619D02*
X3728939Y-988362D01*
X3730949D01*
X3728652Y-989619D01*
G37*
G36*
G01X3730949Y-988362D02*
X3730662Y-990038D01*
X3728652Y-989619D01*
X3730949Y-988362D01*
G37*
G36*
G01X3728078Y-990456D02*
X3728652Y-989619D01*
X3730662Y-990038D01*
X3728078Y-990456D01*
G37*
G36*
G01D02*
X3730662Y-990038D01*
X3727217Y-990875D01*
X3728078Y-990456D01*
G37*
G36*
G01X3730662Y-990038D02*
X3729801Y-991713D01*
X3727217Y-990875D01*
X3730662Y-990038D01*
G37*
G36*
G01X3728939Y-992551D02*
X3722050Y-993388D01*
X3729801Y-991713D01*
X3728939Y-992551D01*
G37*
G36*
G01X3729801Y-991713D02*
X3722050Y-993388D01*
X3727217Y-990875D01*
X3729801Y-991713D01*
G37*
G36*
G01X3722050Y-993388D02*
Y-990875D01*
X3727217D01*
X3722050Y-993388D01*
G37*
G36*
G01X3728939Y-992551D02*
X3727217Y-993388D01*
X3722050D01*
X3728939Y-992551D01*
G37*
G36*
G01X3729801D02*
X3722050Y-993388D01*
X3728939Y-991713D01*
X3729801Y-992551D01*
G37*
G36*
G01X3728939Y-991713D02*
X3722050Y-993388D01*
X3727217Y-990875D01*
X3728939Y-991713D01*
G37*
G36*
G01X3722050Y-993388D02*
Y-990875D01*
X3727217D01*
X3722050Y-993388D01*
G37*
G36*
G01D02*
X3729801Y-992551D01*
X3727217Y-993388D01*
X3722050D01*
G37*
G36*
G01X3727217D02*
X3729801Y-992551D01*
X3728078Y-993807D01*
X3727217Y-993388D01*
G37*
G36*
G01X3729801Y-992551D02*
X3730662Y-994226D01*
X3728078Y-993807D01*
X3729801Y-992551D01*
G37*
G36*
G01X3728652Y-994645D02*
X3728078Y-993807D01*
X3730662Y-994226D01*
X3728652Y-994645D01*
G37*
G36*
G01D02*
X3730662Y-994226D01*
X3728939Y-995901D01*
X3728652Y-994645D01*
G37*
G36*
G01X3730662Y-994226D02*
X3730949Y-995901D01*
X3728939D01*
X3730662Y-994226D01*
G37*
G36*
G01X3728939Y-997158D02*
Y-995901D01*
X3730949D01*
X3728939Y-997158D01*
G37*
G36*
G01X3730949Y-995901D02*
Y-997158D01*
X3728939D01*
X3730949Y-995901D01*
G37*
G36*
G01X3728652Y-998414D02*
X3728939Y-997158D01*
X3730949D01*
X3728652Y-998414D01*
G37*
G36*
G01X3730949Y-997158D02*
X3730662Y-998833D01*
X3728652Y-998414D01*
X3730949Y-997158D01*
G37*
G36*
G01X3728078Y-999252D02*
X3728652Y-998414D01*
X3730662Y-998833D01*
X3728078Y-999252D01*
G37*
G36*
G01D02*
X3730662Y-998833D01*
X3727217Y-999671D01*
X3728078Y-999252D01*
G37*
G36*
G01X3730662Y-998833D02*
X3729801Y-1000508D01*
X3727217Y-999671D01*
X3730662Y-998833D01*
G37*
G36*
G01X3707696Y-982499D02*
Y-1002184D01*
X3709418D01*
Y-982499D01*
X3707696D01*
G37*
G36*
G01X3709418Y-999671D02*
Y-1002184D01*
X3718030D01*
Y-999671D01*
X3709418D01*
G37*
G36*
G01X3720327Y-1002184D02*
Y-982499D01*
X3722050D01*
Y-1002184D01*
X3720327D01*
G37*
G36*
G01X3728939Y-1001765D02*
X3722050Y-1002184D01*
X3729801Y-1000508D01*
X3728939Y-1001765D01*
G37*
G36*
G01X3729801Y-1000508D02*
X3722050Y-1002184D01*
X3727217Y-999671D01*
X3729801Y-1000508D01*
G37*
G36*
G01X3722050Y-1002184D02*
Y-999671D01*
X3727217D01*
X3722050Y-1002184D01*
G37*
G36*
G01X3728939Y-1001765D02*
X3727217Y-1002184D01*
X3722050D01*
X3728939Y-1001765D01*
G37*
G36*
G01X3775517Y-1100226D02*
X3773697Y-1102666D01*
X3768873Y-1108523D01*
X3775517Y-1100226D01*
G37*
G36*
G01X3774970Y-1099738D02*
X3775517Y-1100226D01*
X3768873Y-1108523D01*
X3774970Y-1099738D01*
G37*
G36*
G01X3774423Y-1099249D02*
X3774970Y-1099738D01*
X3768873Y-1108523D01*
X3774423Y-1099249D01*
G37*
G36*
G01X3775702Y-1093230D02*
X3774423Y-1099249D01*
X3768873Y-1108523D01*
X3775702Y-1093230D01*
G37*
G36*
G01X3776498Y-1089488D02*
X3775702Y-1093230D01*
X3768873Y-1108523D01*
X3776498Y-1089488D01*
G37*
G36*
G01X3776671Y-1088675D02*
X3776498Y-1089488D01*
X3768873Y-1108523D01*
X3776671Y-1088675D01*
G37*
G36*
G01D02*
X3768873Y-1108523D01*
X3773092Y-1088675D01*
X3776671D01*
G37*
G36*
G01X3768873Y-1108523D02*
X3773697Y-1102666D01*
X3772452Y-1108523D01*
X3768873D01*
G37*
G36*
G01X3768571Y-1088512D02*
X3769256Y-1088349D01*
X3770035Y-1088512D01*
X3768571D01*
G37*
G36*
G01X3770035D02*
X3770361D01*
X3767723Y-1088675D01*
X3770035Y-1088512D01*
G37*
G36*
G01D02*
X3767723Y-1088675D01*
X3768571Y-1088512D01*
X3770035D01*
G37*
G36*
G01X3767723Y-1088675D02*
X3770361Y-1088512D01*
X3770977Y-1088675D01*
X3767723D01*
G37*
G36*
G01X3770977D02*
X3766969Y-1089163D01*
X3767723Y-1088675D01*
X3770977D01*
G37*
G36*
G01X3766214Y-1089651D02*
X3766969Y-1089163D01*
X3770977Y-1088675D01*
X3766214Y-1089651D01*
G37*
G36*
G01X3768205Y-1091766D02*
X3766214Y-1089651D01*
X3770977Y-1088675D01*
X3768205Y-1091766D01*
G37*
G36*
G01X3768821Y-1091929D02*
X3768205Y-1091766D01*
X3770977Y-1088675D01*
X3768821Y-1091929D01*
G37*
G36*
G01X3769309D02*
X3768821D01*
X3770977Y-1088675D01*
X3769309Y-1091929D01*
G37*
G36*
G01D02*
X3770977Y-1088675D01*
X3770216Y-1092254D01*
X3769309Y-1091929D01*
G37*
G36*
G01X3766214Y-1089651D02*
X3768205Y-1091766D01*
X3767520Y-1091929D01*
X3766214Y-1089651D01*
G37*
G36*
G01D02*
X3767520Y-1091929D01*
X3766800Y-1092254D01*
X3766214Y-1089651D01*
G37*
G36*
G01D02*
X3766800Y-1092254D01*
X3766045Y-1092742D01*
X3766214Y-1089651D01*
G37*
G36*
G01D02*
X3766045Y-1092742D01*
X3765419Y-1093393D01*
X3766214Y-1089651D01*
G37*
G36*
G01X3773697Y-1102666D02*
X3780145Y-1102178D01*
X3779031Y-1102829D01*
X3773697Y-1102666D01*
G37*
G36*
G01X3779031Y-1102829D02*
X3774278Y-1102991D01*
X3773697Y-1102666D01*
X3779031Y-1102829D01*
G37*
G36*
G01X3774929Y-1102991D02*
X3774278D01*
X3779031Y-1102829D01*
X3774929Y-1102991D01*
G37*
G36*
G01X3781294Y-1101364D02*
X3780145Y-1102178D01*
X3773697Y-1102666D01*
X3781294Y-1101364D01*
G37*
G36*
G01X3777598Y-1100388D02*
X3781294Y-1101364D01*
X3773697Y-1102666D01*
X3777598Y-1100388D01*
G37*
G36*
G01X3776947D02*
X3777598D01*
X3773697Y-1102666D01*
X3776947Y-1100388D01*
G37*
G36*
G01X3776133D02*
X3776947D01*
X3773697Y-1102666D01*
X3776133Y-1100388D01*
G37*
G36*
G01X3775517Y-1100226D02*
X3776133Y-1100388D01*
X3773697Y-1102666D01*
X3775517Y-1100226D01*
G37*
G36*
G01X3751326Y-1088512D02*
X3752825Y-1088349D01*
X3753604Y-1088512D01*
X3751326D01*
G37*
G36*
G01X3754255D02*
X3754871Y-1088675D01*
X3749921Y-1089000D01*
X3754255Y-1088512D01*
G37*
G36*
G01X3753604D02*
X3754255D01*
X3749921Y-1089000D01*
X3753604Y-1088512D01*
G37*
G36*
G01D02*
X3749921Y-1089000D01*
X3751326Y-1088512D01*
X3753604D01*
G37*
G36*
G01X3749921Y-1089000D02*
X3754871Y-1088675D01*
X3755452Y-1089000D01*
X3749921D01*
G37*
G36*
G01X3755452D02*
X3748678Y-1089488D01*
X3749921Y-1089000D01*
X3755452D01*
G37*
G36*
G01X3748678Y-1089488D02*
X3755452Y-1089000D01*
X3756487Y-1089488D01*
X3748678D01*
G37*
G36*
G01X3756487D02*
X3747495Y-1090464D01*
X3748678Y-1089488D01*
X3756487D01*
G37*
G36*
G01X3747495Y-1090464D02*
X3756487Y-1089488D01*
X3757256Y-1090464D01*
X3747495D01*
G37*
G36*
G01X3757256D02*
X3752203Y-1091278D01*
X3746474Y-1091441D01*
X3757256Y-1090464D01*
G37*
G36*
G01D02*
X3746474Y-1091441D01*
X3747495Y-1090464D01*
X3757256D01*
G37*
G36*
G01X3746474Y-1091441D02*
X3752203Y-1091278D01*
X3751517Y-1091441D01*
X3746474D01*
G37*
G36*
G01X3752819D02*
X3752203Y-1091278D01*
X3757256Y-1090464D01*
X3752819Y-1091441D01*
G37*
G36*
G01D02*
X3757256Y-1090464D01*
X3757862Y-1091441D01*
X3752819D01*
G37*
G36*
G01X3757862D02*
X3753435Y-1091603D01*
X3752819Y-1091441D01*
X3757862D01*
G37*
G36*
G01X3750275Y-1091929D02*
X3749648Y-1092579D01*
X3745546Y-1092742D01*
X3750275Y-1091929D01*
G37*
G36*
G01X3750832Y-1091603D02*
X3750275Y-1091929D01*
X3745546Y-1092742D01*
X3750832Y-1091603D01*
G37*
G36*
G01X3751517Y-1091441D02*
X3750832Y-1091603D01*
X3745546Y-1092742D01*
X3751517Y-1091441D01*
G37*
G36*
G01D02*
X3745546Y-1092742D01*
X3746474Y-1091441D01*
X3751517D01*
G37*
G36*
G01X3753854Y-1091929D02*
X3753435Y-1091603D01*
X3757862Y-1091441D01*
X3753854Y-1091929D01*
G37*
G36*
G01X3754204Y-1092579D02*
X3753854Y-1091929D01*
X3757862Y-1091441D01*
X3754204Y-1092579D01*
G37*
G36*
G01D02*
X3757862Y-1091441D01*
X3758236Y-1092742D01*
X3754204Y-1092579D01*
G37*
G36*
G01X3745546Y-1092742D02*
X3749648Y-1092579D01*
X3749219Y-1093068D01*
X3745546Y-1092742D01*
G37*
G36*
G01X3758236D02*
X3754425Y-1093068D01*
X3754204Y-1092579D01*
X3758236Y-1092742D01*
G37*
G36*
G01X3749219Y-1093068D02*
X3745246Y-1093393D01*
X3745546Y-1092742D01*
X3749219Y-1093068D01*
G37*
G36*
G01X3754425D02*
X3758236Y-1092742D01*
X3758261Y-1093393D01*
X3754425Y-1093068D01*
G37*
G36*
G01X3745246Y-1093393D02*
X3749219Y-1093068D01*
X3748721Y-1093881D01*
X3745246Y-1093393D01*
G37*
G36*
G01X3758261D02*
X3754578Y-1093881D01*
X3754425Y-1093068D01*
X3758261Y-1093393D01*
G37*
G36*
G01X3748721Y-1093881D02*
X3744910Y-1094206D01*
X3745246Y-1093393D01*
X3748721Y-1093881D01*
G37*
G36*
G01X3754578D02*
X3758261Y-1093393D01*
X3758250Y-1094206D01*
X3754578Y-1093881D01*
G37*
G36*
G01X3744910Y-1094206D02*
X3748721Y-1093881D01*
X3748351Y-1094857D01*
X3744910Y-1094206D01*
G37*
G36*
G01X3758250D02*
X3754533Y-1094857D01*
X3754578Y-1093881D01*
X3758250Y-1094206D01*
G37*
G36*
G01X3748351Y-1094857D02*
X3744737Y-1095020D01*
X3744910Y-1094206D01*
X3748351Y-1094857D01*
G37*
G36*
G01X3754533D02*
X3758250Y-1094206D01*
X3758078Y-1095020D01*
X3754533Y-1094857D01*
G37*
G36*
G01X3744564Y-1095833D02*
X3744737Y-1095020D01*
X3748351Y-1094857D01*
X3744564Y-1095833D01*
G37*
G36*
G01D02*
X3748351Y-1094857D01*
X3748143Y-1095833D01*
X3744564D01*
G37*
G36*
G01X3758078Y-1095020D02*
X3754488Y-1095833D01*
X3754533Y-1094857D01*
X3758078Y-1095020D01*
G37*
G36*
G01X3754488Y-1095833D02*
X3758078Y-1095020D01*
X3758067Y-1095833D01*
X3754488D01*
G37*
G36*
G01X3748143D02*
X3744357Y-1096809D01*
X3744564Y-1095833D01*
X3748143D01*
G37*
G36*
G01X3744357Y-1096809D02*
X3748143Y-1095833D01*
X3747901Y-1096972D01*
X3744357Y-1096809D01*
G37*
G36*
G01X3758067Y-1095833D02*
X3757697Y-1096809D01*
X3754083Y-1096972D01*
X3758067Y-1095833D01*
G37*
G36*
G01D02*
X3754083Y-1096972D01*
X3754488Y-1095833D01*
X3758067D01*
G37*
G36*
G01X3747901Y-1096972D02*
X3744184Y-1097623D01*
X3744357Y-1096809D01*
X3747901Y-1096972D01*
G37*
G36*
G01X3754083D02*
X3757697Y-1096809D01*
X3757524Y-1097623D01*
X3754083Y-1096972D01*
G37*
G36*
G01X3744184Y-1097623D02*
X3747901Y-1096972D01*
X3747857Y-1097948D01*
X3744184Y-1097623D01*
G37*
G36*
G01X3757524D02*
X3753713Y-1097948D01*
X3754083Y-1096972D01*
X3757524Y-1097623D01*
G37*
G36*
G01X3753713Y-1097948D02*
X3757524Y-1097623D01*
X3757223Y-1098273D01*
X3753713Y-1097948D01*
G37*
G36*
G01X3747857D02*
X3744174Y-1098436D01*
X3744184Y-1097623D01*
X3747857Y-1097948D01*
G37*
G36*
G01X3744174Y-1098436D02*
X3747857Y-1097948D01*
X3748044Y-1098599D01*
X3744174Y-1098436D01*
G37*
G36*
G01X3757223Y-1098273D02*
X3753250Y-1098599D01*
X3753713Y-1097948D01*
X3757223Y-1098273D01*
G37*
G36*
G01X3748044Y-1098599D02*
X3744361Y-1099087D01*
X3744174Y-1098436D01*
X3748044Y-1098599D01*
G37*
G36*
G01X3753250D02*
X3757223Y-1098273D01*
X3756887Y-1099087D01*
X3753250Y-1098599D01*
G37*
G36*
G01X3744361Y-1099087D02*
X3748044Y-1098599D01*
X3748231Y-1099249D01*
X3744361Y-1099087D01*
G37*
G36*
G01X3756887D02*
X3752786Y-1099249D01*
X3753250Y-1098599D01*
X3756887Y-1099087D01*
G37*
G36*
G01X3748580Y-1099900D02*
X3748999Y-1100226D01*
X3744572Y-1100388D01*
X3748580Y-1099900D01*
G37*
G36*
G01X3748231Y-1099249D02*
X3748580Y-1099900D01*
X3744572Y-1100388D01*
X3748231Y-1099249D01*
G37*
G36*
G01D02*
X3744572Y-1100388D01*
X3744361Y-1099087D01*
X3748231Y-1099249D01*
G37*
G36*
G01X3744572Y-1100388D02*
X3748999Y-1100226D01*
X3749615Y-1100388D01*
X3744572D01*
G37*
G36*
G01X3752159Y-1099900D02*
X3752786Y-1099249D01*
X3756887Y-1099087D01*
X3752159Y-1099900D01*
G37*
G36*
G01X3751602Y-1100226D02*
X3752159Y-1099900D01*
X3756887Y-1099087D01*
X3751602Y-1100226D01*
G37*
G36*
G01X3750917Y-1100388D02*
X3751602Y-1100226D01*
X3756887Y-1099087D01*
X3750917Y-1100388D01*
G37*
G36*
G01D02*
X3756887Y-1099087D01*
X3755960Y-1100388D01*
X3750917D01*
G37*
G36*
G01X3755960D02*
X3754939Y-1101364D01*
X3745143Y-1101527D01*
X3755960Y-1100388D01*
G37*
G36*
G01X3750917D02*
X3755960D01*
X3745143Y-1101527D01*
X3750917Y-1100388D01*
G37*
G36*
G01X3750266D02*
X3750917D01*
X3745143Y-1101527D01*
X3750266Y-1100388D01*
G37*
G36*
G01X3749615D02*
X3750266D01*
X3745143Y-1101527D01*
X3749615Y-1100388D01*
G37*
G36*
G01D02*
X3745143Y-1101527D01*
X3744572Y-1100388D01*
X3749615D01*
G37*
G36*
G01X3745947Y-1102341D02*
X3745143Y-1101527D01*
X3754939Y-1101364D01*
X3745947Y-1102341D01*
G37*
G36*
G01D02*
X3754939Y-1101364D01*
X3753756Y-1102341D01*
X3745947D01*
G37*
G36*
G01X3753756D02*
X3746982Y-1102829D01*
X3745947Y-1102341D01*
X3753756D01*
G37*
G36*
G01X3746982Y-1102829D02*
X3753756Y-1102341D01*
X3752513Y-1102829D01*
X3746982D01*
G37*
G36*
G01X3752513D02*
X3748214Y-1103154D01*
X3746982Y-1102829D01*
X3752513D01*
G37*
G36*
G01X3748214Y-1103154D02*
X3752513Y-1102829D01*
X3751143Y-1103154D01*
X3748214D01*
G37*
G36*
G01X3751143D02*
X3749644Y-1103317D01*
X3748214Y-1103154D01*
X3751143D01*
G37*
G36*
G01X3766214Y-1089651D02*
X3765419Y-1093393D01*
X3759800Y-1102991D01*
X3766214Y-1089651D01*
G37*
G36*
G01X3766422Y-1088675D02*
X3766214Y-1089651D01*
X3759800Y-1102991D01*
X3766422Y-1088675D01*
G37*
G36*
G01D02*
X3759800Y-1102991D01*
X3762843Y-1088675D01*
X3766422D01*
G37*
G36*
G01X3759800Y-1102991D02*
X3765419Y-1093393D01*
X3763378Y-1102991D01*
X3759800D01*
G37*
G36*
G01X3769704Y-982499D02*
X3765685Y-1002184D01*
X3767407D01*
X3771426Y-982499D01*
X3769704D01*
G37*
G36*
G01X3771426D02*
Y-1002184D01*
X3773148D01*
Y-982499D01*
X3771426D01*
G37*
G36*
G01X3756211Y-984174D02*
X3748461Y-984593D01*
X3755350Y-982918D01*
X3756211Y-984174D01*
G37*
G36*
G01X3755350Y-982918D02*
X3748461Y-984593D01*
X3753628Y-982499D01*
X3755350Y-982918D01*
G37*
G36*
G01X3748461Y-984593D02*
Y-982499D01*
X3753628D01*
X3748461Y-984593D01*
G37*
G36*
G01D02*
X3756211Y-984174D01*
X3753628Y-984593D01*
X3748461D01*
G37*
G36*
G01X3753628D02*
X3756211Y-984174D01*
X3754489Y-985431D01*
X3753628Y-984593D01*
G37*
G36*
G01X3756211Y-984174D02*
X3757073Y-985849D01*
X3754489Y-985431D01*
X3756211Y-984174D01*
G37*
G36*
G01X3755063Y-986268D02*
X3754489Y-985431D01*
X3757073Y-985849D01*
X3755063Y-986268D01*
G37*
G36*
G01D02*
X3757073Y-985849D01*
X3755350Y-987525D01*
X3755063Y-986268D01*
G37*
G36*
G01X3757073Y-985849D02*
X3757359Y-987525D01*
X3755350D01*
X3757073Y-985849D01*
G37*
G36*
G01X3755350Y-988362D02*
Y-987525D01*
X3757359D01*
X3755350Y-988362D01*
G37*
G36*
G01X3757359Y-987525D02*
Y-988362D01*
X3755350D01*
X3757359Y-987525D01*
G37*
G36*
G01X3755063Y-989619D02*
X3755350Y-988362D01*
X3757359D01*
X3755063Y-989619D01*
G37*
G36*
G01X3757359Y-988362D02*
X3757073Y-990038D01*
X3755063Y-989619D01*
X3757359Y-988362D01*
G37*
G36*
G01X3754489Y-990456D02*
X3755063Y-989619D01*
X3757073Y-990038D01*
X3754489Y-990456D01*
G37*
G36*
G01D02*
X3757073Y-990038D01*
X3753628Y-990875D01*
X3754489Y-990456D01*
G37*
G36*
G01X3757073Y-990038D02*
X3756211Y-991713D01*
X3753628Y-990875D01*
X3757073Y-990038D01*
G37*
G36*
G01X3755350Y-992551D02*
X3748461Y-993388D01*
X3756211Y-991713D01*
X3755350Y-992551D01*
G37*
G36*
G01X3756211Y-991713D02*
X3748461Y-993388D01*
X3753628Y-990875D01*
X3756211Y-991713D01*
G37*
G36*
G01X3748461Y-993388D02*
Y-990875D01*
X3753628D01*
X3748461Y-993388D01*
G37*
G36*
G01X3755350Y-992551D02*
X3753628Y-993388D01*
X3748461D01*
X3755350Y-992551D01*
G37*
G36*
G01X3746738Y-982499D02*
Y-1002184D01*
X3748461D01*
Y-982499D01*
X3746738D01*
G37*
G36*
G01X3759369D02*
Y-1002184D01*
X3761091D01*
Y-982499D01*
X3759369D01*
G37*
G36*
G01X3761091D02*
X3765111Y-1002184D01*
X3766833D01*
X3762814Y-982499D01*
X3761091D01*
G37*
G36*
G01X3808187Y-1089651D02*
X3808942Y-1089163D01*
X3812950Y-1088675D01*
X3808187Y-1089651D01*
G37*
G36*
G01X3810178Y-1091766D02*
X3808187Y-1089651D01*
X3812950Y-1088675D01*
X3810178Y-1091766D01*
G37*
G36*
G01X3808187Y-1089651D02*
X3810178Y-1091766D01*
X3809493Y-1091929D01*
X3808187Y-1089651D01*
G37*
G36*
G01D02*
X3809493Y-1091929D01*
X3808773Y-1092254D01*
X3808187Y-1089651D01*
G37*
G36*
G01D02*
X3808773Y-1092254D01*
X3808018Y-1092742D01*
X3808187Y-1089651D01*
G37*
G36*
G01D02*
X3808018Y-1092742D01*
X3807392Y-1093393D01*
X3808187Y-1089651D01*
G37*
G36*
G01D02*
X3807392Y-1093393D01*
X3801772Y-1102991D01*
X3808187Y-1089651D01*
G37*
G36*
G01X3808394Y-1088675D02*
X3808187Y-1089651D01*
X3801772Y-1102991D01*
X3808394Y-1088675D01*
G37*
G36*
G01D02*
X3801772Y-1102991D01*
X3804815Y-1088675D01*
X3808394D01*
G37*
G36*
G01X3801772Y-1102991D02*
X3807392Y-1093393D01*
X3805352Y-1102991D01*
X3801772D01*
G37*
G36*
G01X3778983Y-1088512D02*
X3779831Y-1088349D01*
X3780447Y-1088512D01*
X3778983D01*
G37*
G36*
G01X3780447D02*
X3781098D01*
X3778135Y-1088675D01*
X3780447Y-1088512D01*
G37*
G36*
G01D02*
X3778135Y-1088675D01*
X3778983Y-1088512D01*
X3780447D01*
G37*
G36*
G01X3778135Y-1088675D02*
X3781098Y-1088512D01*
X3781714Y-1088675D01*
X3778135D01*
G37*
G36*
G01X3781714D02*
X3777252Y-1089000D01*
X3778135Y-1088675D01*
X3781714D01*
G37*
G36*
G01X3777252Y-1089000D02*
X3781714Y-1088675D01*
X3782133Y-1089000D01*
X3777252D01*
G37*
G36*
G01X3782133D02*
X3776498Y-1089488D01*
X3777252Y-1089000D01*
X3782133D01*
G37*
G36*
G01X3776498Y-1089488D02*
X3782133Y-1089000D01*
X3783133Y-1089651D01*
X3776498Y-1089488D01*
G37*
G36*
G01X3779499Y-1091441D02*
X3779046Y-1091278D01*
X3783774Y-1090464D01*
X3779499Y-1091441D01*
G37*
G36*
G01D02*
X3783774Y-1090464D01*
X3784217Y-1091441D01*
X3779499D01*
G37*
G36*
G01X3784217D02*
X3779953Y-1091603D01*
X3779499Y-1091441D01*
X3784217D01*
G37*
G36*
G01X3780372Y-1091929D02*
X3779953Y-1091603D01*
X3784217Y-1091441D01*
X3780372Y-1091929D01*
G37*
G36*
G01X3780593Y-1092417D02*
X3780372Y-1091929D01*
X3784217Y-1091441D01*
X3780593Y-1092417D01*
G37*
G36*
G01D02*
X3784217Y-1091441D01*
X3784429Y-1092742D01*
X3780593Y-1092417D01*
G37*
G36*
G01X3784429Y-1092742D02*
X3780780Y-1093068D01*
X3780593Y-1092417D01*
X3784429Y-1092742D01*
G37*
G36*
G01X3780770Y-1093881D02*
X3780780Y-1093068D01*
X3784429Y-1092742D01*
X3780770Y-1093881D01*
G37*
G36*
G01D02*
X3784429Y-1092742D01*
X3784443Y-1094206D01*
X3780770Y-1093881D01*
G37*
G36*
G01X3784443Y-1094206D02*
X3780760Y-1094694D01*
X3780770Y-1093881D01*
X3784443Y-1094206D01*
G37*
G36*
G01X3780681Y-1095833D02*
X3780760Y-1094694D01*
X3784443Y-1094206D01*
X3780681Y-1095833D01*
G37*
G36*
G01D02*
X3784443Y-1094206D01*
X3784260Y-1095833D01*
X3780681D01*
G37*
G36*
G01X3784260D02*
X3780311Y-1096809D01*
X3780681Y-1095833D01*
X3784260D01*
G37*
G36*
G01X3780311Y-1096809D02*
X3784260Y-1095833D01*
X3783751Y-1097460D01*
X3780311Y-1096809D01*
G37*
G36*
G01X3783751Y-1097460D02*
X3779940Y-1097785D01*
X3780311Y-1096809D01*
X3783751Y-1097460D01*
G37*
G36*
G01X3779605Y-1098599D02*
X3779940Y-1097785D01*
X3783751Y-1097460D01*
X3779605Y-1098599D01*
G37*
G36*
G01D02*
X3783751Y-1097460D01*
X3783115Y-1098924D01*
X3779605Y-1098599D01*
G37*
G36*
G01X3783115Y-1098924D02*
X3779141Y-1099249D01*
X3779605Y-1098599D01*
X3783115Y-1098924D01*
G37*
G36*
G01X3778712Y-1099738D02*
X3779141Y-1099249D01*
X3783115Y-1098924D01*
X3778712Y-1099738D01*
G37*
G36*
G01X3778120Y-1100226D02*
X3778712Y-1099738D01*
X3783115Y-1098924D01*
X3778120Y-1100226D01*
G37*
G36*
G01D02*
X3783115Y-1098924D01*
X3782187Y-1100226D01*
X3778120D01*
G37*
G36*
G01X3782187D02*
X3777598Y-1100388D01*
X3778120Y-1100226D01*
X3782187D01*
G37*
G36*
G01X3777598Y-1100388D02*
X3782187Y-1100226D01*
X3781294Y-1101364D01*
X3777598Y-1100388D01*
G37*
G36*
G01X3783133Y-1089651D02*
X3783774Y-1090464D01*
X3779046Y-1091278D01*
X3783133Y-1089651D01*
G37*
G36*
G01D02*
X3779046Y-1091278D01*
X3778198Y-1091441D01*
X3783133Y-1089651D01*
G37*
G36*
G01X3776498Y-1089488D02*
X3783133Y-1089651D01*
X3778198Y-1091441D01*
X3776498Y-1089488D01*
G37*
G36*
G01D02*
X3778198Y-1091441D01*
X3777315Y-1091766D01*
X3776498Y-1089488D01*
G37*
G36*
G01D02*
X3777315Y-1091766D01*
X3776526Y-1092417D01*
X3776498Y-1089488D01*
G37*
G36*
G01D02*
X3776526Y-1092417D01*
X3775702Y-1093230D01*
X3776498Y-1089488D01*
G37*
G36*
G01X3793299Y-1088512D02*
X3794798Y-1088349D01*
X3795577Y-1088512D01*
X3793299D01*
G37*
G36*
G01X3796228D02*
X3796844Y-1088675D01*
X3791894Y-1089000D01*
X3796228Y-1088512D01*
G37*
G36*
G01X3795577D02*
X3796228D01*
X3791894Y-1089000D01*
X3795577Y-1088512D01*
G37*
G36*
G01D02*
X3791894Y-1089000D01*
X3793299Y-1088512D01*
X3795577D01*
G37*
G36*
G01X3791894Y-1089000D02*
X3796844Y-1088675D01*
X3797426Y-1089000D01*
X3791894D01*
G37*
G36*
G01X3797426D02*
X3790652Y-1089488D01*
X3791894Y-1089000D01*
X3797426D01*
G37*
G36*
G01X3790652Y-1089488D02*
X3797426Y-1089000D01*
X3798461Y-1089488D01*
X3790652D01*
G37*
G36*
G01X3798461D02*
X3789468Y-1090464D01*
X3790652Y-1089488D01*
X3798461D01*
G37*
G36*
G01X3789468Y-1090464D02*
X3798461Y-1089488D01*
X3799229Y-1090464D01*
X3789468D01*
G37*
G36*
G01X3799229D02*
X3794176Y-1091278D01*
X3788447Y-1091441D01*
X3799229Y-1090464D01*
G37*
G36*
G01D02*
X3788447Y-1091441D01*
X3789468Y-1090464D01*
X3799229D01*
G37*
G36*
G01X3788447Y-1091441D02*
X3794176Y-1091278D01*
X3793491Y-1091441D01*
X3788447D01*
G37*
G36*
G01X3794792D02*
X3794176Y-1091278D01*
X3799229Y-1090464D01*
X3794792Y-1091441D01*
G37*
G36*
G01D02*
X3799229Y-1090464D01*
X3799835Y-1091441D01*
X3794792D01*
G37*
G36*
G01X3799835D02*
X3795408Y-1091603D01*
X3794792Y-1091441D01*
X3799835D01*
G37*
G36*
G01X3792248Y-1091929D02*
X3791621Y-1092579D01*
X3787520Y-1092742D01*
X3792248Y-1091929D01*
G37*
G36*
G01X3792805Y-1091603D02*
X3792248Y-1091929D01*
X3787520Y-1092742D01*
X3792805Y-1091603D01*
G37*
G36*
G01X3793491Y-1091441D02*
X3792805Y-1091603D01*
X3787520Y-1092742D01*
X3793491Y-1091441D01*
G37*
G36*
G01D02*
X3787520Y-1092742D01*
X3788447Y-1091441D01*
X3793491D01*
G37*
G36*
G01X3795827Y-1091929D02*
X3795408Y-1091603D01*
X3799835Y-1091441D01*
X3795827Y-1091929D01*
G37*
G36*
G01X3796177Y-1092579D02*
X3795827Y-1091929D01*
X3799835Y-1091441D01*
X3796177Y-1092579D01*
G37*
G36*
G01D02*
X3799835Y-1091441D01*
X3800209Y-1092742D01*
X3796177Y-1092579D01*
G37*
G36*
G01X3787520Y-1092742D02*
X3791621Y-1092579D01*
X3791193Y-1093068D01*
X3787520Y-1092742D01*
G37*
G36*
G01X3800209D02*
X3796398Y-1093068D01*
X3796177Y-1092579D01*
X3800209Y-1092742D01*
G37*
G36*
G01X3791193Y-1093068D02*
X3787219Y-1093393D01*
X3787520Y-1092742D01*
X3791193Y-1093068D01*
G37*
G36*
G01X3796398D02*
X3800209Y-1092742D01*
X3800233Y-1093393D01*
X3796398Y-1093068D01*
G37*
G36*
G01X3787219Y-1093393D02*
X3791193Y-1093068D01*
X3790694Y-1093881D01*
X3787219Y-1093393D01*
G37*
G36*
G01X3800233D02*
X3796551Y-1093881D01*
X3796398Y-1093068D01*
X3800233Y-1093393D01*
G37*
G36*
G01X3790694Y-1093881D02*
X3786883Y-1094206D01*
X3787219Y-1093393D01*
X3790694Y-1093881D01*
G37*
G36*
G01X3796551D02*
X3800233Y-1093393D01*
X3800223Y-1094206D01*
X3796551Y-1093881D01*
G37*
G36*
G01X3786883Y-1094206D02*
X3790694Y-1093881D01*
X3790324Y-1094857D01*
X3786883Y-1094206D01*
G37*
G36*
G01X3800223D02*
X3796506Y-1094857D01*
X3796551Y-1093881D01*
X3800223Y-1094206D01*
G37*
G36*
G01X3790324Y-1094857D02*
X3786710Y-1095020D01*
X3786883Y-1094206D01*
X3790324Y-1094857D01*
G37*
G36*
G01X3796506D02*
X3800223Y-1094206D01*
X3800050Y-1095020D01*
X3796506Y-1094857D01*
G37*
G36*
G01X3786537Y-1095833D02*
X3786710Y-1095020D01*
X3790324Y-1094857D01*
X3786537Y-1095833D01*
G37*
G36*
G01D02*
X3790324Y-1094857D01*
X3790117Y-1095833D01*
X3786537D01*
G37*
G36*
G01X3800050Y-1095020D02*
X3796461Y-1095833D01*
X3796506Y-1094857D01*
X3800050Y-1095020D01*
G37*
G36*
G01X3796461Y-1095833D02*
X3800050Y-1095020D01*
X3800040Y-1095833D01*
X3796461D01*
G37*
G36*
G01X3790117D02*
X3786330Y-1096809D01*
X3786537Y-1095833D01*
X3790117D01*
G37*
G36*
G01X3786330Y-1096809D02*
X3790117Y-1095833D01*
X3789874Y-1096972D01*
X3786330Y-1096809D01*
G37*
G36*
G01X3800040Y-1095833D02*
X3799670Y-1096809D01*
X3796056Y-1096972D01*
X3800040Y-1095833D01*
G37*
G36*
G01D02*
X3796056Y-1096972D01*
X3796461Y-1095833D01*
X3800040D01*
G37*
G36*
G01X3789874Y-1096972D02*
X3786157Y-1097623D01*
X3786330Y-1096809D01*
X3789874Y-1096972D01*
G37*
G36*
G01X3796056D02*
X3799670Y-1096809D01*
X3799497Y-1097623D01*
X3796056Y-1096972D01*
G37*
G36*
G01X3786157Y-1097623D02*
X3789874Y-1096972D01*
X3789830Y-1097948D01*
X3786157Y-1097623D01*
G37*
G36*
G01X3799497D02*
X3795686Y-1097948D01*
X3796056Y-1096972D01*
X3799497Y-1097623D01*
G37*
G36*
G01X3795686Y-1097948D02*
X3799497Y-1097623D01*
X3799196Y-1098273D01*
X3795686Y-1097948D01*
G37*
G36*
G01X3789830D02*
X3786147Y-1098436D01*
X3786157Y-1097623D01*
X3789830Y-1097948D01*
G37*
G36*
G01X3786147Y-1098436D02*
X3789830Y-1097948D01*
X3790017Y-1098599D01*
X3786147Y-1098436D01*
G37*
G36*
G01X3799196Y-1098273D02*
X3795222Y-1098599D01*
X3795686Y-1097948D01*
X3799196Y-1098273D01*
G37*
G36*
G01X3790017Y-1098599D02*
X3786334Y-1099087D01*
X3786147Y-1098436D01*
X3790017Y-1098599D01*
G37*
G36*
G01X3795222D02*
X3799196Y-1098273D01*
X3798861Y-1099087D01*
X3795222Y-1098599D01*
G37*
G36*
G01X3786334Y-1099087D02*
X3790017Y-1098599D01*
X3790204Y-1099249D01*
X3786334Y-1099087D01*
G37*
G36*
G01X3798861D02*
X3794759Y-1099249D01*
X3795222Y-1098599D01*
X3798861Y-1099087D01*
G37*
G36*
G01X3790554Y-1099900D02*
X3790972Y-1100226D01*
X3786545Y-1100388D01*
X3790554Y-1099900D01*
G37*
G36*
G01X3790204Y-1099249D02*
X3790554Y-1099900D01*
X3786545Y-1100388D01*
X3790204Y-1099249D01*
G37*
G36*
G01D02*
X3786545Y-1100388D01*
X3786334Y-1099087D01*
X3790204Y-1099249D01*
G37*
G36*
G01X3786545Y-1100388D02*
X3790972Y-1100226D01*
X3791589Y-1100388D01*
X3786545D01*
G37*
G36*
G01X3794133Y-1099900D02*
X3794759Y-1099249D01*
X3798861Y-1099087D01*
X3794133Y-1099900D01*
G37*
G36*
G01X3793575Y-1100226D02*
X3794133Y-1099900D01*
X3798861Y-1099087D01*
X3793575Y-1100226D01*
G37*
G36*
G01X3792890Y-1100388D02*
X3793575Y-1100226D01*
X3798861Y-1099087D01*
X3792890Y-1100388D01*
G37*
G36*
G01D02*
X3798861Y-1099087D01*
X3797933Y-1100388D01*
X3792890D01*
G37*
G36*
G01X3797933D02*
X3796912Y-1101364D01*
X3787117Y-1101527D01*
X3797933Y-1100388D01*
G37*
G36*
G01X3792890D02*
X3797933D01*
X3787117Y-1101527D01*
X3792890Y-1100388D01*
G37*
G36*
G01X3792239D02*
X3792890D01*
X3787117Y-1101527D01*
X3792239Y-1100388D01*
G37*
G36*
G01X3791589D02*
X3792239D01*
X3787117Y-1101527D01*
X3791589Y-1100388D01*
G37*
G36*
G01D02*
X3787117Y-1101527D01*
X3786545Y-1100388D01*
X3791589D01*
G37*
G36*
G01X3775708Y-1103154D02*
X3774929Y-1102991D01*
X3779031Y-1102829D01*
X3775708Y-1103154D01*
G37*
G36*
G01D02*
X3779031Y-1102829D01*
X3777823Y-1103154D01*
X3775708D01*
G37*
G36*
G01X3777823D02*
X3776487Y-1103317D01*
X3775708Y-1103154D01*
X3777823D01*
G37*
G36*
G01X3787920Y-1102341D02*
X3787117Y-1101527D01*
X3796912Y-1101364D01*
X3787920Y-1102341D01*
G37*
G36*
G01D02*
X3796912Y-1101364D01*
X3795729Y-1102341D01*
X3787920D01*
G37*
G36*
G01X3795729D02*
X3788955Y-1102829D01*
X3787920Y-1102341D01*
X3795729D01*
G37*
G36*
G01X3788955Y-1102829D02*
X3795729Y-1102341D01*
X3794486Y-1102829D01*
X3788955D01*
G37*
G36*
G01X3794486D02*
X3790187Y-1103154D01*
X3788955Y-1102829D01*
X3794486D01*
G37*
G36*
G01X3790187Y-1103154D02*
X3794486Y-1102829D01*
X3793115Y-1103154D01*
X3790187D01*
G37*
G36*
G01X3793115D02*
X3791617Y-1103317D01*
X3790187Y-1103154D01*
X3793115D01*
G37*
G36*
G01X3778316Y-982918D02*
X3780039Y-982499D01*
X3782335D01*
X3778316Y-982918D01*
G37*
G36*
G01X3782335Y-982499D02*
X3784057Y-982918D01*
X3778316D01*
X3782335Y-982499D01*
G37*
G36*
G01X3777168Y-984174D02*
X3778316Y-982918D01*
X3784057D01*
X3777168Y-984174D01*
G37*
G36*
G01X3784057Y-982918D02*
X3785206Y-984174D01*
X3777168D01*
X3784057Y-982918D01*
G37*
G36*
G01X3776594Y-985012D02*
X3777168Y-984174D01*
X3785206D01*
X3776594Y-985012D01*
G37*
G36*
G01D02*
X3785206Y-984174D01*
X3780039Y-985012D01*
X3776594D01*
G37*
G36*
G01X3780039D02*
X3785206Y-984174D01*
X3782335Y-985012D01*
X3780039D01*
G37*
G36*
G01X3785206Y-984174D02*
X3785780Y-985012D01*
X3782335D01*
X3785206Y-984174D01*
G37*
G36*
G01X3783483Y-985431D02*
X3782335Y-985012D01*
X3785780D01*
X3783483Y-985431D01*
G37*
G36*
G01X3778029Y-986268D02*
X3775732Y-986687D01*
X3778890Y-985431D01*
X3778029Y-986268D01*
G37*
G36*
G01X3780039Y-985012D02*
X3778890Y-985431D01*
X3776594Y-985012D01*
X3780039D01*
G37*
G36*
G01X3775732Y-986687D02*
X3776594Y-985012D01*
X3778890Y-985431D01*
X3775732Y-986687D01*
G37*
G36*
G01X3783483Y-985431D02*
X3785780Y-985012D01*
X3784344Y-986268D01*
X3783483Y-985431D01*
G37*
G36*
G01X3785780Y-985012D02*
X3786641Y-986687D01*
X3784344Y-986268D01*
X3785780Y-985012D01*
G37*
G36*
G01X3778029Y-986268D02*
X3777455Y-987525D01*
X3775732Y-986687D01*
X3778029Y-986268D01*
G37*
G36*
G01X3784631Y-987525D02*
X3784344Y-986268D01*
X3786641Y-986687D01*
X3784631Y-987525D01*
G37*
G36*
G01X3786641Y-986687D02*
Y-987525D01*
X3784631D01*
X3786641Y-986687D01*
G37*
G36*
G01X3775445Y-989200D02*
X3775732Y-986687D01*
X3777455Y-987525D01*
X3775445Y-989200D01*
G37*
G36*
G01X3777455Y-987525D02*
X3777168Y-989200D01*
X3775445D01*
X3777455Y-987525D01*
G37*
G36*
G01X3775445Y-995482D02*
Y-989200D01*
X3777168D01*
X3775445Y-995482D01*
G37*
G36*
G01X3777168Y-989200D02*
Y-995482D01*
X3775445D01*
X3777168Y-989200D01*
G37*
G36*
G01X3777455Y-997158D02*
X3775732Y-997995D01*
X3777168Y-995482D01*
X3777455Y-997158D01*
G37*
G36*
G01X3775732Y-997995D02*
X3775445Y-995482D01*
X3777168D01*
X3775732Y-997995D01*
G37*
G36*
G01X3777455Y-997158D02*
X3778029Y-998414D01*
X3775732Y-997995D01*
X3777455Y-997158D01*
G37*
G36*
G01X3786641Y-997995D02*
X3784344Y-998414D01*
X3786641Y-997158D01*
Y-997995D01*
G37*
G36*
G01X3784344Y-998414D02*
X3784631Y-997158D01*
X3786641D01*
X3784344Y-998414D01*
G37*
G36*
G01X3778890Y-999252D02*
X3776594Y-999671D01*
X3778029Y-998414D01*
X3778890Y-999252D01*
G37*
G36*
G01X3776594Y-999671D02*
X3775732Y-997995D01*
X3778029Y-998414D01*
X3776594Y-999671D01*
G37*
G36*
G01X3778890Y-999252D02*
X3780039Y-999671D01*
X3776594D01*
X3778890Y-999252D01*
G37*
G36*
G01X3784344Y-998414D02*
X3786641Y-997995D01*
X3783483Y-999252D01*
X3784344Y-998414D01*
G37*
G36*
G01X3782335Y-999671D02*
X3783483Y-999252D01*
X3785780Y-999671D01*
X3782335D01*
G37*
G36*
G01X3786641Y-997995D02*
X3785780Y-999671D01*
X3783483Y-999252D01*
X3786641Y-997995D01*
G37*
G36*
G01X3785780Y-999671D02*
X3777168Y-1000508D01*
X3782335Y-999671D01*
X3785780D01*
G37*
G36*
G01X3782335D02*
X3777168Y-1000508D01*
X3780039Y-999671D01*
X3782335D01*
G37*
G36*
G01X3777168Y-1000508D02*
X3776594Y-999671D01*
X3780039D01*
X3777168Y-1000508D01*
G37*
G36*
G01X3785780Y-999671D02*
X3785206Y-1000508D01*
X3777168D01*
X3785780Y-999671D01*
G37*
G36*
G01X3778316Y-1001765D02*
X3777168Y-1000508D01*
X3785206D01*
X3778316Y-1001765D01*
G37*
G36*
G01X3785206Y-1000508D02*
X3784057Y-1001765D01*
X3778316D01*
X3785206Y-1000508D01*
G37*
G36*
G01X3780039Y-1002184D02*
X3778316Y-1001765D01*
X3784057D01*
X3780039Y-1002184D01*
G37*
G36*
G01X3784057Y-1001765D02*
X3782335Y-1002184D01*
X3780039D01*
X3784057Y-1001765D01*
G37*
G36*
G01X3833965Y-1091603D02*
X3836702Y-1088675D01*
X3836080Y-1091603D01*
X3833965D01*
G37*
G36*
G01X3843897Y-1083144D02*
X3839523Y-1086885D01*
X3840318Y-1083144D01*
X3843897D01*
G37*
G36*
G01X3839523Y-1086885D02*
X3843897Y-1083144D01*
X3843102Y-1086885D01*
X3839523D01*
G37*
G36*
G01X3842721Y-1088675D02*
X3836099Y-1102991D01*
X3839143Y-1088675D01*
X3842721D01*
G37*
G36*
G01X3836099Y-1102991D02*
X3842721Y-1088675D01*
X3839678Y-1102991D01*
X3836099D01*
G37*
G36*
G01X3810544Y-1088512D02*
X3811230Y-1088349D01*
X3812008Y-1088512D01*
X3810544D01*
G37*
G36*
G01X3812008D02*
X3812334D01*
X3809696Y-1088675D01*
X3812008Y-1088512D01*
G37*
G36*
G01D02*
X3809696Y-1088675D01*
X3810544Y-1088512D01*
X3812008D01*
G37*
G36*
G01X3809696Y-1088675D02*
X3812334Y-1088512D01*
X3812950Y-1088675D01*
X3809696D01*
G37*
G36*
G01X3812950D02*
X3808942Y-1089163D01*
X3809696Y-1088675D01*
X3812950D01*
G37*
G36*
G01X3810794Y-1091929D02*
X3810178Y-1091766D01*
X3812950Y-1088675D01*
X3810794Y-1091929D01*
G37*
G36*
G01X3811282D02*
X3810794D01*
X3812950Y-1088675D01*
X3811282Y-1091929D01*
G37*
G36*
G01D02*
X3812950Y-1088675D01*
X3812189Y-1092254D01*
X3811282Y-1091929D01*
G37*
G36*
G01X3819492Y-1088512D02*
X3820991Y-1088349D01*
X3822257Y-1088512D01*
X3819492D01*
G37*
G36*
G01X3822257D02*
X3818319Y-1088675D01*
X3819492Y-1088512D01*
X3822257D01*
G37*
G36*
G01X3818319Y-1088675D02*
X3822257Y-1088512D01*
X3823362Y-1088675D01*
X3818319D01*
G37*
G36*
G01X3823362D02*
X3817273Y-1089000D01*
X3818319Y-1088675D01*
X3823362D01*
G37*
G36*
G01X3817273Y-1089000D02*
X3823362Y-1088675D01*
X3824269Y-1089000D01*
X3817273D01*
G37*
G36*
G01X3824269D02*
X3816193Y-1089488D01*
X3817273Y-1089000D01*
X3824269D01*
G37*
G36*
G01X3816193Y-1089488D02*
X3824269Y-1089000D01*
X3825141Y-1089488D01*
X3816193D01*
G37*
G36*
G01X3825141D02*
X3815404Y-1090139D01*
X3816193Y-1089488D01*
X3825141D01*
G37*
G36*
G01X3815404Y-1090139D02*
X3825141Y-1089488D01*
X3825619Y-1090302D01*
X3815404Y-1090139D01*
G37*
G36*
G01X3825619Y-1090302D02*
X3814581Y-1090953D01*
X3815404Y-1090139D01*
X3825619Y-1090302D01*
G37*
G36*
G01X3820043Y-1091278D02*
X3814581Y-1090953D01*
X3825619Y-1090302D01*
X3820043Y-1091278D01*
G37*
G36*
G01D02*
X3825619Y-1090302D01*
X3825900Y-1091278D01*
X3820043D01*
G37*
G36*
G01X3825900D02*
X3820822Y-1091441D01*
X3820043Y-1091278D01*
X3825900D01*
G37*
G36*
G01X3821472Y-1091441D02*
X3820822D01*
X3825900Y-1091278D01*
X3821472Y-1091441D01*
G37*
G36*
G01X3821891Y-1091766D02*
X3821472Y-1091441D01*
X3825900Y-1091278D01*
X3821891Y-1091766D01*
G37*
G36*
G01D02*
X3825900Y-1091278D01*
X3825958Y-1091766D01*
X3821891D01*
G37*
G36*
G01X3819032Y-1091441D02*
X3818312Y-1091766D01*
X3814048Y-1091929D01*
X3819032Y-1091441D01*
G37*
G36*
G01X3820043Y-1091278D02*
X3819032Y-1091441D01*
X3814048Y-1091929D01*
X3820043Y-1091278D01*
G37*
G36*
G01D02*
X3814048Y-1091929D01*
X3814581Y-1090953D01*
X3820043Y-1091278D01*
G37*
G36*
G01X3814048Y-1091929D02*
X3818312Y-1091766D01*
X3817952Y-1091929D01*
X3814048D01*
G37*
G36*
G01X3825958Y-1091766D02*
X3822182Y-1091929D01*
X3821891Y-1091766D01*
X3825958D01*
G37*
G36*
G01X3822241Y-1092417D02*
X3822182Y-1091929D01*
X3825958Y-1091766D01*
X3822241Y-1092417D01*
G37*
G36*
G01D02*
X3825958Y-1091766D01*
X3825983Y-1092417D01*
X3822241D01*
G37*
G36*
G01X3825983D02*
X3822335Y-1092742D01*
X3822241Y-1092417D01*
X3825983D01*
G37*
G36*
G01X3817720Y-1092254D02*
X3817326Y-1092579D01*
X3813678Y-1092905D01*
X3817720Y-1092254D01*
G37*
G36*
G01X3817952Y-1091929D02*
X3817720Y-1092254D01*
X3813678Y-1092905D01*
X3817952Y-1091929D01*
G37*
G36*
G01D02*
X3813678Y-1092905D01*
X3814048Y-1091929D01*
X3817952D01*
G37*
G36*
G01X3813678Y-1092905D02*
X3817326Y-1092579D01*
X3817257Y-1092905D01*
X3813678D01*
G37*
G36*
G01X3822231Y-1093230D02*
X3822335Y-1092742D01*
X3825983Y-1092417D01*
X3822231Y-1093230D01*
G37*
G36*
G01D02*
X3825983Y-1092417D01*
X3825810Y-1093230D01*
X3822231D01*
G37*
G36*
G01X3825810D02*
X3822290Y-1093718D01*
X3822231Y-1093230D01*
X3825810D01*
G37*
G36*
G01X3822290Y-1093718D02*
X3820628Y-1093881D01*
X3821639Y-1093718D01*
X3822290D01*
G37*
G36*
G01X3820628Y-1093881D02*
X3818641Y-1094044D01*
X3819652Y-1093881D01*
X3820628D01*
G37*
G36*
G01X3825800Y-1094044D02*
X3818641D01*
X3820628Y-1093881D01*
X3825800Y-1094044D01*
G37*
G36*
G01D02*
X3820628Y-1093881D01*
X3822290Y-1093718D01*
X3825800Y-1094044D01*
G37*
G36*
G01X3822290Y-1093718D02*
X3825810Y-1093230D01*
X3825800Y-1094044D01*
X3822290Y-1093718D01*
G37*
G36*
G01X3818641Y-1094044D02*
X3825800D01*
X3816946Y-1094369D01*
X3818641Y-1094044D01*
G37*
G36*
G01D02*
X3816946Y-1094369D01*
X3817828Y-1094044D01*
X3818641D01*
G37*
G36*
G01X3818542Y-1096809D02*
X3820528Y-1096647D01*
X3819518Y-1096809D01*
X3818542D01*
G37*
G36*
G01D02*
X3817694Y-1096972D01*
X3812581Y-1097297D01*
X3818542Y-1096809D01*
G37*
G36*
G01X3820528Y-1096647D02*
X3818542Y-1096809D01*
X3812581Y-1097297D01*
X3820528Y-1096647D01*
G37*
G36*
G01D02*
X3812581Y-1097297D01*
X3813045Y-1096647D01*
X3820528D01*
G37*
G36*
G01X3812581Y-1097297D02*
X3817694Y-1096972D01*
X3816974Y-1097297D01*
X3812581D01*
G37*
G36*
G01X3816974D02*
X3816417Y-1097623D01*
X3812315Y-1097785D01*
X3816974Y-1097297D01*
G37*
G36*
G01D02*
X3812315Y-1097785D01*
X3812581Y-1097297D01*
X3816974D01*
G37*
G36*
G01X3812315Y-1097785D02*
X3816417Y-1097623D01*
X3816022Y-1097948D01*
X3812315Y-1097785D01*
G37*
G36*
G01X3816022Y-1097948D02*
X3812176Y-1098436D01*
X3812315Y-1097785D01*
X3816022Y-1097948D01*
G37*
G36*
G01X3812176Y-1098436D02*
X3816022Y-1097948D01*
X3815756Y-1098436D01*
X3812176D01*
G37*
G36*
G01X3815756D02*
X3812073Y-1098924D01*
X3812176Y-1098436D01*
X3815756D01*
G37*
G36*
G01X3812073Y-1098924D02*
X3815756Y-1098436D01*
X3815652Y-1098924D01*
X3812073D01*
G37*
G36*
G01X3815583Y-1099249D02*
X3815513Y-1099575D01*
X3811865Y-1099900D01*
X3815583Y-1099249D01*
G37*
G36*
G01X3815652Y-1098924D02*
X3815583Y-1099249D01*
X3811865Y-1099900D01*
X3815652Y-1098924D01*
G37*
G36*
G01D02*
X3811865Y-1099900D01*
X3812073Y-1098924D01*
X3815652D01*
G37*
G36*
G01X3811865Y-1099900D02*
X3815513Y-1099575D01*
X3815770Y-1099900D01*
X3811865D01*
G37*
G36*
G01X3817456Y-1100388D02*
X3818432D01*
X3812018Y-1100714D01*
X3817456Y-1100388D01*
G37*
G36*
G01X3816480D02*
X3817456D01*
X3812018Y-1100714D01*
X3816480Y-1100388D01*
G37*
G36*
G01X3815898Y-1100063D02*
X3816480Y-1100388D01*
X3812018Y-1100714D01*
X3815898Y-1100063D01*
G37*
G36*
G01X3815770Y-1099900D02*
X3815898Y-1100063D01*
X3812018Y-1100714D01*
X3815770Y-1099900D01*
G37*
G36*
G01D02*
X3812018Y-1100714D01*
X3811865Y-1099900D01*
X3815770D01*
G37*
G36*
G01X3816260Y-1094532D02*
X3816946Y-1094369D01*
X3825800Y-1094044D01*
X3816260Y-1094532D01*
G37*
G36*
G01X3815540Y-1094857D02*
X3816260Y-1094532D01*
X3825800Y-1094044D01*
X3815540Y-1094857D01*
G37*
G36*
G01X3815018Y-1095020D02*
X3815540Y-1094857D01*
X3825800Y-1094044D01*
X3815018Y-1095020D01*
G37*
G36*
G01X3814426Y-1095508D02*
X3815018Y-1095020D01*
X3825800Y-1094044D01*
X3814426Y-1095508D01*
G37*
G36*
G01X3813869Y-1095833D02*
X3814426Y-1095508D01*
X3825800Y-1094044D01*
X3813869Y-1095833D01*
G37*
G36*
G01X3813439Y-1096321D02*
X3813869Y-1095833D01*
X3825800Y-1094044D01*
X3813439Y-1096321D01*
G37*
G36*
G01X3813045Y-1096647D02*
X3813439Y-1096321D01*
X3825800Y-1094044D01*
X3813045Y-1096647D01*
G37*
G36*
G01X3820528D02*
X3813045D01*
X3825800Y-1094044D01*
X3820528Y-1096647D01*
G37*
G36*
G01X3821667D02*
X3820528D01*
X3825800Y-1094044D01*
X3821667Y-1096647D01*
G37*
G36*
G01X3821183Y-1098924D02*
X3821667Y-1096647D01*
X3825800Y-1094044D01*
X3821183Y-1098924D01*
G37*
G36*
G01X3812333Y-1101527D02*
X3812018Y-1100714D01*
X3818432Y-1100388D01*
X3812333Y-1101527D01*
G37*
G36*
G01X3835348Y-1085096D02*
X3831008Y-1088675D01*
X3831769Y-1085096D01*
X3835348D01*
G37*
G36*
G01X3831008Y-1088675D02*
X3835348Y-1085096D01*
X3834587Y-1088675D01*
X3831008D01*
G37*
G36*
G01X3834587D02*
X3836702D01*
X3828759Y-1091603D01*
X3834587Y-1088675D01*
G37*
G36*
G01X3831008D02*
X3834587D01*
X3828759Y-1091603D01*
X3831008Y-1088675D01*
G37*
G36*
G01D02*
X3828759Y-1091603D01*
X3829381Y-1088675D01*
X3831008D01*
G37*
G36*
G01X3830385Y-1091603D02*
X3828759D01*
X3836702Y-1088675D01*
X3830385Y-1091603D01*
G37*
G36*
G01X3833965D02*
X3830385D01*
X3836702Y-1088675D01*
X3833965Y-1091603D01*
G37*
G36*
G01D02*
X3828864Y-1098762D01*
X3830385Y-1091603D01*
X3833965D01*
G37*
G36*
G01X3828864Y-1098762D02*
X3833965Y-1091603D01*
X3832409Y-1098924D01*
X3828864Y-1098762D01*
G37*
G36*
G01X3832305Y-1099412D02*
X3832236Y-1099738D01*
X3828622Y-1099900D01*
X3832305Y-1099412D01*
G37*
G36*
G01X3832409Y-1098924D02*
X3832305Y-1099412D01*
X3828622Y-1099900D01*
X3832409Y-1098924D01*
G37*
G36*
G01D02*
X3828622Y-1099900D01*
X3828864Y-1098762D01*
X3832409Y-1098924D01*
G37*
G36*
G01X3828622Y-1099900D02*
X3832236Y-1099738D01*
X3832294Y-1100226D01*
X3828622Y-1099900D01*
G37*
G36*
G01X3832748Y-1100388D02*
X3833399D01*
X3828449Y-1100714D01*
X3832748Y-1100388D01*
G37*
G36*
G01X3832423D02*
X3832748D01*
X3828449Y-1100714D01*
X3832423Y-1100388D01*
G37*
G36*
G01X3832294Y-1100226D02*
X3832423Y-1100388D01*
X3828449Y-1100714D01*
X3832294Y-1100226D01*
G37*
G36*
G01D02*
X3828449Y-1100714D01*
X3828622Y-1099900D01*
X3832294Y-1100226D01*
G37*
G36*
G01X3828439Y-1101527D02*
X3828449Y-1100714D01*
X3833399Y-1100388D01*
X3828439Y-1101527D01*
G37*
G36*
G01D02*
X3833399Y-1100388D01*
X3834572Y-1100226D01*
X3828439Y-1101527D01*
G37*
G36*
G01X3820457Y-1102341D02*
X3813393Y-1102666D01*
X3812683Y-1102178D01*
X3820457Y-1102341D01*
G37*
G36*
G01X3813393Y-1102666D02*
X3820457Y-1102341D01*
X3819377Y-1102829D01*
X3813393Y-1102666D01*
G37*
G36*
G01X3819377Y-1102829D02*
X3814137Y-1102991D01*
X3813393Y-1102666D01*
X3819377Y-1102829D01*
G37*
G36*
G01X3814137Y-1102991D02*
X3819377Y-1102829D01*
X3818367Y-1102991D01*
X3814137D01*
G37*
G36*
G01X3812683Y-1102178D02*
X3812333Y-1101527D01*
X3818432Y-1100388D01*
X3812683Y-1102178D01*
G37*
G36*
G01X3820457Y-1102341D02*
X3812683Y-1102178D01*
X3818432Y-1100388D01*
X3820457Y-1102341D01*
G37*
G36*
G01D02*
X3818432Y-1100388D01*
X3819314Y-1100063D01*
X3820457Y-1102341D01*
G37*
G36*
G01D02*
X3819314Y-1100063D01*
X3820394Y-1099575D01*
X3820457Y-1102341D01*
G37*
G36*
G01D02*
X3820394Y-1099575D01*
X3821183Y-1098924D01*
X3820457Y-1102341D01*
G37*
G36*
G01D02*
X3821183Y-1098924D01*
X3825800Y-1094044D01*
X3820457Y-1102341D01*
G37*
G36*
G01X3820319Y-1102991D02*
X3820457Y-1102341D01*
X3825800Y-1094044D01*
X3820319Y-1102991D01*
G37*
G36*
G01D02*
X3825800Y-1094044D01*
X3823898Y-1102991D01*
X3820319D01*
G37*
G36*
G01X3818367D02*
X3815078Y-1103154D01*
X3814137Y-1102991D01*
X3818367D01*
G37*
G36*
G01X3815078Y-1103154D02*
X3818367Y-1102991D01*
X3817356Y-1103154D01*
X3815078D01*
G37*
G36*
G01X3817356D02*
X3816182Y-1103317D01*
X3815078Y-1103154D01*
X3817356D01*
G37*
G36*
G01X3828626Y-1102178D02*
X3828439Y-1101527D01*
X3834572Y-1100226D01*
X3828626Y-1102178D01*
G37*
G36*
G01X3829010Y-1102666D02*
X3828626Y-1102178D01*
X3834572Y-1100226D01*
X3829010Y-1102666D01*
G37*
G36*
G01X3829592Y-1102991D02*
X3829010Y-1102666D01*
X3834572Y-1100226D01*
X3829592Y-1102991D01*
G37*
G36*
G01D02*
X3834572Y-1100226D01*
X3833984Y-1102991D01*
X3829592D01*
G37*
G36*
G01X3833984D02*
X3830533Y-1103154D01*
X3829592Y-1102991D01*
X3833984D01*
G37*
G36*
G01X3830533Y-1103154D02*
X3833984Y-1102991D01*
X3832648Y-1103154D01*
X3830533D01*
G37*
G36*
G01X3832648D02*
X3831475Y-1103317D01*
X3830533Y-1103154D01*
X3832648D01*
G37*
G36*
G01X3834320Y-1030387D02*
X3834753Y-1030203D01*
X3835331D01*
X3834320Y-1030387D01*
G37*
G36*
G01X3835331Y-1030203D02*
X3835764Y-1030387D01*
X3834320D01*
X3835331Y-1030203D01*
G37*
G36*
G01X3834031Y-1030755D02*
X3834320Y-1030387D01*
X3835764D01*
X3834031Y-1030755D01*
G37*
G36*
G01X3835764Y-1030387D02*
X3836052Y-1030755D01*
X3834031D01*
X3835764Y-1030387D01*
G37*
G36*
G01X3833743Y-1030755D02*
X3833887Y-1030940D01*
X3832732D01*
X3833743Y-1030755D01*
G37*
G36*
G01X3833887Y-1030940D02*
X3834031Y-1030755D01*
X3836052D01*
X3833887Y-1030940D01*
G37*
G36*
G01X3834609D02*
X3833021Y-1031124D01*
X3833887Y-1030940D01*
X3834609D01*
G37*
G36*
G01X3833021Y-1031124D02*
X3832732Y-1030940D01*
X3833887D01*
X3833021Y-1031124D01*
G37*
G36*
G01X3834609Y-1030940D02*
X3834320Y-1031124D01*
X3833021D01*
X3834609Y-1030940D01*
G37*
G36*
G01X3833887D02*
X3836052Y-1030755D01*
X3834609Y-1030940D01*
X3833887D01*
G37*
G36*
G01X3834609D02*
X3836052Y-1030755D01*
X3835042Y-1030940D01*
X3834609D01*
G37*
G36*
G01X3835042D02*
X3836052Y-1030755D01*
X3835331Y-1031124D01*
X3835042Y-1030940D01*
G37*
G36*
G01X3836052Y-1030755D02*
X3836197Y-1031124D01*
X3835331D01*
X3836052Y-1030755D01*
G37*
G36*
G01X3833165Y-1031308D02*
X3833021Y-1031124D01*
X3834320D01*
X3833165Y-1031308D01*
G37*
G36*
G01X3834320Y-1031124D02*
X3834176Y-1031308D01*
X3833165D01*
X3834320Y-1031124D01*
G37*
G36*
G01X3835475Y-1031308D02*
X3835331Y-1031124D01*
X3836197D01*
X3835475Y-1031308D01*
G37*
G36*
G01X3833310Y-1031677D02*
X3833165Y-1031308D01*
X3834176D01*
X3833310Y-1031677D01*
G37*
G36*
G01X3834176Y-1031308D02*
X3834031Y-1031677D01*
X3833310D01*
X3834176Y-1031308D01*
G37*
G36*
G01X3835475D02*
X3836197Y-1031124D01*
X3835619Y-1031677D01*
X3835475Y-1031308D01*
G37*
G36*
G01X3836197Y-1031124D02*
X3836341Y-1031677D01*
X3835619D01*
X3836197Y-1031124D01*
G37*
G36*
G01X3838507Y-1030387D02*
X3838940Y-1030203D01*
X3839517D01*
X3838507Y-1030387D01*
G37*
G36*
G01X3839517Y-1030203D02*
X3839950Y-1030387D01*
X3838507D01*
X3839517Y-1030203D01*
G37*
G36*
G01X3840816Y-1030387D02*
X3841249Y-1030203D01*
X3841827D01*
X3840816Y-1030387D01*
G37*
G36*
G01X3841827Y-1030203D02*
X3842260Y-1030387D01*
X3840816D01*
X3841827Y-1030203D01*
G37*
G36*
G01X3838218Y-1030755D02*
X3838507Y-1030387D01*
X3839950D01*
X3838218Y-1030755D01*
G37*
G36*
G01X3839950Y-1030387D02*
X3840239Y-1030755D01*
X3838218D01*
X3839950Y-1030387D01*
G37*
G36*
G01X3840528Y-1030755D02*
X3840816Y-1030387D01*
X3842260D01*
X3840528Y-1030755D01*
G37*
G36*
G01X3842260Y-1030387D02*
X3842548Y-1030755D01*
X3840528D01*
X3842260Y-1030387D01*
G37*
G36*
G01X3838940Y-1030940D02*
X3840239Y-1030755D01*
X3839228Y-1030940D01*
X3838940D01*
G37*
G36*
G01X3840239Y-1030755D02*
X3840383Y-1030940D01*
X3839228D01*
X3840239Y-1030755D01*
G37*
G36*
G01X3840383Y-1030940D02*
X3840528Y-1030755D01*
X3842548D01*
X3840383Y-1030940D01*
G37*
G36*
G01X3841105D02*
X3839517Y-1031124D01*
X3840383Y-1030940D01*
X3841105D01*
G37*
G36*
G01X3839517Y-1031124D02*
X3839228Y-1030940D01*
X3840383D01*
X3839517Y-1031124D01*
G37*
G36*
G01X3841105Y-1030940D02*
X3840816Y-1031124D01*
X3839517D01*
X3841105Y-1030940D01*
G37*
G36*
G01X3840383D02*
X3842548Y-1030755D01*
X3841105Y-1030940D01*
X3840383D01*
G37*
G36*
G01X3841105D02*
X3842548Y-1030755D01*
X3841538Y-1030940D01*
X3841105D01*
G37*
G36*
G01X3841538D02*
X3842548Y-1030755D01*
X3841827Y-1031124D01*
X3841538Y-1030940D01*
G37*
G36*
G01X3842548Y-1030755D02*
X3842693Y-1031124D01*
X3841827D01*
X3842548Y-1030755D01*
G37*
G36*
G01X3839661Y-1031308D02*
X3839517Y-1031124D01*
X3840816D01*
X3839661Y-1031308D01*
G37*
G36*
G01X3840816Y-1031124D02*
X3840672Y-1031308D01*
X3839661D01*
X3840816Y-1031124D01*
G37*
G36*
G01X3841971Y-1031308D02*
X3841827Y-1031124D01*
X3842693D01*
X3841971Y-1031308D01*
G37*
G36*
G01X3839806Y-1031677D02*
X3839661Y-1031308D01*
X3840672D01*
X3839806Y-1031677D01*
G37*
G36*
G01X3840672Y-1031308D02*
X3840528Y-1031677D01*
X3839806D01*
X3840672Y-1031308D01*
G37*
G36*
G01X3841971D02*
X3842693Y-1031124D01*
X3842115Y-1031677D01*
X3841971Y-1031308D01*
G37*
G36*
G01X3842693Y-1031124D02*
X3842837Y-1031677D01*
X3842115D01*
X3842693Y-1031124D01*
G37*
G36*
G01X3840239Y-1030755D02*
X3838940Y-1030940D01*
X3838218Y-1030755D01*
X3840239D01*
G37*
G36*
G01X3838940Y-1030940D02*
X3838507Y-1031124D01*
X3838218Y-1030755D01*
X3838940Y-1030940D01*
G37*
G36*
G01X3838507Y-1031124D02*
X3838218Y-1031492D01*
Y-1030755D01*
X3838507Y-1031124D01*
G37*
G36*
G01X3833310Y-1036100D02*
Y-1031677D01*
X3834031D01*
X3833310Y-1036100D01*
G37*
G36*
G01X3834031Y-1031677D02*
Y-1036100D01*
X3833310D01*
X3834031Y-1031677D01*
G37*
G36*
G01X3835619Y-1036100D02*
Y-1031677D01*
X3836341D01*
X3835619Y-1036100D01*
G37*
G36*
G01X3836341Y-1031677D02*
Y-1036100D01*
X3835619D01*
X3836341Y-1031677D01*
G37*
G36*
G01X3838218Y-1031492D02*
X3837496Y-1036100D01*
X3838218Y-1030755D01*
Y-1031492D01*
G37*
G36*
G01Y-1030755D02*
X3837496Y-1036100D01*
X3838218Y-1030203D01*
Y-1030755D01*
G37*
G36*
G01X3837496Y-1036100D02*
Y-1030203D01*
X3838218D01*
X3837496Y-1036100D01*
G37*
G36*
G01X3838218Y-1031492D02*
Y-1036100D01*
X3837496D01*
X3838218Y-1031492D01*
G37*
G36*
G01X3839806Y-1036100D02*
Y-1031677D01*
X3840528D01*
X3839806Y-1036100D01*
G37*
G36*
G01X3840528Y-1031677D02*
Y-1036100D01*
X3839806D01*
X3840528Y-1031677D01*
G37*
G36*
G01X3842115Y-1036100D02*
Y-1031677D01*
X3842837D01*
X3842115Y-1036100D01*
G37*
G36*
G01X3842837Y-1031677D02*
Y-1036100D01*
X3842115D01*
X3842837Y-1031677D01*
G37*
G36*
G01X3809780Y-1027438D02*
Y-1028360D01*
X3815265D01*
Y-1027438D01*
X3809780D01*
G37*
G36*
G01X3819884Y-1028728D02*
Y-1030203D01*
X3821617Y-1027438D01*
X3820751D01*
X3819884Y-1028728D01*
G37*
G36*
G01X3827247Y-1027438D02*
X3828113Y-1027623D01*
X3826380D01*
X3827247Y-1027438D01*
G37*
G36*
G01X3826092Y-1027807D02*
X3826380Y-1027623D01*
X3828113D01*
X3826092Y-1027807D01*
G37*
G36*
G01X3828113Y-1027623D02*
X3828402Y-1027807D01*
X3826092D01*
X3828113Y-1027623D01*
G37*
G36*
G01X3825659Y-1028175D02*
X3826092Y-1027807D01*
X3828402D01*
X3825659Y-1028175D01*
G37*
G36*
G01X3828402Y-1027807D02*
X3828835Y-1028175D01*
X3825659D01*
X3828402Y-1027807D01*
G37*
G36*
G01X3827247Y-1028360D02*
X3825370Y-1028544D01*
X3828835Y-1028175D01*
X3827247Y-1028360D01*
G37*
G36*
G01X3825370Y-1028544D02*
X3825659Y-1028175D01*
X3828835D01*
X3825370Y-1028544D01*
G37*
G36*
G01X3827247Y-1028360D02*
X3826525Y-1028544D01*
X3825370D01*
X3827247Y-1028360D01*
G37*
G36*
G01D02*
X3828835Y-1028175D01*
X3827969Y-1028544D01*
X3827247Y-1028360D01*
G37*
G36*
G01X3828835Y-1028175D02*
X3829123Y-1028544D01*
X3827969D01*
X3828835Y-1028175D01*
G37*
G36*
G01X3828402Y-1028912D02*
X3827969Y-1028544D01*
X3829123D01*
X3828402Y-1028912D01*
G37*
G36*
G01X3826092D02*
X3825081Y-1029097D01*
X3826525Y-1028544D01*
X3826092Y-1028912D01*
G37*
G36*
G01X3825081Y-1029097D02*
X3825370Y-1028544D01*
X3826525D01*
X3825081Y-1029097D01*
G37*
G36*
G01X3829123Y-1028544D02*
X3829412Y-1029097D01*
X3828402Y-1028912D01*
X3829123Y-1028544D01*
G37*
G36*
G01X3828691Y-1029465D02*
X3828402Y-1028912D01*
X3829412Y-1029097D01*
X3828691Y-1029465D01*
G37*
G36*
G01X3829412Y-1029097D02*
X3829556Y-1029465D01*
X3828691D01*
X3829412Y-1029097D01*
G37*
G36*
G01X3825081D02*
X3826092Y-1028912D01*
X3824937Y-1029465D01*
X3825081Y-1029097D01*
G37*
G36*
G01X3826092Y-1028912D02*
X3825659Y-1029650D01*
X3824937Y-1029465D01*
X3826092Y-1028912D01*
G37*
G36*
G01X3824793Y-1030018D02*
X3824937Y-1029465D01*
X3825659Y-1029650D01*
X3824793Y-1030018D01*
G37*
G36*
G01X3825659Y-1029650D02*
X3825515Y-1030018D01*
X3824793D01*
X3825659Y-1029650D01*
G37*
G36*
G01X3824648Y-1030940D02*
X3824793Y-1030018D01*
X3825515D01*
X3824648Y-1030940D01*
G37*
G36*
G01X3825515Y-1030018D02*
X3825370Y-1031124D01*
X3824648Y-1030940D01*
X3825515Y-1030018D01*
G37*
G36*
G01X3825370Y-1032414D02*
X3824648Y-1032598D01*
X3825370Y-1031124D01*
Y-1032414D01*
G37*
G36*
G01X3824648Y-1032598D02*
Y-1030940D01*
X3825370Y-1031124D01*
X3824648Y-1032598D01*
G37*
G36*
G01D02*
X3825370Y-1032414D01*
X3824793Y-1033520D01*
X3824648Y-1032598D01*
G37*
G36*
G01X3825370Y-1032414D02*
X3825515Y-1033520D01*
X3824793D01*
X3825370Y-1032414D01*
G37*
G36*
G01X3825659Y-1033888D02*
X3824937Y-1034073D01*
X3825515Y-1033520D01*
X3825659Y-1033888D01*
G37*
G36*
G01X3824937Y-1034073D02*
X3824793Y-1033520D01*
X3825515D01*
X3824937Y-1034073D01*
G37*
G36*
G01D02*
X3825659Y-1033888D01*
X3825081Y-1034441D01*
X3824937Y-1034073D01*
G37*
G36*
G01X3826380Y-1030755D02*
X3827247Y-1030571D01*
X3827680D01*
X3826380Y-1030755D01*
G37*
G36*
G01X3827680Y-1030571D02*
X3828546Y-1030755D01*
X3826380D01*
X3827680Y-1030571D01*
G37*
G36*
G01X3825803Y-1031124D02*
X3826380Y-1030755D01*
X3828546D01*
X3825803Y-1031124D01*
G37*
G36*
G01D02*
X3828546Y-1030755D01*
X3827247Y-1031492D01*
X3825803Y-1031124D01*
G37*
G36*
G01X3827247Y-1031492D02*
X3828546Y-1030755D01*
X3827680Y-1031492D01*
X3827247D01*
G37*
G36*
G01X3828546Y-1030755D02*
X3829412Y-1031492D01*
X3827680D01*
X3828546Y-1030755D01*
G37*
G36*
G01X3825226Y-1031677D02*
X3825803Y-1031124D01*
X3827247Y-1031492D01*
X3825226Y-1031677D01*
G37*
G36*
G01X3827247Y-1031492D02*
X3826380Y-1031677D01*
X3825226D01*
X3827247Y-1031492D01*
G37*
G36*
G01X3828257Y-1031677D02*
X3827680Y-1031492D01*
X3829412D01*
X3828257Y-1031677D01*
G37*
G36*
G01D02*
X3829412Y-1031492D01*
X3828691Y-1032045D01*
X3828257Y-1031677D01*
G37*
G36*
G01X3829412Y-1031492D02*
X3829701Y-1032045D01*
X3828691D01*
X3829412Y-1031492D01*
G37*
G36*
G01X3825948Y-1032045D02*
X3824937Y-1032230D01*
X3826380Y-1031677D01*
X3825948Y-1032045D01*
G37*
G36*
G01X3824937Y-1032230D02*
X3825226Y-1031677D01*
X3826380D01*
X3824937Y-1032230D01*
G37*
G36*
G01X3825948Y-1032045D02*
X3825659Y-1032414D01*
X3824937Y-1032230D01*
X3825948Y-1032045D01*
G37*
G36*
G01X3828979Y-1032598D02*
X3828691Y-1032045D01*
X3829701D01*
X3828979Y-1032598D01*
G37*
G36*
G01X3829701Y-1032045D02*
X3829845Y-1032967D01*
X3828979Y-1032598D01*
X3829701Y-1032045D01*
G37*
G36*
G01X3829123Y-1033335D02*
X3828979Y-1032598D01*
X3829845Y-1032967D01*
X3829123Y-1033335D01*
G37*
G36*
G01X3825515Y-1032967D02*
X3824793Y-1033520D01*
X3825659Y-1032414D01*
X3825515Y-1032967D01*
G37*
G36*
G01X3824793Y-1033520D02*
X3824937Y-1032230D01*
X3825659Y-1032414D01*
X3824793Y-1033520D01*
G37*
G36*
G01X3825515Y-1032967D02*
Y-1033520D01*
X3824793D01*
X3825515Y-1032967D01*
G37*
G36*
G01X3829845D02*
Y-1033704D01*
X3829123Y-1033335D01*
X3829845Y-1032967D01*
G37*
G36*
G01X3829123Y-1033888D02*
Y-1033335D01*
X3829845Y-1033704D01*
X3829123Y-1033888D01*
G37*
G36*
G01D02*
X3829845Y-1033704D01*
X3828835Y-1034441D01*
X3829123Y-1033888D01*
G37*
G36*
G01X3829845Y-1033704D02*
X3829701Y-1034441D01*
X3828835D01*
X3829845Y-1033704D01*
G37*
G36*
G01X3832010Y-1030387D02*
X3832443Y-1030203D01*
X3833021D01*
X3832010Y-1030387D01*
G37*
G36*
G01X3833021Y-1030203D02*
X3833454Y-1030387D01*
X3832010D01*
X3833021Y-1030203D01*
G37*
G36*
G01X3831722Y-1030755D02*
X3832010Y-1030387D01*
X3833454D01*
X3831722Y-1030755D01*
G37*
G36*
G01X3833454Y-1030387D02*
X3833743Y-1030755D01*
X3831722D01*
X3833454Y-1030387D01*
G37*
G36*
G01X3832443Y-1030940D02*
X3833743Y-1030755D01*
X3832732Y-1030940D01*
X3832443D01*
G37*
G36*
G01X3833743Y-1030755D02*
X3832443Y-1030940D01*
X3831722Y-1030755D01*
X3833743D01*
G37*
G36*
G01X3832443Y-1030940D02*
X3832010Y-1031124D01*
X3831722Y-1030755D01*
X3832443Y-1030940D01*
G37*
G36*
G01X3832010Y-1031124D02*
X3831722Y-1031492D01*
Y-1030755D01*
X3832010Y-1031124D01*
G37*
G36*
G01X3812089Y-1028360D02*
Y-1036100D01*
X3812956D01*
Y-1028360D01*
X3812089D01*
G37*
G36*
G01X3820751Y-1027438D02*
Y-1036100D01*
X3821617D01*
Y-1027438D01*
X3820751D01*
G37*
G36*
G01X3822772Y-1035178D02*
Y-1036100D01*
X3823493D01*
Y-1035178D01*
X3822772D01*
G37*
G36*
G01X3825659Y-1033888D02*
X3826092Y-1034625D01*
X3825081Y-1034441D01*
X3825659Y-1033888D01*
G37*
G36*
G01X3825370Y-1034994D02*
X3825081Y-1034441D01*
X3826092Y-1034625D01*
X3825370Y-1034994D01*
G37*
G36*
G01X3826092Y-1034625D02*
X3826525Y-1034994D01*
X3825370D01*
X3826092Y-1034625D01*
G37*
G36*
G01X3827247Y-1035178D02*
X3825659Y-1035362D01*
X3826525Y-1034994D01*
X3827247Y-1035178D01*
G37*
G36*
G01X3825659Y-1035362D02*
X3825370Y-1034994D01*
X3826525D01*
X3825659Y-1035362D01*
G37*
G36*
G01D02*
X3827247Y-1035178D01*
X3826092Y-1035731D01*
X3825659Y-1035362D01*
G37*
G36*
G01X3826092Y-1035731D02*
X3827247Y-1035178D01*
X3826380Y-1035916D01*
X3826092Y-1035731D01*
G37*
G36*
G01X3827247Y-1035178D02*
Y-1036100D01*
X3826380Y-1035916D01*
X3827247Y-1035178D01*
G37*
G36*
G01X3828546Y-1034810D02*
X3828835Y-1034441D01*
X3829701D01*
X3828546Y-1034810D01*
G37*
G36*
G01D02*
X3829701Y-1034441D01*
X3828257Y-1034994D01*
X3828546Y-1034810D01*
G37*
G36*
G01X3829701Y-1034441D02*
X3829412Y-1034994D01*
X3828257D01*
X3829701Y-1034441D01*
G37*
G36*
G01X3827680Y-1035178D02*
X3828257Y-1034994D01*
X3829412D01*
X3827680Y-1035178D01*
G37*
G36*
G01X3829412Y-1034994D02*
X3828979Y-1035547D01*
X3827680Y-1035178D01*
X3829412Y-1034994D01*
G37*
G36*
G01X3828546Y-1035916D02*
X3827247Y-1036100D01*
X3828979Y-1035547D01*
X3828546Y-1035916D01*
G37*
G36*
G01X3828979Y-1035547D02*
X3827247Y-1036100D01*
X3827680Y-1035178D01*
X3828979Y-1035547D01*
G37*
G36*
G01X3827247Y-1036100D02*
Y-1035178D01*
X3827680D01*
X3827247Y-1036100D01*
G37*
G36*
G01X3828546Y-1035916D02*
X3827680Y-1036100D01*
X3827247D01*
X3828546Y-1035916D01*
G37*
G36*
G01X3831722Y-1031492D02*
X3831000Y-1036100D01*
X3831722Y-1030755D01*
Y-1031492D01*
G37*
G36*
G01Y-1030755D02*
X3831000Y-1036100D01*
X3831722Y-1030203D01*
Y-1030755D01*
G37*
G36*
G01X3831000Y-1036100D02*
Y-1030203D01*
X3831722D01*
X3831000Y-1036100D01*
G37*
G36*
G01X3831722Y-1031492D02*
Y-1036100D01*
X3831000D01*
X3831722Y-1031492D01*
G37*
G36*
G01X3868623Y-1088512D02*
X3869471Y-1088349D01*
X3870575Y-1088512D01*
X3868623D01*
G37*
G36*
G01X3870575D02*
X3867613Y-1088675D01*
X3868623Y-1088512D01*
X3870575D01*
G37*
G36*
G01X3867613Y-1088675D02*
X3870575Y-1088512D01*
X3871645Y-1088838D01*
X3867613Y-1088675D01*
G37*
G36*
G01X3871645Y-1088838D02*
X3866695Y-1089163D01*
X3867613Y-1088675D01*
X3871645Y-1088838D01*
G37*
G36*
G01X3866695Y-1089163D02*
X3871645Y-1088838D01*
X3872389Y-1089163D01*
X3866695D01*
G37*
G36*
G01X3868977Y-1091441D02*
X3868523Y-1091278D01*
X3873380Y-1090627D01*
X3868977Y-1091441D01*
G37*
G36*
G01X3869302D02*
X3868977D01*
X3873380Y-1090627D01*
X3869302Y-1091441D01*
G37*
G36*
G01D02*
X3873380Y-1090627D01*
X3873695Y-1091441D01*
X3869302D01*
G37*
G36*
G01X3873695D02*
X3869593Y-1091603D01*
X3869302Y-1091441D01*
X3873695D01*
G37*
G36*
G01X3869849Y-1091929D02*
X3869593Y-1091603D01*
X3873695Y-1091441D01*
X3869849Y-1091929D01*
G37*
G36*
G01X3869943Y-1092254D02*
X3869849Y-1091929D01*
X3873695Y-1091441D01*
X3869943Y-1092254D01*
G37*
G36*
G01D02*
X3873695Y-1091441D01*
X3873615Y-1092579D01*
X3869943Y-1092254D01*
G37*
G36*
G01X3873615Y-1092579D02*
X3870002Y-1092742D01*
X3869943Y-1092254D01*
X3873615Y-1092579D01*
G37*
G36*
G01X3869898Y-1093230D02*
X3870002Y-1092742D01*
X3873615Y-1092579D01*
X3869898Y-1093230D01*
G37*
G36*
G01X3869922Y-1093881D02*
X3869898Y-1093230D01*
X3873615Y-1092579D01*
X3869922Y-1093881D01*
G37*
G36*
G01D02*
X3873615Y-1092579D01*
X3873501Y-1093881D01*
X3869922D01*
G37*
G36*
G01X3873065Y-1089814D02*
X3873380Y-1090627D01*
X3868523Y-1091278D01*
X3873065Y-1089814D01*
G37*
G36*
G01D02*
X3868523Y-1091278D01*
X3867838Y-1091441D01*
X3873065Y-1089814D01*
G37*
G36*
G01X3873501Y-1093881D02*
X3867986Y-1102991D01*
X3869922Y-1093881D01*
X3873501D01*
G37*
G36*
G01X3867986Y-1102991D02*
X3873501Y-1093881D01*
X3871565Y-1102991D01*
X3867986D01*
G37*
G36*
G01X3851053Y-1088512D02*
X3852552Y-1088349D01*
X3853331Y-1088512D01*
X3851053D01*
G37*
G36*
G01X3853981D02*
X3854598Y-1088675D01*
X3849648Y-1089000D01*
X3853981Y-1088512D01*
G37*
G36*
G01X3853331D02*
X3853981D01*
X3849648Y-1089000D01*
X3853331Y-1088512D01*
G37*
G36*
G01D02*
X3849648Y-1089000D01*
X3851053Y-1088512D01*
X3853331D01*
G37*
G36*
G01X3849648Y-1089000D02*
X3854598Y-1088675D01*
X3855179Y-1089000D01*
X3849648D01*
G37*
G36*
G01X3855179D02*
X3848405Y-1089488D01*
X3849648Y-1089000D01*
X3855179D01*
G37*
G36*
G01X3848405Y-1089488D02*
X3855179Y-1089000D01*
X3856214Y-1089488D01*
X3848405D01*
G37*
G36*
G01X3856214D02*
X3847222Y-1090464D01*
X3848405Y-1089488D01*
X3856214D01*
G37*
G36*
G01X3847222Y-1090464D02*
X3856214Y-1089488D01*
X3856983Y-1090464D01*
X3847222D01*
G37*
G36*
G01X3856983D02*
X3851929Y-1091278D01*
X3846201Y-1091441D01*
X3856983Y-1090464D01*
G37*
G36*
G01D02*
X3846201Y-1091441D01*
X3847222Y-1090464D01*
X3856983D01*
G37*
G36*
G01X3846201Y-1091441D02*
X3851929Y-1091278D01*
X3851244Y-1091441D01*
X3846201D01*
G37*
G36*
G01X3852546D02*
X3851929Y-1091278D01*
X3856983Y-1090464D01*
X3852546Y-1091441D01*
G37*
G36*
G01D02*
X3856983Y-1090464D01*
X3857589Y-1091441D01*
X3852546D01*
G37*
G36*
G01X3857589D02*
X3853162Y-1091603D01*
X3852546Y-1091441D01*
X3857589D01*
G37*
G36*
G01X3850002Y-1091929D02*
X3849375Y-1092579D01*
X3845273Y-1092742D01*
X3850002Y-1091929D01*
G37*
G36*
G01X3850559Y-1091603D02*
X3850002Y-1091929D01*
X3845273Y-1092742D01*
X3850559Y-1091603D01*
G37*
G36*
G01X3851244Y-1091441D02*
X3850559Y-1091603D01*
X3845273Y-1092742D01*
X3851244Y-1091441D01*
G37*
G36*
G01D02*
X3845273Y-1092742D01*
X3846201Y-1091441D01*
X3851244D01*
G37*
G36*
G01X3853581Y-1091929D02*
X3853162Y-1091603D01*
X3857589Y-1091441D01*
X3853581Y-1091929D01*
G37*
G36*
G01X3853930Y-1092579D02*
X3853581Y-1091929D01*
X3857589Y-1091441D01*
X3853930Y-1092579D01*
G37*
G36*
G01D02*
X3857589Y-1091441D01*
X3857963Y-1092742D01*
X3853930Y-1092579D01*
G37*
G36*
G01X3845273Y-1092742D02*
X3849375Y-1092579D01*
X3848946Y-1093068D01*
X3845273Y-1092742D01*
G37*
G36*
G01X3857963D02*
X3854152Y-1093068D01*
X3853930Y-1092579D01*
X3857963Y-1092742D01*
G37*
G36*
G01X3848946Y-1093068D02*
X3844972Y-1093393D01*
X3845273Y-1092742D01*
X3848946Y-1093068D01*
G37*
G36*
G01X3854152D02*
X3857963Y-1092742D01*
X3857987Y-1093393D01*
X3854152Y-1093068D01*
G37*
G36*
G01X3844972Y-1093393D02*
X3848946Y-1093068D01*
X3848448Y-1093881D01*
X3844972Y-1093393D01*
G37*
G36*
G01X3857987D02*
X3854304Y-1093881D01*
X3854152Y-1093068D01*
X3857987Y-1093393D01*
G37*
G36*
G01X3848448Y-1093881D02*
X3844637Y-1094206D01*
X3844972Y-1093393D01*
X3848448Y-1093881D01*
G37*
G36*
G01X3854304D02*
X3857987Y-1093393D01*
X3857977Y-1094206D01*
X3854304Y-1093881D01*
G37*
G36*
G01X3844637Y-1094206D02*
X3848448Y-1093881D01*
X3848078Y-1094857D01*
X3844637Y-1094206D01*
G37*
G36*
G01X3857977D02*
X3854259Y-1094857D01*
X3854304Y-1093881D01*
X3857977Y-1094206D01*
G37*
G36*
G01X3848078Y-1094857D02*
X3844464Y-1095020D01*
X3844637Y-1094206D01*
X3848078Y-1094857D01*
G37*
G36*
G01X3854259D02*
X3857977Y-1094206D01*
X3857804Y-1095020D01*
X3854259Y-1094857D01*
G37*
G36*
G01X3844291Y-1095833D02*
X3844464Y-1095020D01*
X3848078Y-1094857D01*
X3844291Y-1095833D01*
G37*
G36*
G01D02*
X3848078Y-1094857D01*
X3847870Y-1095833D01*
X3844291D01*
G37*
G36*
G01X3857804Y-1095020D02*
X3854215Y-1095833D01*
X3854259Y-1094857D01*
X3857804Y-1095020D01*
G37*
G36*
G01X3854215Y-1095833D02*
X3857804Y-1095020D01*
X3857794Y-1095833D01*
X3854215D01*
G37*
G36*
G01X3847870D02*
X3844083Y-1096809D01*
X3844291Y-1095833D01*
X3847870D01*
G37*
G36*
G01X3844083Y-1096809D02*
X3847870Y-1095833D01*
X3847628Y-1096972D01*
X3844083Y-1096809D01*
G37*
G36*
G01X3857794Y-1095833D02*
X3857424Y-1096809D01*
X3853810Y-1096972D01*
X3857794Y-1095833D01*
G37*
G36*
G01D02*
X3853810Y-1096972D01*
X3854215Y-1095833D01*
X3857794D01*
G37*
G36*
G01X3847628Y-1096972D02*
X3843911Y-1097623D01*
X3844083Y-1096809D01*
X3847628Y-1096972D01*
G37*
G36*
G01X3853810D02*
X3857424Y-1096809D01*
X3857251Y-1097623D01*
X3853810Y-1096972D01*
G37*
G36*
G01X3843911Y-1097623D02*
X3847628Y-1096972D01*
X3847583Y-1097948D01*
X3843911Y-1097623D01*
G37*
G36*
G01X3857251D02*
X3853440Y-1097948D01*
X3853810Y-1096972D01*
X3857251Y-1097623D01*
G37*
G36*
G01X3853440Y-1097948D02*
X3857251Y-1097623D01*
X3856950Y-1098273D01*
X3853440Y-1097948D01*
G37*
G36*
G01X3847583D02*
X3843900Y-1098436D01*
X3843911Y-1097623D01*
X3847583Y-1097948D01*
G37*
G36*
G01X3843900Y-1098436D02*
X3847583Y-1097948D01*
X3847770Y-1098599D01*
X3843900Y-1098436D01*
G37*
G36*
G01X3856950Y-1098273D02*
X3852976Y-1098599D01*
X3853440Y-1097948D01*
X3856950Y-1098273D01*
G37*
G36*
G01X3847770Y-1098599D02*
X3844087Y-1099087D01*
X3843900Y-1098436D01*
X3847770Y-1098599D01*
G37*
G36*
G01X3852976D02*
X3856950Y-1098273D01*
X3856614Y-1099087D01*
X3852976Y-1098599D01*
G37*
G36*
G01X3844087Y-1099087D02*
X3847770Y-1098599D01*
X3847957Y-1099249D01*
X3844087Y-1099087D01*
G37*
G36*
G01X3856614D02*
X3852513Y-1099249D01*
X3852976Y-1098599D01*
X3856614Y-1099087D01*
G37*
G36*
G01X3848307Y-1099900D02*
X3848726Y-1100226D01*
X3844299Y-1100388D01*
X3848307Y-1099900D01*
G37*
G36*
G01X3847957Y-1099249D02*
X3848307Y-1099900D01*
X3844299Y-1100388D01*
X3847957Y-1099249D01*
G37*
G36*
G01D02*
X3844299Y-1100388D01*
X3844087Y-1099087D01*
X3847957Y-1099249D01*
G37*
G36*
G01X3844299Y-1100388D02*
X3848726Y-1100226D01*
X3849342Y-1100388D01*
X3844299D01*
G37*
G36*
G01X3851886Y-1099900D02*
X3852513Y-1099249D01*
X3856614Y-1099087D01*
X3851886Y-1099900D01*
G37*
G36*
G01X3851329Y-1100226D02*
X3851886Y-1099900D01*
X3856614Y-1099087D01*
X3851329Y-1100226D01*
G37*
G36*
G01X3850644Y-1100388D02*
X3851329Y-1100226D01*
X3856614Y-1099087D01*
X3850644Y-1100388D01*
G37*
G36*
G01D02*
X3856614Y-1099087D01*
X3855687Y-1100388D01*
X3850644D01*
G37*
G36*
G01X3855687D02*
X3854666Y-1101364D01*
X3844870Y-1101527D01*
X3855687Y-1100388D01*
G37*
G36*
G01X3850644D02*
X3855687D01*
X3844870Y-1101527D01*
X3850644Y-1100388D01*
G37*
G36*
G01X3849993D02*
X3850644D01*
X3844870Y-1101527D01*
X3849993Y-1100388D01*
G37*
G36*
G01X3849342D02*
X3849993D01*
X3844870Y-1101527D01*
X3849342Y-1100388D01*
G37*
G36*
G01D02*
X3844870Y-1101527D01*
X3844299Y-1100388D01*
X3849342D01*
G37*
G36*
G01X3872389Y-1089163D02*
X3865941Y-1089651D01*
X3866695Y-1089163D01*
X3872389D01*
G37*
G36*
G01X3865941Y-1089651D02*
X3872389Y-1089163D01*
X3873065Y-1089814D01*
X3865941Y-1089651D01*
G37*
G36*
G01D02*
X3873065Y-1089814D01*
X3867838Y-1091441D01*
X3865941Y-1089651D01*
G37*
G36*
G01D02*
X3867838Y-1091441D01*
X3866956Y-1091766D01*
X3865941Y-1089651D01*
G37*
G36*
G01D02*
X3866956Y-1091766D01*
X3866038Y-1092254D01*
X3865941Y-1089651D01*
G37*
G36*
G01D02*
X3866038Y-1092254D01*
X3865215Y-1093068D01*
X3865941Y-1089651D01*
G37*
G36*
G01X3845673Y-1102341D02*
X3844870Y-1101527D01*
X3854666Y-1101364D01*
X3845673Y-1102341D01*
G37*
G36*
G01D02*
X3854666Y-1101364D01*
X3853482Y-1102341D01*
X3845673D01*
G37*
G36*
G01X3853482D02*
X3846709Y-1102829D01*
X3845673Y-1102341D01*
X3853482D01*
G37*
G36*
G01X3846709Y-1102829D02*
X3853482Y-1102341D01*
X3852240Y-1102829D01*
X3846709D01*
G37*
G36*
G01X3852240D02*
X3847941Y-1103154D01*
X3846709Y-1102829D01*
X3852240D01*
G37*
G36*
G01X3847941Y-1103154D02*
X3852240Y-1102829D01*
X3850869Y-1103154D01*
X3847941D01*
G37*
G36*
G01X3850869D02*
X3849370Y-1103317D01*
X3847941Y-1103154D01*
X3850869D01*
G37*
G36*
G01X3865941Y-1089651D02*
X3865215Y-1093068D01*
X3859526Y-1102991D01*
X3865941Y-1089651D01*
G37*
G36*
G01X3866148Y-1088675D02*
X3865941Y-1089651D01*
X3859526Y-1102991D01*
X3866148Y-1088675D01*
G37*
G36*
G01D02*
X3859526Y-1102991D01*
X3862569Y-1088675D01*
X3866148D01*
G37*
G36*
G01X3859526Y-1102991D02*
X3865215Y-1093068D01*
X3863105Y-1102991D01*
X3859526D01*
G37*
G36*
G01X4007769Y-1109995D02*
X4006194Y-1110247D01*
X4007769Y-1109493D01*
Y-1109995D01*
G37*
G36*
G01X4006194Y-1110247D02*
X4006391Y-1109493D01*
X4007769D01*
X4006194Y-1110247D01*
G37*
G36*
G01D02*
X4007769Y-1109995D01*
X4005604Y-1110749D01*
X4006194Y-1110247D01*
G37*
G36*
G01X4004817Y-1111001D02*
X4005604Y-1110749D01*
X4007178Y-1111001D01*
X4004817D01*
G37*
G36*
G01X4007769Y-1109995D02*
X4007178Y-1111001D01*
X4005604Y-1110749D01*
X4007769Y-1109995D01*
G37*
G36*
G01X4006785Y-1111503D02*
X4005998Y-1112257D01*
X4002061D01*
X4006785Y-1111503D01*
G37*
G36*
G01X4003242Y-1112508D02*
X4002061Y-1112257D01*
X4005998D01*
X4003242Y-1112508D01*
G37*
G36*
G01X4005998Y-1112257D02*
X4004817Y-1112508D01*
X4003242D01*
X4005998Y-1112257D01*
G37*
G36*
G01X4009541Y-1100697D02*
Y-1112508D01*
X4010722D01*
Y-1100697D01*
X4009541D01*
G37*
G36*
G01X4015446Y-1112257D02*
X4010722Y-1112508D01*
X4016234Y-1111503D01*
X4015446Y-1112257D01*
G37*
G36*
G01X4016234Y-1111503D02*
X4010722Y-1112508D01*
X4016628Y-1111001D01*
X4016234Y-1111503D01*
G37*
G36*
G01X4016628Y-1111001D02*
X4010722Y-1112508D01*
X4014265Y-1111001D01*
X4016628D01*
G37*
G36*
G01X4010722Y-1112508D02*
Y-1111001D01*
X4014265D01*
X4010722Y-1112508D01*
G37*
G36*
G01X4015446Y-1112257D02*
X4014265Y-1112508D01*
X4010722D01*
X4015446Y-1112257D01*
G37*
G36*
G01X4000092Y-1108488D02*
Y-1104718D01*
X4001273D01*
X4000092Y-1108488D01*
G37*
G36*
G01X4001273Y-1104718D02*
Y-1108488D01*
X4000092D01*
X4001273Y-1104718D01*
G37*
G36*
G01X4001470Y-1109493D02*
X4000289Y-1109995D01*
X4001273Y-1108488D01*
X4001470Y-1109493D01*
G37*
G36*
G01X4000289Y-1109995D02*
X4000092Y-1108488D01*
X4001273D01*
X4000289Y-1109995D01*
G37*
G36*
G01X4001470Y-1109493D02*
X4001864Y-1110247D01*
X4000289Y-1109995D01*
X4001470Y-1109493D01*
G37*
G36*
G01X4002454Y-1110749D02*
X4000880Y-1111001D01*
X4001864Y-1110247D01*
X4002454Y-1110749D01*
G37*
G36*
G01X4000880Y-1111001D02*
X4000289Y-1109995D01*
X4001864Y-1110247D01*
X4000880Y-1111001D01*
G37*
G36*
G01X4002454Y-1110749D02*
X4003242Y-1111001D01*
X4000880D01*
X4002454Y-1110749D01*
G37*
G36*
G01X4007178Y-1111001D02*
X4001273Y-1111503D01*
X4004817Y-1111001D01*
X4007178D01*
G37*
G36*
G01X4004817D02*
X4001273Y-1111503D01*
X4003242Y-1111001D01*
X4004817D01*
G37*
G36*
G01X4001273Y-1111503D02*
X4000880Y-1111001D01*
X4003242D01*
X4001273Y-1111503D01*
G37*
G36*
G01X4007178Y-1111001D02*
X4006785Y-1111503D01*
X4001273D01*
X4007178Y-1111001D01*
G37*
G36*
G01X4002061Y-1112257D02*
X4001273Y-1111503D01*
X4006785D01*
X4002061Y-1112257D01*
G37*
G36*
G01Y-1100949D02*
X4003242Y-1100697D01*
X4004817D01*
X4002061Y-1100949D01*
G37*
G36*
G01X4004817Y-1100697D02*
X4005998Y-1100949D01*
X4002061D01*
X4004817Y-1100697D01*
G37*
G36*
G01X4003242Y-1102205D02*
X4006785Y-1101703D01*
X4004817Y-1102205D01*
X4003242D01*
G37*
G36*
G01X4006785Y-1101703D02*
X4007178Y-1102205D01*
X4004817D01*
X4006785Y-1101703D01*
G37*
G36*
G01X4005604Y-1102457D02*
X4004817Y-1102205D01*
X4007178D01*
X4005604Y-1102457D01*
G37*
G36*
G01D02*
X4007178Y-1102205D01*
X4006194Y-1102959D01*
X4005604Y-1102457D01*
G37*
G36*
G01X4007178Y-1102205D02*
X4007769Y-1103210D01*
X4006194Y-1102959D01*
X4007178Y-1102205D01*
G37*
G36*
G01X4006391Y-1103713D02*
X4006194Y-1102959D01*
X4007769Y-1103210D01*
X4006391Y-1103713D01*
G37*
G36*
G01X4007769Y-1103210D02*
Y-1103713D01*
X4006391D01*
X4007769Y-1103210D01*
G37*
G36*
G01X4016234Y-1101703D02*
X4010722Y-1102205D01*
X4015446Y-1100949D01*
X4016234Y-1101703D01*
G37*
G36*
G01X4015446Y-1100949D02*
X4010722Y-1102205D01*
X4014265Y-1100697D01*
X4015446Y-1100949D01*
G37*
G36*
G01X4010722Y-1102205D02*
Y-1100697D01*
X4014265D01*
X4010722Y-1102205D01*
G37*
G36*
G01D02*
X4016234Y-1101703D01*
X4014265Y-1102205D01*
X4010722D01*
G37*
G36*
G01X4001273Y-1101703D02*
X4002061Y-1100949D01*
X4005998D01*
X4001273Y-1101703D01*
G37*
G36*
G01X4005998Y-1100949D02*
X4006785Y-1101703D01*
X4001273D01*
X4005998Y-1100949D01*
G37*
G36*
G01X4000880Y-1102205D02*
X4001273Y-1101703D01*
X4006785D01*
X4000880Y-1102205D01*
G37*
G36*
G01D02*
X4006785Y-1101703D01*
X4003242Y-1102205D01*
X4000880D01*
G37*
G36*
G01X4001864Y-1102959D02*
X4000289Y-1103210D01*
X4002454Y-1102457D01*
X4001864Y-1102959D01*
G37*
G36*
G01X4003242Y-1102205D02*
X4002454Y-1102457D01*
X4000880Y-1102205D01*
X4003242D01*
G37*
G36*
G01X4000289Y-1103210D02*
X4000880Y-1102205D01*
X4002454Y-1102457D01*
X4000289Y-1103210D01*
G37*
G36*
G01X4001864Y-1102959D02*
X4001470Y-1103713D01*
X4000289Y-1103210D01*
X4001864Y-1102959D01*
G37*
G36*
G01X4000092Y-1104718D02*
X4000289Y-1103210D01*
X4001470Y-1103713D01*
X4000092Y-1104718D01*
G37*
G36*
G01X4001470Y-1103713D02*
X4001273Y-1104718D01*
X4000092D01*
X4001470Y-1103713D01*
G37*
G36*
G01X4042612Y-1101451D02*
X4037100Y-1107482D01*
X4042612Y-1100697D01*
Y-1101451D01*
G37*
G36*
G01X4037100Y-1107482D02*
X4041824Y-1100697D01*
X4042612D01*
X4037100Y-1107482D01*
G37*
G36*
G01D02*
X4042612Y-1101451D01*
X4037100Y-1108488D01*
Y-1107482D01*
G37*
G36*
G01X4042612Y-1101451D02*
X4037691Y-1108488D01*
X4037100D01*
X4042612Y-1101451D01*
G37*
G36*
G01X4037100Y-1107482D02*
Y-1108990D01*
X4044974D01*
Y-1107482D01*
X4037100D01*
G37*
G36*
G01X4041824Y-1100697D02*
Y-1112508D01*
X4043006D01*
Y-1100697D01*
X4041824D01*
G37*
G36*
G01X4016234Y-1108488D02*
Y-1104718D01*
X4017415D01*
X4016234Y-1108488D01*
G37*
G36*
G01X4017415Y-1104718D02*
Y-1108488D01*
X4016234D01*
X4017415Y-1104718D01*
G37*
G36*
G01X4016037Y-1109493D02*
X4016234Y-1108488D01*
X4017415D01*
X4016037Y-1109493D01*
G37*
G36*
G01X4017415Y-1108488D02*
X4017218Y-1109995D01*
X4016037Y-1109493D01*
X4017415Y-1108488D01*
G37*
G36*
G01X4015643Y-1110247D02*
X4016037Y-1109493D01*
X4017218Y-1109995D01*
X4015643Y-1110247D01*
G37*
G36*
G01D02*
X4017218Y-1109995D01*
X4015053Y-1110749D01*
X4015643Y-1110247D01*
G37*
G36*
G01X4014265Y-1111001D02*
X4015053Y-1110749D01*
X4016628Y-1111001D01*
X4014265D01*
G37*
G36*
G01X4017218Y-1109995D02*
X4016628Y-1111001D01*
X4015053Y-1110749D01*
X4017218Y-1109995D01*
G37*
G36*
G01X4028439Y-1112508D02*
Y-1100697D01*
X4029619D01*
Y-1112508D01*
X4028439D01*
G37*
G36*
G01X4034344Y-1106729D02*
X4029619Y-1107231D01*
X4034935Y-1106226D01*
X4034344Y-1106729D01*
G37*
G36*
G01X4034935Y-1106226D02*
X4029619Y-1107231D01*
X4033163Y-1105723D01*
X4034935Y-1106226D01*
G37*
G36*
G01X4029619Y-1107231D02*
Y-1105723D01*
X4033163D01*
X4029619Y-1107231D01*
G37*
G36*
G01X4034344Y-1106729D02*
X4033163Y-1107231D01*
X4029619D01*
X4034344Y-1106729D01*
G37*
G36*
G01X4034935D02*
X4029619Y-1107231D01*
X4034344Y-1106226D01*
X4034935Y-1106729D01*
G37*
G36*
G01X4034344Y-1106226D02*
X4029619Y-1107231D01*
X4033163Y-1105723D01*
X4034344Y-1106226D01*
G37*
G36*
G01X4029619Y-1107231D02*
Y-1105723D01*
X4033163D01*
X4029619Y-1107231D01*
G37*
G36*
G01D02*
X4034935Y-1106729D01*
X4033163Y-1107231D01*
X4029619D01*
G37*
G36*
G01X4033163D02*
X4034935Y-1106729D01*
X4033754Y-1107482D01*
X4033163Y-1107231D01*
G37*
G36*
G01X4034935Y-1106729D02*
X4035525Y-1107734D01*
X4033754Y-1107482D01*
X4034935Y-1106729D01*
G37*
G36*
G01X4034147Y-1107985D02*
X4033754Y-1107482D01*
X4035525Y-1107734D01*
X4034147Y-1107985D01*
G37*
G36*
G01D02*
X4035525Y-1107734D01*
X4034344Y-1108739D01*
X4034147Y-1107985D01*
G37*
G36*
G01X4035525Y-1107734D02*
X4035722Y-1108739D01*
X4034344D01*
X4035525Y-1107734D01*
G37*
G36*
G01X4034344Y-1109493D02*
Y-1108739D01*
X4035722D01*
X4034344Y-1109493D01*
G37*
G36*
G01X4035722Y-1108739D02*
Y-1109493D01*
X4034344D01*
X4035722Y-1108739D01*
G37*
G36*
G01X4034147Y-1110247D02*
X4034344Y-1109493D01*
X4035722D01*
X4034147Y-1110247D01*
G37*
G36*
G01X4035722Y-1109493D02*
X4035525Y-1110498D01*
X4034147Y-1110247D01*
X4035722Y-1109493D01*
G37*
G36*
G01X4033754Y-1110749D02*
X4034147Y-1110247D01*
X4035525Y-1110498D01*
X4033754Y-1110749D01*
G37*
G36*
G01D02*
X4035525Y-1110498D01*
X4033163Y-1111001D01*
X4033754Y-1110749D01*
G37*
G36*
G01X4035525Y-1110498D02*
X4034935Y-1111503D01*
X4033163Y-1111001D01*
X4035525Y-1110498D01*
G37*
G36*
G01X4034344Y-1112257D02*
X4029619Y-1112508D01*
X4034935Y-1111503D01*
X4034344Y-1112257D01*
G37*
G36*
G01X4034935Y-1111503D02*
X4029619Y-1112508D01*
X4033163Y-1111001D01*
X4034935Y-1111503D01*
G37*
G36*
G01X4029619Y-1112508D02*
Y-1111001D01*
X4033163D01*
X4029619Y-1112508D01*
G37*
G36*
G01X4034344Y-1112257D02*
X4033163Y-1112508D01*
X4029619D01*
X4034344Y-1112257D01*
G37*
G36*
G01X4034935Y-1101703D02*
X4029619Y-1101954D01*
X4034344Y-1100949D01*
X4034935Y-1101703D01*
G37*
G36*
G01X4034344Y-1100949D02*
X4029619Y-1101954D01*
X4033163Y-1100697D01*
X4034344Y-1100949D01*
G37*
G36*
G01X4029619Y-1101954D02*
Y-1100697D01*
X4033163D01*
X4029619Y-1101954D01*
G37*
G36*
G01D02*
X4034935Y-1101703D01*
X4033163Y-1101954D01*
X4029619D01*
G37*
G36*
G01X4016234Y-1101703D02*
X4016628Y-1102205D01*
X4014265D01*
X4016234Y-1101703D01*
G37*
G36*
G01X4015053Y-1102457D02*
X4014265Y-1102205D01*
X4016628D01*
X4015053Y-1102457D01*
G37*
G36*
G01D02*
X4016628Y-1102205D01*
X4015643Y-1102959D01*
X4015053Y-1102457D01*
G37*
G36*
G01X4016628Y-1102205D02*
X4017218Y-1103210D01*
X4015643Y-1102959D01*
X4016628Y-1102205D01*
G37*
G36*
G01X4016037Y-1103713D02*
X4015643Y-1102959D01*
X4017218Y-1103210D01*
X4016037Y-1103713D01*
G37*
G36*
G01D02*
X4017218Y-1103210D01*
X4016234Y-1104718D01*
X4016037Y-1103713D01*
G37*
G36*
G01X4017218Y-1103210D02*
X4017415Y-1104718D01*
X4016234D01*
X4017218Y-1103210D01*
G37*
G36*
G01X4033163Y-1101954D02*
X4034935Y-1101703D01*
X4033754Y-1102457D01*
X4033163Y-1101954D01*
G37*
G36*
G01X4034935Y-1101703D02*
X4035525Y-1102708D01*
X4033754Y-1102457D01*
X4034935Y-1101703D01*
G37*
G36*
G01X4034147Y-1102959D02*
X4033754Y-1102457D01*
X4035525Y-1102708D01*
X4034147Y-1102959D01*
G37*
G36*
G01D02*
X4035525Y-1102708D01*
X4034344Y-1103713D01*
X4034147Y-1102959D01*
G37*
G36*
G01X4035525Y-1102708D02*
X4035722Y-1103713D01*
X4034344D01*
X4035525Y-1102708D01*
G37*
G36*
G01X4034344Y-1104216D02*
Y-1103713D01*
X4035722D01*
X4034344Y-1104216D01*
G37*
G36*
G01X4035722Y-1103713D02*
Y-1104216D01*
X4034344D01*
X4035722Y-1103713D01*
G37*
G36*
G01X4034147Y-1104970D02*
X4034344Y-1104216D01*
X4035722D01*
X4034147Y-1104970D01*
G37*
G36*
G01X4035722Y-1104216D02*
X4035525Y-1105221D01*
X4034147Y-1104970D01*
X4035722Y-1104216D01*
G37*
G36*
G01X4033754Y-1105472D02*
X4034147Y-1104970D01*
X4035525Y-1105221D01*
X4033754Y-1105472D01*
G37*
G36*
G01D02*
X4035525Y-1105221D01*
X4033163Y-1105723D01*
X4033754Y-1105472D01*
G37*
G36*
G01X4035525Y-1105221D02*
X4034935Y-1106226D01*
X4033163Y-1105723D01*
X4035525Y-1105221D01*
G37*
G36*
G01X4072533Y-1105723D02*
X4073517Y-1105472D01*
X4072533Y-1107482D01*
Y-1105723D01*
G37*
G36*
G01X4073517Y-1105472D02*
Y-1107734D01*
X4072533Y-1107482D01*
X4073517Y-1105472D01*
G37*
G36*
G01X4072336Y-1108990D02*
X4072533Y-1107482D01*
X4073517Y-1107734D01*
X4072336Y-1108990D01*
G37*
G36*
G01X4073517Y-1107734D02*
X4073320Y-1108990D01*
X4072336D01*
X4073517Y-1107734D01*
G37*
G36*
G01X4072139Y-1109493D02*
X4072336Y-1108990D01*
X4073320D01*
X4072139Y-1109493D01*
G37*
G36*
G01X4073320Y-1108990D02*
X4073124Y-1109744D01*
X4072139Y-1109493D01*
X4073320Y-1108990D01*
G37*
G36*
G01X4072927Y-1110247D02*
X4071549Y-1110498D01*
X4073124Y-1109744D01*
X4072927Y-1110247D01*
G37*
G36*
G01X4071549Y-1110498D02*
X4072139Y-1109493D01*
X4073124Y-1109744D01*
X4071549Y-1110498D01*
G37*
G36*
G01D02*
X4072927Y-1110247D01*
X4070958Y-1111001D01*
X4071549Y-1110498D01*
G37*
G36*
G01X4072927Y-1110247D02*
X4072533Y-1111001D01*
X4070958D01*
X4072927Y-1110247D01*
G37*
G36*
G01X4069974Y-1111252D02*
X4070958Y-1111001D01*
X4072533D01*
X4069974Y-1111252D01*
G37*
G36*
G01X4071549Y-1112006D02*
X4071155Y-1112257D01*
X4068793D01*
X4071549Y-1112006D01*
G37*
G36*
G01X4069974Y-1112508D02*
X4068793Y-1112257D01*
X4071155D01*
X4069974Y-1112508D01*
G37*
G36*
G01X4075092Y-1108488D02*
Y-1104718D01*
X4076273D01*
X4075092Y-1108488D01*
G37*
G36*
G01X4076273Y-1104718D02*
Y-1108488D01*
X4075092D01*
X4076273Y-1104718D01*
G37*
G36*
G01X4076470Y-1109493D02*
X4075289Y-1109995D01*
X4076273Y-1108488D01*
X4076470Y-1109493D01*
G37*
G36*
G01X4075289Y-1109995D02*
X4075092Y-1108488D01*
X4076273D01*
X4075289Y-1109995D01*
G37*
G36*
G01X4076470Y-1109493D02*
X4076864Y-1110247D01*
X4075289Y-1109995D01*
X4076470Y-1109493D01*
G37*
G36*
G01X4077454Y-1110749D02*
X4075880Y-1111001D01*
X4076864Y-1110247D01*
X4077454Y-1110749D01*
G37*
G36*
G01X4075880Y-1111001D02*
X4075289Y-1109995D01*
X4076864Y-1110247D01*
X4075880Y-1111001D01*
G37*
G36*
G01X4077454Y-1110749D02*
X4078242Y-1111001D01*
X4075880D01*
X4077454Y-1110749D01*
G37*
G36*
G01X4082179Y-1111001D02*
X4076273Y-1111503D01*
X4079817Y-1111001D01*
X4082179D01*
G37*
G36*
G01X4079817D02*
X4076273Y-1111503D01*
X4078242Y-1111001D01*
X4079817D01*
G37*
G36*
G01X4076273Y-1111503D02*
X4075880Y-1111001D01*
X4078242D01*
X4076273Y-1111503D01*
G37*
G36*
G01X4082179Y-1111001D02*
X4081785Y-1111503D01*
X4076273D01*
X4082179Y-1111001D01*
G37*
G36*
G01X4077061Y-1112257D02*
X4076273Y-1111503D01*
X4081785D01*
X4077061Y-1112257D01*
G37*
G36*
G01X4081785Y-1111503D02*
X4080998Y-1112257D01*
X4077061D01*
X4081785Y-1111503D01*
G37*
G36*
G01X4078242Y-1112508D02*
X4077061Y-1112257D01*
X4080998D01*
X4078242Y-1112508D01*
G37*
G36*
G01X4080998Y-1112257D02*
X4079817Y-1112508D01*
X4078242D01*
X4080998Y-1112257D01*
G37*
G36*
G01X4051667Y-1106729D02*
X4050486Y-1106980D01*
X4052257Y-1106477D01*
X4051667Y-1106729D01*
G37*
G36*
G01X4050486Y-1106980D02*
Y-1105975D01*
X4052257Y-1106477D01*
X4050486Y-1106980D01*
G37*
G36*
G01X4052257Y-1106477D02*
X4049698Y-1106980D01*
X4051667Y-1106226D01*
X4052257Y-1106477D01*
G37*
G36*
G01X4051667Y-1106226D02*
X4049698Y-1106980D01*
X4050486Y-1105975D01*
X4051667Y-1106226D01*
G37*
G36*
G01X4049698Y-1106980D02*
Y-1105975D01*
X4050486D01*
X4049698Y-1106980D01*
G37*
G36*
G01D02*
X4052257Y-1106477D01*
X4050486Y-1106980D01*
X4049698D01*
G37*
G36*
G01X4050486D02*
X4052257Y-1106477D01*
X4051470Y-1107231D01*
X4050486Y-1106980D01*
G37*
G36*
G01X4052257Y-1106477D02*
X4053045Y-1107231D01*
X4051470D01*
X4052257Y-1106477D01*
G37*
G36*
G01X4051863Y-1107482D02*
X4051470Y-1107231D01*
X4053045D01*
X4051863Y-1107482D01*
G37*
G36*
G01D02*
X4053045Y-1107231D01*
X4052257Y-1107985D01*
X4051863Y-1107482D01*
G37*
G36*
G01X4053045Y-1107231D02*
X4053439Y-1107985D01*
X4052257D01*
X4053045Y-1107231D01*
G37*
G36*
G01X4052651Y-1108739D02*
X4052257Y-1107985D01*
X4053439D01*
X4052651Y-1108739D01*
G37*
G36*
G01X4053439Y-1107985D02*
X4053635Y-1108990D01*
X4052651Y-1108739D01*
X4053439Y-1107985D01*
G37*
G36*
G01X4052651Y-1109744D02*
Y-1108739D01*
X4053635Y-1108990D01*
X4052651Y-1109744D01*
G37*
G36*
G01X4053635Y-1108990D02*
Y-1109744D01*
X4052651D01*
X4053635Y-1108990D01*
G37*
G36*
G01X4052454Y-1110247D02*
X4052651Y-1109744D01*
X4053635D01*
X4052454Y-1110247D01*
G37*
G36*
G01X4047730D02*
X4046746Y-1110498D01*
X4047533Y-1109744D01*
X4047730Y-1110247D01*
G37*
G36*
G01X4046746Y-1110498D02*
X4046549Y-1109744D01*
X4047533D01*
X4046746Y-1110498D01*
G37*
G36*
G01X4053635Y-1109744D02*
X4053439Y-1110498D01*
X4052454Y-1110247D01*
X4053635Y-1109744D01*
G37*
G36*
G01X4047730Y-1110247D02*
X4048124Y-1110749D01*
X4046746Y-1110498D01*
X4047730Y-1110247D01*
G37*
G36*
G01X4052061Y-1110749D02*
X4052454Y-1110247D01*
X4053439Y-1110498D01*
X4052061Y-1110749D01*
G37*
G36*
G01X4048517Y-1111001D02*
X4047139Y-1111252D01*
X4048124Y-1110749D01*
X4048517Y-1111001D01*
G37*
G36*
G01X4047139Y-1111252D02*
X4046746Y-1110498D01*
X4048124Y-1110749D01*
X4047139Y-1111252D01*
G37*
G36*
G01X4048517Y-1111001D02*
X4049502Y-1111252D01*
X4047139D01*
X4048517Y-1111001D01*
G37*
G36*
G01X4052061Y-1110749D02*
X4053439Y-1110498D01*
X4051667Y-1111001D01*
X4052061Y-1110749D01*
G37*
G36*
G01X4050683Y-1111252D02*
X4051667Y-1111001D01*
X4053045Y-1111252D01*
X4050683D01*
G37*
G36*
G01X4053439Y-1110498D02*
X4053045Y-1111252D01*
X4051667Y-1111001D01*
X4053439Y-1110498D01*
G37*
G36*
G01X4053045Y-1111252D02*
X4047730Y-1111755D01*
X4050683Y-1111252D01*
X4053045D01*
G37*
G36*
G01X4050683D02*
X4047730Y-1111755D01*
X4049502Y-1111252D01*
X4050683D01*
G37*
G36*
G01X4047730Y-1111755D02*
X4047139Y-1111252D01*
X4049502D01*
X4047730Y-1111755D01*
G37*
G36*
G01X4053045Y-1111252D02*
X4052454Y-1111755D01*
X4047730D01*
X4053045Y-1111252D01*
G37*
G36*
G01X4048517Y-1112257D02*
X4047730Y-1111755D01*
X4052454D01*
X4048517Y-1112257D01*
G37*
G36*
G01X4052454Y-1111755D02*
X4051667Y-1112257D01*
X4048517D01*
X4052454Y-1111755D01*
G37*
G36*
G01X4049305Y-1112508D02*
X4048517Y-1112257D01*
X4051667D01*
X4049305Y-1112508D01*
G37*
G36*
G01X4051667Y-1112257D02*
X4050880Y-1112508D01*
X4049305D01*
X4051667Y-1112257D01*
G37*
G36*
G01X4049698Y-1105975D02*
Y-1106980D01*
X4047927Y-1106477D01*
X4049698Y-1105975D01*
G37*
G36*
G01X4047139Y-1107231D02*
X4047927Y-1106477D01*
X4049698Y-1106980D01*
X4047139Y-1107231D01*
G37*
G36*
G01X4049698Y-1106980D02*
X4048714Y-1107231D01*
X4047139D01*
X4049698Y-1106980D01*
G37*
G36*
G01X4048320Y-1107482D02*
X4046746Y-1107985D01*
X4048714Y-1107231D01*
X4048320Y-1107482D01*
G37*
G36*
G01X4046746Y-1107985D02*
X4047139Y-1107231D01*
X4048714D01*
X4046746Y-1107985D01*
G37*
G36*
G01X4048320Y-1107482D02*
X4047927Y-1107985D01*
X4046746D01*
X4048320Y-1107482D01*
G37*
G36*
G01X4046549Y-1108488D02*
X4046746Y-1107985D01*
X4047927D01*
X4046549Y-1108488D01*
G37*
G36*
G01X4047927Y-1107985D02*
X4047533Y-1108990D01*
X4046549Y-1108488D01*
X4047927Y-1107985D01*
G37*
G36*
G01X4046549Y-1109744D02*
Y-1108488D01*
X4047533Y-1108990D01*
X4046549Y-1109744D01*
G37*
G36*
G01X4047533Y-1108990D02*
Y-1109744D01*
X4046549D01*
X4047533Y-1108990D01*
G37*
G36*
G01X4055210Y-1111252D02*
Y-1112508D01*
X4056194D01*
Y-1111252D01*
X4055210D01*
G37*
G36*
G01X4058754Y-1107482D02*
X4057769Y-1107734D01*
X4058754Y-1105723D01*
Y-1107482D01*
G37*
G36*
G01X4057769Y-1107734D02*
Y-1105472D01*
X4058754Y-1105723D01*
X4057769Y-1107734D01*
G37*
G36*
G01D02*
X4058754Y-1107482D01*
X4057966Y-1108990D01*
X4057769Y-1107734D01*
G37*
G36*
G01X4058754Y-1107482D02*
X4058950Y-1108990D01*
X4057966D01*
X4058754Y-1107482D01*
G37*
G36*
G01X4063872Y-1105723D02*
X4064856Y-1105472D01*
X4063872Y-1107482D01*
Y-1105723D01*
G37*
G36*
G01X4064856Y-1105472D02*
Y-1107734D01*
X4063872Y-1107482D01*
X4064856Y-1105472D01*
G37*
G36*
G01X4063675Y-1108990D02*
X4063872Y-1107482D01*
X4064856Y-1107734D01*
X4063675Y-1108990D01*
G37*
G36*
G01X4064856Y-1107734D02*
X4064659Y-1108990D01*
X4063675D01*
X4064856Y-1107734D01*
G37*
G36*
G01X4063478Y-1109493D02*
X4063675Y-1108990D01*
X4064659D01*
X4063478Y-1109493D01*
G37*
G36*
G01X4059147D02*
X4058163Y-1109744D01*
X4058950Y-1108990D01*
X4059147Y-1109493D01*
G37*
G36*
G01X4058163Y-1109744D02*
X4057966Y-1108990D01*
X4058950D01*
X4058163Y-1109744D01*
G37*
G36*
G01X4064659Y-1108990D02*
X4064462Y-1109744D01*
X4063478Y-1109493D01*
X4064659Y-1108990D01*
G37*
G36*
G01X4058163Y-1109744D02*
X4059147Y-1109493D01*
X4058360Y-1110247D01*
X4058163Y-1109744D01*
G37*
G36*
G01X4059147Y-1109493D02*
X4059738Y-1110498D01*
X4058360Y-1110247D01*
X4059147Y-1109493D01*
G37*
G36*
G01X4064265Y-1110247D02*
X4062887Y-1110498D01*
X4064462Y-1109744D01*
X4064265Y-1110247D01*
G37*
G36*
G01X4062887Y-1110498D02*
X4063478Y-1109493D01*
X4064462Y-1109744D01*
X4062887Y-1110498D01*
G37*
G36*
G01X4058754Y-1111001D02*
X4058360Y-1110247D01*
X4059738Y-1110498D01*
X4058754Y-1111001D01*
G37*
G36*
G01X4059738Y-1110498D02*
X4060328Y-1111001D01*
X4058754D01*
X4059738Y-1110498D01*
G37*
G36*
G01X4062887D02*
X4064265Y-1110247D01*
X4062296Y-1111001D01*
X4062887Y-1110498D01*
G37*
G36*
G01X4064265Y-1110247D02*
X4063872Y-1111001D01*
X4062296D01*
X4064265Y-1110247D01*
G37*
G36*
G01X4061313Y-1111252D02*
X4062296Y-1111001D01*
X4063872D01*
X4061313Y-1111252D01*
G37*
G36*
G01D02*
X4059147Y-1111503D01*
X4060328Y-1111001D01*
X4061313Y-1111252D01*
G37*
G36*
G01X4059147Y-1111503D02*
X4058754Y-1111001D01*
X4060328D01*
X4059147Y-1111503D01*
G37*
G36*
G01X4061313Y-1111252D02*
X4063872Y-1111001D01*
X4059147Y-1111503D01*
X4061313Y-1111252D01*
G37*
G36*
G01X4063872Y-1111001D02*
X4063478Y-1111503D01*
X4059147D01*
X4063872Y-1111001D01*
G37*
G36*
G01X4059738Y-1112006D02*
X4059147Y-1111503D01*
X4063478D01*
X4059738Y-1112006D01*
G37*
G36*
G01X4063478Y-1111503D02*
X4062887Y-1112006D01*
X4059738D01*
X4063478Y-1111503D01*
G37*
G36*
G01X4060131Y-1112257D02*
X4059738Y-1112006D01*
X4062887D01*
X4060131Y-1112257D01*
G37*
G36*
G01X4062887Y-1112006D02*
X4062493Y-1112257D01*
X4060131D01*
X4062887Y-1112006D01*
G37*
G36*
G01X4061313Y-1112508D02*
X4060131Y-1112257D01*
X4062493D01*
X4061313Y-1112508D01*
G37*
G36*
G01X4067415Y-1107482D02*
X4066431Y-1107734D01*
X4067415Y-1105723D01*
Y-1107482D01*
G37*
G36*
G01X4066431Y-1107734D02*
Y-1105472D01*
X4067415Y-1105723D01*
X4066431Y-1107734D01*
G37*
G36*
G01D02*
X4067415Y-1107482D01*
X4066628Y-1108990D01*
X4066431Y-1107734D01*
G37*
G36*
G01X4067415Y-1107482D02*
X4067612Y-1108990D01*
X4066628D01*
X4067415Y-1107482D01*
G37*
G36*
G01X4067809Y-1109493D02*
X4066824Y-1109744D01*
X4067612Y-1108990D01*
X4067809Y-1109493D01*
G37*
G36*
G01X4066824Y-1109744D02*
X4066628Y-1108990D01*
X4067612D01*
X4066824Y-1109744D01*
G37*
G36*
G01D02*
X4067809Y-1109493D01*
X4067021Y-1110247D01*
X4066824Y-1109744D01*
G37*
G36*
G01X4067809Y-1109493D02*
X4068399Y-1110498D01*
X4067021Y-1110247D01*
X4067809Y-1109493D01*
G37*
G36*
G01X4067415Y-1111001D02*
X4067021Y-1110247D01*
X4068399Y-1110498D01*
X4067415Y-1111001D01*
G37*
G36*
G01X4068399Y-1110498D02*
X4068990Y-1111001D01*
X4067415D01*
X4068399Y-1110498D01*
G37*
G36*
G01X4069974Y-1111252D02*
X4067809Y-1111503D01*
X4068990Y-1111001D01*
X4069974Y-1111252D01*
G37*
G36*
G01X4067809Y-1111503D02*
X4067415Y-1111001D01*
X4068990D01*
X4067809Y-1111503D01*
G37*
G36*
G01X4069974Y-1111252D02*
X4072533Y-1111001D01*
X4067809Y-1111503D01*
X4069974Y-1111252D01*
G37*
G36*
G01X4072533Y-1111001D02*
X4072139Y-1111503D01*
X4067809D01*
X4072533Y-1111001D01*
G37*
G36*
G01X4068399Y-1112006D02*
X4067809Y-1111503D01*
X4072139D01*
X4068399Y-1112006D01*
G37*
G36*
G01X4072139Y-1111503D02*
X4071549Y-1112006D01*
X4068399D01*
X4072139Y-1111503D01*
G37*
G36*
G01X4068793Y-1112257D02*
X4068399Y-1112006D01*
X4071549D01*
X4068793Y-1112257D01*
G37*
G36*
G01X4069974Y-1100697D02*
X4071155Y-1100949D01*
X4068793D01*
X4069974Y-1100697D01*
G37*
G36*
G01X4077061Y-1100949D02*
X4078242Y-1100697D01*
X4079817D01*
X4077061Y-1100949D01*
G37*
G36*
G01X4079817Y-1100697D02*
X4080998Y-1100949D01*
X4077061D01*
X4079817Y-1100697D01*
G37*
G36*
G01X4076273Y-1101703D02*
X4077061Y-1100949D01*
X4080998D01*
X4076273Y-1101703D01*
G37*
G36*
G01X4080998Y-1100949D02*
X4081785Y-1101703D01*
X4076273D01*
X4080998Y-1100949D01*
G37*
G36*
G01X4069974Y-1101954D02*
X4072139Y-1101703D01*
X4070958Y-1102205D01*
X4069974Y-1101954D01*
G37*
G36*
G01X4072139Y-1101703D02*
X4072533Y-1102205D01*
X4070958D01*
X4072139Y-1101703D01*
G37*
G36*
G01X4071549Y-1102708D02*
X4070958Y-1102205D01*
X4072533D01*
X4071549Y-1102708D01*
G37*
G36*
G01X4072533Y-1102205D02*
X4072927Y-1102959D01*
X4071549Y-1102708D01*
X4072533Y-1102205D01*
G37*
G36*
G01X4073124Y-1103462D02*
X4072139Y-1103713D01*
X4072927Y-1102959D01*
X4073124Y-1103462D01*
G37*
G36*
G01X4072139Y-1103713D02*
X4071549Y-1102708D01*
X4072927Y-1102959D01*
X4072139Y-1103713D01*
G37*
G36*
G01D02*
X4073124Y-1103462D01*
X4072336Y-1104216D01*
X4072139Y-1103713D01*
G37*
G36*
G01X4073124Y-1103462D02*
X4073320Y-1104216D01*
X4072336D01*
X4073124Y-1103462D01*
G37*
G36*
G01X4073517Y-1105472D02*
X4072533Y-1105723D01*
X4073320Y-1104216D01*
X4073517Y-1105472D01*
G37*
G36*
G01X4072533Y-1105723D02*
X4072336Y-1104216D01*
X4073320D01*
X4072533Y-1105723D01*
G37*
G36*
G01X4075880Y-1102205D02*
X4076273Y-1101703D01*
X4081785D01*
X4075880Y-1102205D01*
G37*
G36*
G01D02*
X4081785Y-1101703D01*
X4078242Y-1102205D01*
X4075880D01*
G37*
G36*
G01X4078242D02*
X4081785Y-1101703D01*
X4079817Y-1102205D01*
X4078242D01*
G37*
G36*
G01X4076864Y-1102959D02*
X4075289Y-1103210D01*
X4077454Y-1102457D01*
X4076864Y-1102959D01*
G37*
G36*
G01X4078242Y-1102205D02*
X4077454Y-1102457D01*
X4075880Y-1102205D01*
X4078242D01*
G37*
G36*
G01X4075289Y-1103210D02*
X4075880Y-1102205D01*
X4077454Y-1102457D01*
X4075289Y-1103210D01*
G37*
G36*
G01X4076864Y-1102959D02*
X4076470Y-1103713D01*
X4075289Y-1103210D01*
X4076864Y-1102959D01*
G37*
G36*
G01X4075092Y-1104718D02*
X4075289Y-1103210D01*
X4076470Y-1103713D01*
X4075092Y-1104718D01*
G37*
G36*
G01X4076470Y-1103713D02*
X4076273Y-1104718D01*
X4075092D01*
X4076470Y-1103713D01*
G37*
G36*
G01X4048517Y-1100949D02*
X4049895Y-1100697D01*
X4050289D01*
X4048517Y-1100949D01*
G37*
G36*
G01X4050289Y-1100697D02*
X4051667Y-1100949D01*
X4048517D01*
X4050289Y-1100697D01*
G37*
G36*
G01X4047730Y-1101451D02*
X4048517Y-1100949D01*
X4051667D01*
X4047730Y-1101451D01*
G37*
G36*
G01X4051667Y-1100949D02*
X4052454Y-1101451D01*
X4047730D01*
X4051667Y-1100949D01*
G37*
G36*
G01X4047336Y-1101954D02*
X4047730Y-1101451D01*
X4052454D01*
X4047336Y-1101954D01*
G37*
G36*
G01D02*
X4052454Y-1101451D01*
X4049698Y-1101954D01*
X4047336D01*
G37*
G36*
G01X4049698D02*
X4052454Y-1101451D01*
X4050486Y-1101954D01*
X4049698D01*
G37*
G36*
G01X4052454Y-1101451D02*
X4052848Y-1101954D01*
X4050486D01*
X4052454Y-1101451D01*
G37*
G36*
G01X4061313Y-1100697D02*
X4062493Y-1100949D01*
X4060131D01*
X4061313Y-1100697D01*
G37*
G36*
G01X4059738Y-1101200D02*
X4060131Y-1100949D01*
X4062493D01*
X4059738Y-1101200D01*
G37*
G36*
G01X4062493Y-1100949D02*
X4062887Y-1101200D01*
X4059738D01*
X4062493Y-1100949D01*
G37*
G36*
G01X4059147Y-1101703D02*
X4059738Y-1101200D01*
X4062887D01*
X4059147Y-1101703D01*
G37*
G36*
G01X4062887Y-1101200D02*
X4063478Y-1101703D01*
X4059147D01*
X4062887Y-1101200D01*
G37*
G36*
G01X4068399D02*
X4068793Y-1100949D01*
X4071155D01*
X4068399Y-1101200D01*
G37*
G36*
G01X4071155Y-1100949D02*
X4071549Y-1101200D01*
X4068399D01*
X4071155Y-1100949D01*
G37*
G36*
G01X4067809Y-1101703D02*
X4068399Y-1101200D01*
X4071549D01*
X4067809Y-1101703D01*
G37*
G36*
G01X4071549Y-1101200D02*
X4072139Y-1101703D01*
X4067809D01*
X4071549Y-1101200D01*
G37*
G36*
G01X4051187Y-1078540D02*
Y-1080014D01*
X4052919Y-1077250D01*
X4052053D01*
X4051187Y-1078540D01*
G37*
G36*
G01X4052053Y-1077250D02*
Y-1085912D01*
X4052919D01*
Y-1077250D01*
X4052053D01*
G37*
G36*
G01X4051470Y-1102205D02*
X4050486Y-1101954D01*
X4052848D01*
X4051470Y-1102205D01*
G37*
G36*
G01X4048714D02*
X4046943Y-1102457D01*
X4049698Y-1101954D01*
X4048714Y-1102205D01*
G37*
G36*
G01X4046943Y-1102457D02*
X4047336Y-1101954D01*
X4049698D01*
X4046943Y-1102457D01*
G37*
G36*
G01X4052848Y-1101954D02*
X4053242Y-1102457D01*
X4051470Y-1102205D01*
X4052848Y-1101954D01*
G37*
G36*
G01X4048714Y-1102205D02*
X4048124Y-1102708D01*
X4046943Y-1102457D01*
X4048714Y-1102205D01*
G37*
G36*
G01X4052061Y-1102708D02*
X4051470Y-1102205D01*
X4053242Y-1102457D01*
X4052061Y-1102708D01*
G37*
G36*
G01X4046746Y-1103462D02*
X4046943Y-1102457D01*
X4048124Y-1102708D01*
X4046746Y-1103462D01*
G37*
G36*
G01X4048124Y-1102708D02*
X4047730Y-1103462D01*
X4046746D01*
X4048124Y-1102708D01*
G37*
G36*
G01X4052061D02*
X4053242Y-1102457D01*
X4052454Y-1103462D01*
X4052061Y-1102708D01*
G37*
G36*
G01X4053242Y-1102457D02*
X4053439Y-1103462D01*
X4052454D01*
X4053242Y-1102457D01*
G37*
G36*
G01X4052454Y-1103964D02*
Y-1103462D01*
X4053439D01*
X4052454Y-1103964D01*
G37*
G36*
G01X4053439Y-1103462D02*
Y-1103964D01*
X4052454D01*
X4053439Y-1103462D01*
G37*
G36*
G01X4052061Y-1104970D02*
X4052454Y-1103964D01*
X4053439D01*
X4052061Y-1104970D01*
G37*
G36*
G01X4053439Y-1103964D02*
X4053242Y-1104970D01*
X4052061D01*
X4053439Y-1103964D01*
G37*
G36*
G01X4051667Y-1105472D02*
X4052061Y-1104970D01*
X4053242D01*
X4051667Y-1105472D01*
G37*
G36*
G01D02*
X4053242Y-1104970D01*
X4051273Y-1105723D01*
X4051667Y-1105472D01*
G37*
G36*
G01X4053242Y-1104970D02*
X4052848Y-1105723D01*
X4051273D01*
X4053242Y-1104970D01*
G37*
G36*
G01X4050486Y-1105975D02*
X4051273Y-1105723D01*
X4052848D01*
X4050486Y-1105975D01*
G37*
G36*
G01X4052848Y-1105723D02*
X4052257Y-1106477D01*
X4050486Y-1105975D01*
X4052848Y-1105723D01*
G37*
G36*
G01X4046746Y-1103964D02*
Y-1103462D01*
X4047730D01*
X4046746Y-1103964D01*
G37*
G36*
G01X4047730Y-1103462D02*
Y-1103964D01*
X4046746D01*
X4047730Y-1103462D01*
G37*
G36*
G01X4046943Y-1104970D02*
X4046746Y-1103964D01*
X4047730D01*
X4046943Y-1104970D01*
G37*
G36*
G01X4047730Y-1103964D02*
X4048124Y-1104970D01*
X4046943D01*
X4047730Y-1103964D01*
G37*
G36*
G01X4048517Y-1105472D02*
X4047336Y-1105723D01*
X4048124Y-1104970D01*
X4048517Y-1105472D01*
G37*
G36*
G01X4047336Y-1105723D02*
X4046943Y-1104970D01*
X4048124D01*
X4047336Y-1105723D01*
G37*
G36*
G01X4048517Y-1105472D02*
X4048911Y-1105723D01*
X4047336D01*
X4048517Y-1105472D01*
G37*
G36*
G01X4049698Y-1105975D02*
X4047927Y-1106477D01*
X4048911Y-1105723D01*
X4049698Y-1105975D01*
G37*
G36*
G01X4047927Y-1106477D02*
X4047336Y-1105723D01*
X4048911D01*
X4047927Y-1106477D01*
G37*
G36*
G01X4061313Y-1101954D02*
X4058754Y-1102205D01*
X4063478Y-1101703D01*
X4061313Y-1101954D01*
G37*
G36*
G01X4058754Y-1102205D02*
X4059147Y-1101703D01*
X4063478D01*
X4058754Y-1102205D01*
G37*
G36*
G01X4061313Y-1101954D02*
X4060328Y-1102205D01*
X4058754D01*
X4061313Y-1101954D01*
G37*
G36*
G01D02*
X4063478Y-1101703D01*
X4062296Y-1102205D01*
X4061313Y-1101954D01*
G37*
G36*
G01X4063478Y-1101703D02*
X4063872Y-1102205D01*
X4062296D01*
X4063478Y-1101703D01*
G37*
G36*
G01X4062887Y-1102708D02*
X4062296Y-1102205D01*
X4063872D01*
X4062887Y-1102708D01*
G37*
G36*
G01X4059738D02*
X4058360Y-1102959D01*
X4060328Y-1102205D01*
X4059738Y-1102708D01*
G37*
G36*
G01X4058360Y-1102959D02*
X4058754Y-1102205D01*
X4060328D01*
X4058360Y-1102959D01*
G37*
G36*
G01X4063872Y-1102205D02*
X4064265Y-1102959D01*
X4062887Y-1102708D01*
X4063872Y-1102205D01*
G37*
G36*
G01X4058360Y-1102959D02*
X4059738Y-1102708D01*
X4058163Y-1103462D01*
X4058360Y-1102959D01*
G37*
G36*
G01X4059738Y-1102708D02*
X4059147Y-1103713D01*
X4058163Y-1103462D01*
X4059738Y-1102708D01*
G37*
G36*
G01X4064462Y-1103462D02*
X4063478Y-1103713D01*
X4064265Y-1102959D01*
X4064462Y-1103462D01*
G37*
G36*
G01X4063478Y-1103713D02*
X4062887Y-1102708D01*
X4064265Y-1102959D01*
X4063478Y-1103713D01*
G37*
G36*
G01X4057966Y-1104216D02*
X4058163Y-1103462D01*
X4059147Y-1103713D01*
X4057966Y-1104216D01*
G37*
G36*
G01X4059147Y-1103713D02*
X4058950Y-1104216D01*
X4057966D01*
X4059147Y-1103713D01*
G37*
G36*
G01X4063478D02*
X4064462Y-1103462D01*
X4063675Y-1104216D01*
X4063478Y-1103713D01*
G37*
G36*
G01X4064462Y-1103462D02*
X4064659Y-1104216D01*
X4063675D01*
X4064462Y-1103462D01*
G37*
G36*
G01X4057769Y-1105472D02*
X4057966Y-1104216D01*
X4058950D01*
X4057769Y-1105472D01*
G37*
G36*
G01X4058950Y-1104216D02*
X4058754Y-1105723D01*
X4057769Y-1105472D01*
X4058950Y-1104216D01*
G37*
G36*
G01X4064856Y-1105472D02*
X4063872Y-1105723D01*
X4064659Y-1104216D01*
X4064856Y-1105472D01*
G37*
G36*
G01X4063872Y-1105723D02*
X4063675Y-1104216D01*
X4064659D01*
X4063872Y-1105723D01*
G37*
G36*
G01X4069974Y-1101954D02*
X4067415Y-1102205D01*
X4072139Y-1101703D01*
X4069974Y-1101954D01*
G37*
G36*
G01X4067415Y-1102205D02*
X4067809Y-1101703D01*
X4072139D01*
X4067415Y-1102205D01*
G37*
G36*
G01X4069974Y-1101954D02*
X4068990Y-1102205D01*
X4067415D01*
X4069974Y-1101954D01*
G37*
G36*
G01X4068399Y-1102708D02*
X4067021Y-1102959D01*
X4068990Y-1102205D01*
X4068399Y-1102708D01*
G37*
G36*
G01X4067021Y-1102959D02*
X4067415Y-1102205D01*
X4068990D01*
X4067021Y-1102959D01*
G37*
G36*
G01D02*
X4068399Y-1102708D01*
X4066824Y-1103462D01*
X4067021Y-1102959D01*
G37*
G36*
G01X4068399Y-1102708D02*
X4067809Y-1103713D01*
X4066824Y-1103462D01*
X4068399Y-1102708D01*
G37*
G36*
G01X4066628Y-1104216D02*
X4066824Y-1103462D01*
X4067809Y-1103713D01*
X4066628Y-1104216D01*
G37*
G36*
G01X4067809Y-1103713D02*
X4067612Y-1104216D01*
X4066628D01*
X4067809Y-1103713D01*
G37*
G36*
G01X4066431Y-1105472D02*
X4066628Y-1104216D01*
X4067612D01*
X4066431Y-1105472D01*
G37*
G36*
G01X4067612Y-1104216D02*
X4067415Y-1105723D01*
X4066431Y-1105472D01*
X4067612Y-1104216D01*
G37*
G36*
G01X4105407Y-1107482D02*
X4104423Y-1107734D01*
X4105407Y-1105723D01*
Y-1107482D01*
G37*
G36*
G01X4104423Y-1107734D02*
Y-1105472D01*
X4105407Y-1105723D01*
X4104423Y-1107734D01*
G37*
G36*
G01D02*
X4105407Y-1107482D01*
X4104620Y-1108990D01*
X4104423Y-1107734D01*
G37*
G36*
G01X4105407Y-1107482D02*
X4105604Y-1108990D01*
X4104620D01*
X4105407Y-1107482D01*
G37*
G36*
G01X4110525Y-1105723D02*
X4111509Y-1105472D01*
X4110525Y-1107482D01*
Y-1105723D01*
G37*
G36*
G01X4111509Y-1105472D02*
Y-1107734D01*
X4110525Y-1107482D01*
X4111509Y-1105472D01*
G37*
G36*
G01X4110328Y-1108990D02*
X4110525Y-1107482D01*
X4111509Y-1107734D01*
X4110328Y-1108990D01*
G37*
G36*
G01X4111509Y-1107734D02*
X4111313Y-1108990D01*
X4110328D01*
X4111509Y-1107734D01*
G37*
G36*
G01X4110131Y-1109493D02*
X4110328Y-1108990D01*
X4111313D01*
X4110131Y-1109493D01*
G37*
G36*
G01X4105801D02*
X4104817Y-1109744D01*
X4105604Y-1108990D01*
X4105801Y-1109493D01*
G37*
G36*
G01X4104817Y-1109744D02*
X4104620Y-1108990D01*
X4105604D01*
X4104817Y-1109744D01*
G37*
G36*
G01X4111313Y-1108990D02*
X4111116Y-1109744D01*
X4110131Y-1109493D01*
X4111313Y-1108990D01*
G37*
G36*
G01X4104817Y-1109744D02*
X4105801Y-1109493D01*
X4105013Y-1110247D01*
X4104817Y-1109744D01*
G37*
G36*
G01X4105801Y-1109493D02*
X4106391Y-1110498D01*
X4105013Y-1110247D01*
X4105801Y-1109493D01*
G37*
G36*
G01X4110919Y-1110247D02*
X4109541Y-1110498D01*
X4111116Y-1109744D01*
X4110919Y-1110247D01*
G37*
G36*
G01X4109541Y-1110498D02*
X4110131Y-1109493D01*
X4111116Y-1109744D01*
X4109541Y-1110498D01*
G37*
G36*
G01X4105407Y-1111001D02*
X4105013Y-1110247D01*
X4106391Y-1110498D01*
X4105407Y-1111001D01*
G37*
G36*
G01X4106391Y-1110498D02*
X4106981Y-1111001D01*
X4105407D01*
X4106391Y-1110498D01*
G37*
G36*
G01X4109541D02*
X4110919Y-1110247D01*
X4108950Y-1111001D01*
X4109541Y-1110498D01*
G37*
G36*
G01X4110919Y-1110247D02*
X4110525Y-1111001D01*
X4108950D01*
X4110919Y-1110247D01*
G37*
G36*
G01X4107966Y-1111252D02*
X4108950Y-1111001D01*
X4110525D01*
X4107966Y-1111252D01*
G37*
G36*
G01D02*
X4105801Y-1111503D01*
X4106981Y-1111001D01*
X4107966Y-1111252D01*
G37*
G36*
G01X4105801Y-1111503D02*
X4105407Y-1111001D01*
X4106981D01*
X4105801Y-1111503D01*
G37*
G36*
G01X4107966Y-1111252D02*
X4110525Y-1111001D01*
X4105801Y-1111503D01*
X4107966Y-1111252D01*
G37*
G36*
G01X4110525Y-1111001D02*
X4110131Y-1111503D01*
X4105801D01*
X4110525Y-1111001D01*
G37*
G36*
G01X4106391Y-1112006D02*
X4105801Y-1111503D01*
X4110131D01*
X4106391Y-1112006D01*
G37*
G36*
G01X4110131Y-1111503D02*
X4109541Y-1112006D01*
X4106391D01*
X4110131Y-1111503D01*
G37*
G36*
G01X4106785Y-1112257D02*
X4106391Y-1112006D01*
X4109541D01*
X4106785Y-1112257D01*
G37*
G36*
G01X4109541Y-1112006D02*
X4109147Y-1112257D01*
X4106785D01*
X4109541Y-1112006D01*
G37*
G36*
G01X4107966Y-1112508D02*
X4106785Y-1112257D01*
X4109147D01*
X4107966Y-1112508D01*
G37*
G36*
G01X4081588Y-1109493D02*
X4081785Y-1108488D01*
X4082966D01*
X4081588Y-1109493D01*
G37*
G36*
G01X4082966Y-1108488D02*
X4082769Y-1109995D01*
X4081588Y-1109493D01*
X4082966Y-1108488D01*
G37*
G36*
G01X4081194Y-1110247D02*
X4081588Y-1109493D01*
X4082769Y-1109995D01*
X4081194Y-1110247D01*
G37*
G36*
G01D02*
X4082769Y-1109995D01*
X4080604Y-1110749D01*
X4081194Y-1110247D01*
G37*
G36*
G01X4079817Y-1111001D02*
X4080604Y-1110749D01*
X4082179Y-1111001D01*
X4079817D01*
G37*
G36*
G01X4082769Y-1109995D02*
X4082179Y-1111001D01*
X4080604Y-1110749D01*
X4082769Y-1109995D01*
G37*
G36*
G01X4082966Y-1104718D02*
X4081785D01*
Y-1108488D01*
X4082966D01*
Y-1104718D01*
G37*
G36*
G01X4079423Y-1109493D02*
X4081785Y-1112508D01*
X4082966D01*
X4080604Y-1109493D01*
X4079423D01*
G37*
G36*
G01X4085525Y-1107482D02*
X4084541Y-1107734D01*
X4085525Y-1105723D01*
Y-1107482D01*
G37*
G36*
G01X4084541Y-1107734D02*
Y-1105472D01*
X4085525Y-1105723D01*
X4084541Y-1107734D01*
G37*
G36*
G01D02*
X4085525Y-1107482D01*
X4084737Y-1108990D01*
X4084541Y-1107734D01*
G37*
G36*
G01X4085525Y-1107482D02*
X4085722Y-1108990D01*
X4084737D01*
X4085525Y-1107482D01*
G37*
G36*
G01X4090643Y-1105723D02*
X4091628Y-1105472D01*
X4090643Y-1107482D01*
Y-1105723D01*
G37*
G36*
G01X4091628Y-1105472D02*
Y-1107734D01*
X4090643Y-1107482D01*
X4091628Y-1105472D01*
G37*
G36*
G01X4090446Y-1108990D02*
X4090643Y-1107482D01*
X4091628Y-1107734D01*
X4090446Y-1108990D01*
G37*
G36*
G01X4091628Y-1107734D02*
X4091431Y-1108990D01*
X4090446D01*
X4091628Y-1107734D01*
G37*
G36*
G01X4090250Y-1109493D02*
X4090446Y-1108990D01*
X4091431D01*
X4090250Y-1109493D01*
G37*
G36*
G01X4085919D02*
X4084934Y-1109744D01*
X4085722Y-1108990D01*
X4085919Y-1109493D01*
G37*
G36*
G01X4084934Y-1109744D02*
X4084737Y-1108990D01*
X4085722D01*
X4084934Y-1109744D01*
G37*
G36*
G01X4091431Y-1108990D02*
X4091234Y-1109744D01*
X4090250Y-1109493D01*
X4091431Y-1108990D01*
G37*
G36*
G01X4084934Y-1109744D02*
X4085919Y-1109493D01*
X4085131Y-1110247D01*
X4084934Y-1109744D01*
G37*
G36*
G01X4085919Y-1109493D02*
X4086509Y-1110498D01*
X4085131Y-1110247D01*
X4085919Y-1109493D01*
G37*
G36*
G01X4091037Y-1110247D02*
X4089659Y-1110498D01*
X4091234Y-1109744D01*
X4091037Y-1110247D01*
G37*
G36*
G01X4089659Y-1110498D02*
X4090250Y-1109493D01*
X4091234Y-1109744D01*
X4089659Y-1110498D01*
G37*
G36*
G01X4085525Y-1111001D02*
X4085131Y-1110247D01*
X4086509Y-1110498D01*
X4085525Y-1111001D01*
G37*
G36*
G01X4086509Y-1110498D02*
X4087100Y-1111001D01*
X4085525D01*
X4086509Y-1110498D01*
G37*
G36*
G01X4089659D02*
X4091037Y-1110247D01*
X4089069Y-1111001D01*
X4089659Y-1110498D01*
G37*
G36*
G01X4091037Y-1110247D02*
X4090643Y-1111001D01*
X4089069D01*
X4091037Y-1110247D01*
G37*
G36*
G01X4088084Y-1111252D02*
X4089069Y-1111001D01*
X4090643D01*
X4088084Y-1111252D01*
G37*
G36*
G01D02*
X4085919Y-1111503D01*
X4087100Y-1111001D01*
X4088084Y-1111252D01*
G37*
G36*
G01X4085919Y-1111503D02*
X4085525Y-1111001D01*
X4087100D01*
X4085919Y-1111503D01*
G37*
G36*
G01X4088084Y-1111252D02*
X4090643Y-1111001D01*
X4085919Y-1111503D01*
X4088084Y-1111252D01*
G37*
G36*
G01X4090643Y-1111001D02*
X4090250Y-1111503D01*
X4085919D01*
X4090643Y-1111001D01*
G37*
G36*
G01X4086509Y-1112006D02*
X4085919Y-1111503D01*
X4090250D01*
X4086509Y-1112006D01*
G37*
G36*
G01X4090250Y-1111503D02*
X4089659Y-1112006D01*
X4086509D01*
X4090250Y-1111503D01*
G37*
G36*
G01X4086903Y-1112257D02*
X4086509Y-1112006D01*
X4089659D01*
X4086903Y-1112257D01*
G37*
G36*
G01X4089659Y-1112006D02*
X4089265Y-1112257D01*
X4086903D01*
X4089659Y-1112006D01*
G37*
G36*
G01X4088084Y-1112508D02*
X4086903Y-1112257D01*
X4089265D01*
X4088084Y-1112508D01*
G37*
G36*
G01X4098320Y-1106729D02*
X4097139Y-1106980D01*
X4098911Y-1106477D01*
X4098320Y-1106729D01*
G37*
G36*
G01X4097139Y-1106980D02*
Y-1105975D01*
X4098911Y-1106477D01*
X4097139Y-1106980D01*
G37*
G36*
G01X4098911Y-1106477D02*
X4096352Y-1106980D01*
X4098320Y-1106226D01*
X4098911Y-1106477D01*
G37*
G36*
G01X4098320Y-1106226D02*
X4096352Y-1106980D01*
X4097139Y-1105975D01*
X4098320Y-1106226D01*
G37*
G36*
G01X4096352Y-1106980D02*
Y-1105975D01*
X4097139D01*
X4096352Y-1106980D01*
G37*
G36*
G01D02*
X4098911Y-1106477D01*
X4097139Y-1106980D01*
X4096352D01*
G37*
G36*
G01X4097139D02*
X4098911Y-1106477D01*
X4098124Y-1107231D01*
X4097139Y-1106980D01*
G37*
G36*
G01X4098911Y-1106477D02*
X4099698Y-1107231D01*
X4098124D01*
X4098911Y-1106477D01*
G37*
G36*
G01X4098517Y-1107482D02*
X4098124Y-1107231D01*
X4099698D01*
X4098517Y-1107482D01*
G37*
G36*
G01D02*
X4099698Y-1107231D01*
X4098911Y-1107985D01*
X4098517Y-1107482D01*
G37*
G36*
G01X4099698Y-1107231D02*
X4100092Y-1107985D01*
X4098911D01*
X4099698Y-1107231D01*
G37*
G36*
G01X4099305Y-1108739D02*
X4098911Y-1107985D01*
X4100092D01*
X4099305Y-1108739D01*
G37*
G36*
G01X4100092Y-1107985D02*
X4100289Y-1108990D01*
X4099305Y-1108739D01*
X4100092Y-1107985D01*
G37*
G36*
G01X4099305Y-1109744D02*
Y-1108739D01*
X4100289Y-1108990D01*
X4099305Y-1109744D01*
G37*
G36*
G01X4100289Y-1108990D02*
Y-1109744D01*
X4099305D01*
X4100289Y-1108990D01*
G37*
G36*
G01X4099108Y-1110247D02*
X4099305Y-1109744D01*
X4100289D01*
X4099108Y-1110247D01*
G37*
G36*
G01X4094383D02*
X4093399Y-1110498D01*
X4094187Y-1109744D01*
X4094383Y-1110247D01*
G37*
G36*
G01X4093399Y-1110498D02*
X4093202Y-1109744D01*
X4094187D01*
X4093399Y-1110498D01*
G37*
G36*
G01X4100289Y-1109744D02*
X4100092Y-1110498D01*
X4099108Y-1110247D01*
X4100289Y-1109744D01*
G37*
G36*
G01X4094383Y-1110247D02*
X4094777Y-1110749D01*
X4093399Y-1110498D01*
X4094383Y-1110247D01*
G37*
G36*
G01X4098714Y-1110749D02*
X4099108Y-1110247D01*
X4100092Y-1110498D01*
X4098714Y-1110749D01*
G37*
G36*
G01X4095171Y-1111001D02*
X4093793Y-1111252D01*
X4094777Y-1110749D01*
X4095171Y-1111001D01*
G37*
G36*
G01X4093793Y-1111252D02*
X4093399Y-1110498D01*
X4094777Y-1110749D01*
X4093793Y-1111252D01*
G37*
G36*
G01X4095171Y-1111001D02*
X4096155Y-1111252D01*
X4093793D01*
X4095171Y-1111001D01*
G37*
G36*
G01X4098714Y-1110749D02*
X4100092Y-1110498D01*
X4098320Y-1111001D01*
X4098714Y-1110749D01*
G37*
G36*
G01X4097336Y-1111252D02*
X4098320Y-1111001D01*
X4099698Y-1111252D01*
X4097336D01*
G37*
G36*
G01X4100092Y-1110498D02*
X4099698Y-1111252D01*
X4098320Y-1111001D01*
X4100092Y-1110498D01*
G37*
G36*
G01X4099698Y-1111252D02*
X4094383Y-1111755D01*
X4097336Y-1111252D01*
X4099698D01*
G37*
G36*
G01X4097336D02*
X4094383Y-1111755D01*
X4096155Y-1111252D01*
X4097336D01*
G37*
G36*
G01X4094383Y-1111755D02*
X4093793Y-1111252D01*
X4096155D01*
X4094383Y-1111755D01*
G37*
G36*
G01X4099698Y-1111252D02*
X4099108Y-1111755D01*
X4094383D01*
X4099698Y-1111252D01*
G37*
G36*
G01X4095171Y-1112257D02*
X4094383Y-1111755D01*
X4099108D01*
X4095171Y-1112257D01*
G37*
G36*
G01X4099108Y-1111755D02*
X4098320Y-1112257D01*
X4095171D01*
X4099108Y-1111755D01*
G37*
G36*
G01X4095958Y-1112508D02*
X4095171Y-1112257D01*
X4098320D01*
X4095958Y-1112508D01*
G37*
G36*
G01X4098320Y-1112257D02*
X4097533Y-1112508D01*
X4095958D01*
X4098320Y-1112257D01*
G37*
G36*
G01X4101864Y-1111252D02*
Y-1112508D01*
X4102848D01*
Y-1111252D01*
X4101864D01*
G37*
G36*
G01X4107966Y-1100697D02*
X4109147Y-1100949D01*
X4106785D01*
X4107966Y-1100697D01*
G37*
G36*
G01X4106391Y-1101200D02*
X4106785Y-1100949D01*
X4109147D01*
X4106391Y-1101200D01*
G37*
G36*
G01X4109147Y-1100949D02*
X4109541Y-1101200D01*
X4106391D01*
X4109147Y-1100949D01*
G37*
G36*
G01X4105801Y-1101703D02*
X4106391Y-1101200D01*
X4109541D01*
X4105801Y-1101703D01*
G37*
G36*
G01X4109541Y-1101200D02*
X4110131Y-1101703D01*
X4105801D01*
X4109541Y-1101200D01*
G37*
G36*
G01X4107966Y-1101954D02*
X4105407Y-1102205D01*
X4110131Y-1101703D01*
X4107966Y-1101954D01*
G37*
G36*
G01X4105407Y-1102205D02*
X4105801Y-1101703D01*
X4110131D01*
X4105407Y-1102205D01*
G37*
G36*
G01X4107966Y-1101954D02*
X4106981Y-1102205D01*
X4105407D01*
X4107966Y-1101954D01*
G37*
G36*
G01D02*
X4110131Y-1101703D01*
X4108950Y-1102205D01*
X4107966Y-1101954D01*
G37*
G36*
G01X4110131Y-1101703D02*
X4110525Y-1102205D01*
X4108950D01*
X4110131Y-1101703D01*
G37*
G36*
G01X4109541Y-1102708D02*
X4108950Y-1102205D01*
X4110525D01*
X4109541Y-1102708D01*
G37*
G36*
G01X4106391D02*
X4105013Y-1102959D01*
X4106981Y-1102205D01*
X4106391Y-1102708D01*
G37*
G36*
G01X4105013Y-1102959D02*
X4105407Y-1102205D01*
X4106981D01*
X4105013Y-1102959D01*
G37*
G36*
G01X4110525Y-1102205D02*
X4110919Y-1102959D01*
X4109541Y-1102708D01*
X4110525Y-1102205D01*
G37*
G36*
G01X4105013Y-1102959D02*
X4106391Y-1102708D01*
X4104817Y-1103462D01*
X4105013Y-1102959D01*
G37*
G36*
G01X4106391Y-1102708D02*
X4105801Y-1103713D01*
X4104817Y-1103462D01*
X4106391Y-1102708D01*
G37*
G36*
G01X4111116Y-1103462D02*
X4110131Y-1103713D01*
X4110919Y-1102959D01*
X4111116Y-1103462D01*
G37*
G36*
G01X4110131Y-1103713D02*
X4109541Y-1102708D01*
X4110919Y-1102959D01*
X4110131Y-1103713D01*
G37*
G36*
G01X4104620Y-1104216D02*
X4104817Y-1103462D01*
X4105801Y-1103713D01*
X4104620Y-1104216D01*
G37*
G36*
G01X4105801Y-1103713D02*
X4105604Y-1104216D01*
X4104620D01*
X4105801Y-1103713D01*
G37*
G36*
G01X4110131D02*
X4111116Y-1103462D01*
X4110328Y-1104216D01*
X4110131Y-1103713D01*
G37*
G36*
G01X4111116Y-1103462D02*
X4111313Y-1104216D01*
X4110328D01*
X4111116Y-1103462D01*
G37*
G36*
G01X4104423Y-1105472D02*
X4104620Y-1104216D01*
X4105604D01*
X4104423Y-1105472D01*
G37*
G36*
G01X4105604Y-1104216D02*
X4105407Y-1105723D01*
X4104423Y-1105472D01*
X4105604Y-1104216D01*
G37*
G36*
G01X4111509Y-1105472D02*
X4110525Y-1105723D01*
X4111313Y-1104216D01*
X4111509Y-1105472D01*
G37*
G36*
G01X4110525Y-1105723D02*
X4110328Y-1104216D01*
X4111313D01*
X4110525Y-1105723D01*
G37*
G36*
G01X4088084Y-1100697D02*
X4089265Y-1100949D01*
X4086903D01*
X4088084Y-1100697D01*
G37*
G36*
G01X4086509Y-1101200D02*
X4086903Y-1100949D01*
X4089265D01*
X4086509Y-1101200D01*
G37*
G36*
G01X4089265Y-1100949D02*
X4089659Y-1101200D01*
X4086509D01*
X4089265Y-1100949D01*
G37*
G36*
G01X4085919Y-1101703D02*
X4086509Y-1101200D01*
X4089659D01*
X4085919Y-1101703D01*
G37*
G36*
G01X4089659Y-1101200D02*
X4090250Y-1101703D01*
X4085919D01*
X4089659Y-1101200D01*
G37*
G36*
G01X4095171Y-1100949D02*
X4096548Y-1100697D01*
X4096943D01*
X4095171Y-1100949D01*
G37*
G36*
G01X4096943Y-1100697D02*
X4098320Y-1100949D01*
X4095171D01*
X4096943Y-1100697D01*
G37*
G36*
G01X4094383Y-1101451D02*
X4095171Y-1100949D01*
X4098320D01*
X4094383Y-1101451D01*
G37*
G36*
G01X4098320Y-1100949D02*
X4099108Y-1101451D01*
X4094383D01*
X4098320Y-1100949D01*
G37*
G36*
G01X4093990Y-1101954D02*
X4094383Y-1101451D01*
X4099108D01*
X4093990Y-1101954D01*
G37*
G36*
G01D02*
X4099108Y-1101451D01*
X4096352Y-1101954D01*
X4093990D01*
G37*
G36*
G01X4096352D02*
X4099108Y-1101451D01*
X4097139Y-1101954D01*
X4096352D01*
G37*
G36*
G01X4099108Y-1101451D02*
X4099502Y-1101954D01*
X4097139D01*
X4099108Y-1101451D01*
G37*
G36*
G01X4081785Y-1101703D02*
X4082179Y-1102205D01*
X4079817D01*
X4081785Y-1101703D01*
G37*
G36*
G01X4080604Y-1102457D02*
X4079817Y-1102205D01*
X4082179D01*
X4080604Y-1102457D01*
G37*
G36*
G01D02*
X4082179Y-1102205D01*
X4081194Y-1102959D01*
X4080604Y-1102457D01*
G37*
G36*
G01X4082179Y-1102205D02*
X4082769Y-1103210D01*
X4081194Y-1102959D01*
X4082179Y-1102205D01*
G37*
G36*
G01X4081588Y-1103713D02*
X4081194Y-1102959D01*
X4082769Y-1103210D01*
X4081588Y-1103713D01*
G37*
G36*
G01D02*
X4082769Y-1103210D01*
X4081785Y-1104718D01*
X4081588Y-1103713D01*
G37*
G36*
G01X4082769Y-1103210D02*
X4082966Y-1104718D01*
X4081785D01*
X4082769Y-1103210D01*
G37*
G36*
G01X4088084Y-1101954D02*
X4085525Y-1102205D01*
X4090250Y-1101703D01*
X4088084Y-1101954D01*
G37*
G36*
G01X4085525Y-1102205D02*
X4085919Y-1101703D01*
X4090250D01*
X4085525Y-1102205D01*
G37*
G36*
G01X4088084Y-1101954D02*
X4087100Y-1102205D01*
X4085525D01*
X4088084Y-1101954D01*
G37*
G36*
G01D02*
X4090250Y-1101703D01*
X4089069Y-1102205D01*
X4088084Y-1101954D01*
G37*
G36*
G01X4090250Y-1101703D02*
X4090643Y-1102205D01*
X4089069D01*
X4090250Y-1101703D01*
G37*
G36*
G01X4089659Y-1102708D02*
X4089069Y-1102205D01*
X4090643D01*
X4089659Y-1102708D01*
G37*
G36*
G01X4086509D02*
X4085131Y-1102959D01*
X4087100Y-1102205D01*
X4086509Y-1102708D01*
G37*
G36*
G01X4085131Y-1102959D02*
X4085525Y-1102205D01*
X4087100D01*
X4085131Y-1102959D01*
G37*
G36*
G01X4090643Y-1102205D02*
X4091037Y-1102959D01*
X4089659Y-1102708D01*
X4090643Y-1102205D01*
G37*
G36*
G01X4085131Y-1102959D02*
X4086509Y-1102708D01*
X4084934Y-1103462D01*
X4085131Y-1102959D01*
G37*
G36*
G01X4086509Y-1102708D02*
X4085919Y-1103713D01*
X4084934Y-1103462D01*
X4086509Y-1102708D01*
G37*
G36*
G01X4091234Y-1103462D02*
X4090250Y-1103713D01*
X4091037Y-1102959D01*
X4091234Y-1103462D01*
G37*
G36*
G01X4090250Y-1103713D02*
X4089659Y-1102708D01*
X4091037Y-1102959D01*
X4090250Y-1103713D01*
G37*
G36*
G01X4084737Y-1104216D02*
X4084934Y-1103462D01*
X4085919Y-1103713D01*
X4084737Y-1104216D01*
G37*
G36*
G01X4085919Y-1103713D02*
X4085722Y-1104216D01*
X4084737D01*
X4085919Y-1103713D01*
G37*
G36*
G01X4090250D02*
X4091234Y-1103462D01*
X4090446Y-1104216D01*
X4090250Y-1103713D01*
G37*
G36*
G01X4091234Y-1103462D02*
X4091431Y-1104216D01*
X4090446D01*
X4091234Y-1103462D01*
G37*
G36*
G01X4084541Y-1105472D02*
X4084737Y-1104216D01*
X4085722D01*
X4084541Y-1105472D01*
G37*
G36*
G01X4085722Y-1104216D02*
X4085525Y-1105723D01*
X4084541Y-1105472D01*
X4085722Y-1104216D01*
G37*
G36*
G01X4091628Y-1105472D02*
X4090643Y-1105723D01*
X4091431Y-1104216D01*
X4091628Y-1105472D01*
G37*
G36*
G01X4090643Y-1105723D02*
X4090446Y-1104216D01*
X4091431D01*
X4090643Y-1105723D01*
G37*
G36*
G01X4098124Y-1102205D02*
X4097139Y-1101954D01*
X4099502D01*
X4098124Y-1102205D01*
G37*
G36*
G01X4095368D02*
X4093596Y-1102457D01*
X4096352Y-1101954D01*
X4095368Y-1102205D01*
G37*
G36*
G01X4093596Y-1102457D02*
X4093990Y-1101954D01*
X4096352D01*
X4093596Y-1102457D01*
G37*
G36*
G01X4099502Y-1101954D02*
X4099895Y-1102457D01*
X4098124Y-1102205D01*
X4099502Y-1101954D01*
G37*
G36*
G01X4095368Y-1102205D02*
X4094777Y-1102708D01*
X4093596Y-1102457D01*
X4095368Y-1102205D01*
G37*
G36*
G01X4098714Y-1102708D02*
X4098124Y-1102205D01*
X4099895Y-1102457D01*
X4098714Y-1102708D01*
G37*
G36*
G01X4093399Y-1103462D02*
X4093596Y-1102457D01*
X4094777Y-1102708D01*
X4093399Y-1103462D01*
G37*
G36*
G01X4094777Y-1102708D02*
X4094383Y-1103462D01*
X4093399D01*
X4094777Y-1102708D01*
G37*
G36*
G01X4098714D02*
X4099895Y-1102457D01*
X4099108Y-1103462D01*
X4098714Y-1102708D01*
G37*
G36*
G01X4099895Y-1102457D02*
X4100092Y-1103462D01*
X4099108D01*
X4099895Y-1102457D01*
G37*
G36*
G01X4099108Y-1103964D02*
Y-1103462D01*
X4100092D01*
X4099108Y-1103964D01*
G37*
G36*
G01X4100092Y-1103462D02*
Y-1103964D01*
X4099108D01*
X4100092Y-1103462D01*
G37*
G36*
G01X4098714Y-1104970D02*
X4099108Y-1103964D01*
X4100092D01*
X4098714Y-1104970D01*
G37*
G36*
G01X4100092Y-1103964D02*
X4099895Y-1104970D01*
X4098714D01*
X4100092Y-1103964D01*
G37*
G36*
G01X4098320Y-1105472D02*
X4098714Y-1104970D01*
X4099895D01*
X4098320Y-1105472D01*
G37*
G36*
G01D02*
X4099895Y-1104970D01*
X4097927Y-1105723D01*
X4098320Y-1105472D01*
G37*
G36*
G01X4099895Y-1104970D02*
X4099502Y-1105723D01*
X4097927D01*
X4099895Y-1104970D01*
G37*
G36*
G01X4097139Y-1105975D02*
X4097927Y-1105723D01*
X4099502D01*
X4097139Y-1105975D01*
G37*
G36*
G01X4099502Y-1105723D02*
X4098911Y-1106477D01*
X4097139Y-1105975D01*
X4099502Y-1105723D01*
G37*
G36*
G01X4114069Y-1107482D02*
X4113084Y-1107734D01*
X4114069Y-1105723D01*
Y-1107482D01*
G37*
G36*
G01X4113084Y-1107734D02*
Y-1105472D01*
X4114069Y-1105723D01*
X4113084Y-1107734D01*
G37*
G36*
G01D02*
X4114069Y-1107482D01*
X4113281Y-1108990D01*
X4113084Y-1107734D01*
G37*
G36*
G01X4114069Y-1107482D02*
X4114265Y-1108990D01*
X4113281D01*
X4114069Y-1107482D01*
G37*
G36*
G01X4119187Y-1105723D02*
X4120171Y-1105472D01*
X4119187Y-1107482D01*
Y-1105723D01*
G37*
G36*
G01X4120171Y-1105472D02*
Y-1107734D01*
X4119187Y-1107482D01*
X4120171Y-1105472D01*
G37*
G36*
G01X4118990Y-1108990D02*
X4119187Y-1107482D01*
X4120171Y-1107734D01*
X4118990Y-1108990D01*
G37*
G36*
G01X4120171Y-1107734D02*
X4119974Y-1108990D01*
X4118990D01*
X4120171Y-1107734D01*
G37*
G36*
G01X4118793Y-1109493D02*
X4118990Y-1108990D01*
X4119974D01*
X4118793Y-1109493D01*
G37*
G36*
G01X4114462D02*
X4113478Y-1109744D01*
X4114265Y-1108990D01*
X4114462Y-1109493D01*
G37*
G36*
G01X4113478Y-1109744D02*
X4113281Y-1108990D01*
X4114265D01*
X4113478Y-1109744D01*
G37*
G36*
G01X4119974Y-1108990D02*
X4119777Y-1109744D01*
X4118793Y-1109493D01*
X4119974Y-1108990D01*
G37*
G36*
G01X4113478Y-1109744D02*
X4114462Y-1109493D01*
X4113675Y-1110247D01*
X4113478Y-1109744D01*
G37*
G36*
G01X4114462Y-1109493D02*
X4115053Y-1110498D01*
X4113675Y-1110247D01*
X4114462Y-1109493D01*
G37*
G36*
G01X4119580Y-1110247D02*
X4118202Y-1110498D01*
X4119777Y-1109744D01*
X4119580Y-1110247D01*
G37*
G36*
G01X4118202Y-1110498D02*
X4118793Y-1109493D01*
X4119777Y-1109744D01*
X4118202Y-1110498D01*
G37*
G36*
G01X4114069Y-1111001D02*
X4113675Y-1110247D01*
X4115053Y-1110498D01*
X4114069Y-1111001D01*
G37*
G36*
G01X4115053Y-1110498D02*
X4115643Y-1111001D01*
X4114069D01*
X4115053Y-1110498D01*
G37*
G36*
G01X4118202D02*
X4119580Y-1110247D01*
X4117612Y-1111001D01*
X4118202Y-1110498D01*
G37*
G36*
G01X4119580Y-1110247D02*
X4119187Y-1111001D01*
X4117612D01*
X4119580Y-1110247D01*
G37*
G36*
G01X4116628Y-1111252D02*
X4117612Y-1111001D01*
X4119187D01*
X4116628Y-1111252D01*
G37*
G36*
G01D02*
X4114462Y-1111503D01*
X4115643Y-1111001D01*
X4116628Y-1111252D01*
G37*
G36*
G01X4114462Y-1111503D02*
X4114069Y-1111001D01*
X4115643D01*
X4114462Y-1111503D01*
G37*
G36*
G01X4116628Y-1111252D02*
X4119187Y-1111001D01*
X4114462Y-1111503D01*
X4116628Y-1111252D01*
G37*
G36*
G01X4119187Y-1111001D02*
X4118793Y-1111503D01*
X4114462D01*
X4119187Y-1111001D01*
G37*
G36*
G01X4115053Y-1112006D02*
X4114462Y-1111503D01*
X4118793D01*
X4115053Y-1112006D01*
G37*
G36*
G01X4118793Y-1111503D02*
X4118202Y-1112006D01*
X4115053D01*
X4118793Y-1111503D01*
G37*
G36*
G01X4115446Y-1112257D02*
X4115053Y-1112006D01*
X4118202D01*
X4115446Y-1112257D01*
G37*
G36*
G01X4118202Y-1112006D02*
X4117809Y-1112257D01*
X4115446D01*
X4118202Y-1112006D01*
G37*
G36*
G01X4116628Y-1112508D02*
X4115446Y-1112257D01*
X4117809D01*
X4116628Y-1112508D01*
G37*
G36*
G01X4122927Y-1100697D02*
Y-1112508D01*
X4124108D01*
Y-1100697D01*
X4122927D01*
G37*
G36*
G01X4116628D02*
X4117809Y-1100949D01*
X4115446D01*
X4116628Y-1100697D01*
G37*
G36*
G01X4115053Y-1101200D02*
X4115446Y-1100949D01*
X4117809D01*
X4115053Y-1101200D01*
G37*
G36*
G01X4117809Y-1100949D02*
X4118202Y-1101200D01*
X4115053D01*
X4117809Y-1100949D01*
G37*
G36*
G01X4114462Y-1101703D02*
X4115053Y-1101200D01*
X4118202D01*
X4114462Y-1101703D01*
G37*
G36*
G01X4118202Y-1101200D02*
X4118793Y-1101703D01*
X4114462D01*
X4118202Y-1101200D01*
G37*
G36*
G01X4130082Y-1078540D02*
Y-1080014D01*
X4131815Y-1077250D01*
X4130948D01*
X4130082Y-1078540D01*
G37*
G36*
G01X4130948Y-1077250D02*
Y-1085912D01*
X4131815D01*
Y-1077250D01*
X4130948D01*
G37*
G36*
G01X4116628Y-1101954D02*
X4114069Y-1102205D01*
X4118793Y-1101703D01*
X4116628Y-1101954D01*
G37*
G36*
G01X4114069Y-1102205D02*
X4114462Y-1101703D01*
X4118793D01*
X4114069Y-1102205D01*
G37*
G36*
G01X4116628Y-1101954D02*
X4115643Y-1102205D01*
X4114069D01*
X4116628Y-1101954D01*
G37*
G36*
G01D02*
X4118793Y-1101703D01*
X4117612Y-1102205D01*
X4116628Y-1101954D01*
G37*
G36*
G01X4118793Y-1101703D02*
X4119187Y-1102205D01*
X4117612D01*
X4118793Y-1101703D01*
G37*
G36*
G01X4118202Y-1102708D02*
X4117612Y-1102205D01*
X4119187D01*
X4118202Y-1102708D01*
G37*
G36*
G01X4115053D02*
X4113675Y-1102959D01*
X4115643Y-1102205D01*
X4115053Y-1102708D01*
G37*
G36*
G01X4113675Y-1102959D02*
X4114069Y-1102205D01*
X4115643D01*
X4113675Y-1102959D01*
G37*
G36*
G01X4119187Y-1102205D02*
X4119580Y-1102959D01*
X4118202Y-1102708D01*
X4119187Y-1102205D01*
G37*
G36*
G01X4113675Y-1102959D02*
X4115053Y-1102708D01*
X4113478Y-1103462D01*
X4113675Y-1102959D01*
G37*
G36*
G01X4115053Y-1102708D02*
X4114462Y-1103713D01*
X4113478Y-1103462D01*
X4115053Y-1102708D01*
G37*
G36*
G01X4119777Y-1103462D02*
X4118793Y-1103713D01*
X4119580Y-1102959D01*
X4119777Y-1103462D01*
G37*
G36*
G01X4118793Y-1103713D02*
X4118202Y-1102708D01*
X4119580Y-1102959D01*
X4118793Y-1103713D01*
G37*
G36*
G01X4113281Y-1104216D02*
X4113478Y-1103462D01*
X4114462Y-1103713D01*
X4113281Y-1104216D01*
G37*
G36*
G01X4114462Y-1103713D02*
X4114265Y-1104216D01*
X4113281D01*
X4114462Y-1103713D01*
G37*
G36*
G01X4118793D02*
X4119777Y-1103462D01*
X4118990Y-1104216D01*
X4118793Y-1103713D01*
G37*
G36*
G01X4119777Y-1103462D02*
X4119974Y-1104216D01*
X4118990D01*
X4119777Y-1103462D01*
G37*
G36*
G01X4113084Y-1105472D02*
X4113281Y-1104216D01*
X4114265D01*
X4113084Y-1105472D01*
G37*
G36*
G01X4114265Y-1104216D02*
X4114069Y-1105723D01*
X4113084Y-1105472D01*
X4114265Y-1104216D01*
G37*
G36*
G01X4120171Y-1105472D02*
X4119187Y-1105723D01*
X4119974Y-1104216D01*
X4120171Y-1105472D01*
G37*
G36*
G01X4119187Y-1105723D02*
X4118990Y-1104216D01*
X4119974D01*
X4119187Y-1105723D01*
G37*
G36*
G01X4121746Y-1102457D02*
Y-1104467D01*
X4124108Y-1100697D01*
X4122927D01*
X4121746Y-1102457D01*
G37*
G54D10*
G01X-487930Y-1120610D02*
Y2152090D01*
G01X4155148Y-1120610D02*
X-487930D01*
G01X-506942Y-1139623D02*
Y2171401D01*
G01Y-1139623D02*
X4174160D01*
G01X-492683Y-1000747D02*
X-493396Y-1001697D01*
X-494822Y-1002648D01*
X-496248D01*
X-497674Y-1001697D01*
X-498387Y-1000747D01*
X-499100Y-999796D01*
X-499813Y-996945D01*
X-499100Y-994093D01*
X-498387Y-993142D01*
X-497674Y-992192D01*
X-496248Y-991241D01*
X-494822D01*
X-493396Y-992192D01*
X-492683Y-993142D01*
X-491970Y-994093D01*
X-491257Y-996945D01*
X-491970Y-999796D01*
X-492683Y-1000747D01*
G01X-506942Y-888575D02*
X-487930D01*
G01X-498387Y-785910D02*
Y-774502D01*
X-492683Y-785910D01*
Y-774502D01*
G01X-506942Y-671836D02*
X-487930D01*
G01X-499100Y-569171D02*
Y-557764D01*
X-495535Y-567270D01*
X-491970Y-557764D01*
Y-569171D01*
G01X-506942Y-455098D02*
X-487930D01*
G01X-498387Y-341215D02*
Y-352622D01*
X-492683D01*
G01X-506942Y-238359D02*
X-487930D01*
G01X-498387Y-124477D02*
Y-135884D01*
G01X-495535Y-128279D02*
X-492683Y-135884D01*
G01X-498387Y-131131D02*
X-492683Y-124477D01*
G01X-506942Y-21621D02*
X-487930D01*
G01X-495535Y92453D02*
Y82946D01*
X-496010Y81995D01*
X-496961Y81045D01*
X-497911D01*
X-498862Y81995D01*
X-499337Y82946D01*
G01X-506942Y195118D02*
X-487930D01*
G01X-499337Y309191D02*
Y297784D01*
G01X-506942Y411856D02*
X-487930D01*
G01X-499337Y520036D02*
X-495535D01*
G01X-499337Y525740D02*
Y514332D01*
G01X-495535Y525740D02*
Y514332D01*
G01X-506942Y628595D02*
X-487930D01*
G01X-499813Y739627D02*
X-498862Y741527D01*
X-497911Y742478D01*
X-496961D01*
X-496010Y741527D01*
X-495535Y740577D01*
G01X-497436Y736775D02*
X-495535D01*
Y732972D01*
X-496010Y732021D01*
X-496961Y731071D01*
X-497911D01*
X-498862Y732021D01*
X-499337Y732972D01*
X-499813Y733923D01*
X-500288Y736775D01*
X-499813Y739627D01*
G01X-506942Y845334D02*
X-487930D01*
G01X-499717Y948000D02*
Y959407D01*
X-495915D01*
G01X-499717Y953703D02*
X-497341D01*
G01X-506942Y1062073D02*
X-487930D01*
G01X-495535Y1164929D02*
X-499337D01*
Y1176336D01*
X-495535D01*
G01X-499337Y1170632D02*
X-496961D01*
G01X-506942Y1278811D02*
X-487930D01*
G01X-495535Y1384329D02*
X-496485Y1382427D01*
X-497436Y1381477D01*
X-499337D01*
Y1392884D01*
G01X-496485Y1391934D02*
X-495535Y1390032D01*
X-495059Y1387180D01*
X-495535Y1384329D01*
G01X-499337Y1392884D02*
X-497436D01*
X-496485Y1391934D01*
G01X-506942Y1495550D02*
X-487930D01*
G01X-499813Y1606961D02*
X-498862Y1608862D01*
X-497911Y1609813D01*
X-496961D01*
X-496010Y1608862D01*
X-495535Y1607912D01*
G01Y1600307D02*
X-496010Y1599356D01*
X-496961Y1598406D01*
X-497911D01*
X-498862Y1599356D01*
G01D02*
X-499813Y1601258D01*
X-500288Y1604109D01*
X-499813Y1606961D01*
G01X-506942Y1712288D02*
X-487930D01*
G01X-496485Y1814954D02*
X-495535Y1816855D01*
Y1819707D01*
G01X-499813Y1826362D02*
Y1814954D01*
X-496485D01*
G01X-495535Y1819707D02*
X-496485Y1821608D01*
X-496010Y1822559D01*
Y1825411D01*
X-496485Y1826362D01*
X-499813D01*
G01Y1821608D02*
X-496485D01*
G01X-506942Y1929027D02*
X-487930D01*
G01X-499813Y2031693D02*
X-497436Y2043100D01*
X-495059Y2031693D01*
G01X-498862Y2035495D02*
X-496010D01*
G01X-487930Y2152090D02*
X4155148D01*
G01X-506942Y2171102D02*
X4174160D01*
G01X-506942Y2171401D02*
X4174160D01*
G01X-366968Y-1124413D02*
Y-1135820D01*
G01Y2167300D02*
Y2155892D01*
G01X-260500Y-1120610D02*
Y-1139623D01*
G01X-242621Y320130D02*
X-242134Y323738D01*
X-241646Y325904D01*
G01D02*
X-240672Y328791D01*
X-244570D01*
G01X-19589Y317964D02*
X-266729D01*
G01X-258067Y324460D02*
X-257345Y326626D01*
X-255902Y328069D01*
X-253737Y328791D01*
X-251571Y328069D01*
X-250128Y326626D01*
X-249406Y324460D01*
X-250128Y322295D01*
X-251571Y320851D01*
X-253737Y320130D01*
X-255902Y320851D01*
X-257345Y322295D01*
X-258067Y324460D01*
G01X-257345Y317964D02*
X-250128Y330956D01*
G01X-83690Y747158D02*
X-268467D01*
G01X-261898Y736331D02*
Y744993D01*
X-258001Y736331D01*
Y744993D01*
G01X-259084Y747158D02*
X-251866Y760150D01*
G01X-267258Y744993D02*
X-268232Y743549D01*
X-268719Y741384D01*
Y739940D01*
X-268232Y737775D01*
X-267258Y736331D01*
G01X-250206Y738497D02*
X-251180Y737053D01*
X-252154Y736331D01*
X-253129Y737053D01*
X-254103Y738497D01*
Y739940D01*
X-253129Y741384D01*
X-252154Y742105D01*
X-251180Y741384D01*
X-250206Y739940D01*
Y738497D01*
G01X-244846Y754376D02*
X-245821Y755097D01*
X-246308Y755819D01*
Y756541D01*
X-245821Y757263D01*
X-244846Y757985D01*
X-243872D01*
X-242898Y757263D01*
X-242410Y756541D01*
Y755819D01*
X-242898Y755097D01*
X-243872Y754376D01*
G01X-246795Y751488D02*
Y752210D01*
X-246308Y752932D01*
X-245821Y753654D01*
X-244846Y754376D01*
X-243872D01*
X-242898Y753654D01*
G01D02*
X-241923Y752210D01*
Y751488D01*
X-242410Y750767D01*
X-242898Y750045D01*
X-243872Y749323D01*
X-244846D01*
G01D02*
X-245821Y750045D01*
X-246795Y751488D01*
G01X-259806Y753654D02*
X-259084Y755819D01*
X-257640Y757263D01*
X-255475Y757985D01*
X-253309Y757263D01*
X-251866Y755819D01*
X-251144Y753654D01*
X-251866Y751488D01*
X-253309Y750045D01*
X-255475Y749323D01*
X-257640Y750045D01*
X-259084Y751488D01*
X-259806Y753654D01*
G01X-260500Y2171102D02*
Y2152090D01*
G01X-17190Y275425D02*
X-209763D01*
G01X-211477Y264599D02*
Y273260D01*
X-209041Y266042D01*
X-206605Y273260D01*
Y264599D01*
G01X-214887Y271817D02*
X-215374Y272538D01*
X-216349Y273260D01*
X-217323D01*
X-218298Y272538D01*
X-218785Y271817D01*
Y271095D01*
X-218298Y270373D01*
X-217323Y269651D01*
X-216349Y268929D01*
X-215374Y268208D01*
X-214887Y267486D01*
Y266042D01*
X-215374Y265321D01*
X-216349Y264599D01*
X-217323D01*
X-218298Y265321D01*
X-218785Y266042D01*
X-219272Y266764D01*
G01X-219235Y320130D02*
X-220209Y320851D01*
X-220697Y321573D01*
X-221184Y323017D01*
Y325904D01*
X-220697Y327347D01*
X-220209Y328069D01*
X-219235Y328791D01*
X-218261Y328069D01*
X-217774Y327347D01*
X-217286Y325904D01*
Y323017D01*
X-217774Y321573D01*
X-218261Y320851D01*
X-219235Y320130D01*
G01X-234826D02*
X-235313D01*
Y320851D01*
X-234826Y320130D01*
G01X-225081Y328791D02*
X-228005D01*
X-228492Y325182D01*
X-227518Y325904D01*
X-226543D01*
X-225569Y325182D01*
X-225081Y324460D01*
X-224594Y323017D01*
X-225081Y321573D01*
X-225569Y320851D01*
X-226543Y320130D01*
X-227518D01*
X-228492Y320851D01*
X-228979Y321573D01*
G01X-203921Y737775D02*
X-204408Y737053D01*
X-205383Y736331D01*
X-206357Y737053D01*
X-207331Y738497D01*
Y739940D01*
X-206357Y741384D01*
X-205383Y742105D01*
X-204408Y741384D01*
X-203921Y739940D01*
X-207331D01*
G01X-212204Y737053D02*
X-213178Y736331D01*
X-214152Y737053D01*
X-215127Y738497D01*
Y739940D01*
X-214152Y741384D01*
X-213178Y742105D01*
X-212204Y741384D01*
G01X-236564Y744993D02*
Y736331D01*
G01X-230230D02*
Y742105D01*
G01X-219024D02*
Y736331D01*
G01X-230230Y740662D02*
X-229256Y742105D01*
X-228281D01*
X-227794Y741384D01*
G01X-219024Y738497D02*
X-219999Y737053D01*
X-220973Y736331D01*
X-221948Y737053D01*
X-222922Y738497D01*
Y739940D01*
X-221948Y741384D01*
X-220973Y742105D01*
X-219999Y741384D01*
X-219024Y739940D01*
G01X-239000Y744993D02*
X-234128D01*
G01X-207819Y754376D02*
X-204408D01*
G01X-207819Y757985D02*
Y749323D01*
X-204408D01*
X-203921Y750045D01*
X-203434Y750767D01*
Y752932D01*
G01X-212691Y757985D02*
X-213665Y756541D01*
X-214152Y754376D01*
Y752932D01*
X-213665Y750767D01*
X-212691Y749323D01*
G01X-203434Y752932D02*
X-204408Y754376D01*
X-203921Y755097D01*
Y757263D01*
X-204408Y757985D01*
X-207819D01*
G01X-228769Y749323D02*
X-229743Y750045D01*
X-230230Y750767D01*
X-230717Y752210D01*
Y755097D01*
X-230230Y756541D01*
X-229743Y757263D01*
X-228769Y757985D01*
X-227794Y757263D01*
X-227307Y756541D01*
X-226820Y755097D01*
Y752210D01*
X-227307Y750767D01*
X-227794Y750045D01*
X-228769Y749323D01*
G01X-220973D02*
X-221948Y750045D01*
X-222435Y750767D01*
X-222922Y752210D01*
Y755097D01*
X-222435Y756541D01*
X-221948Y757263D01*
X-220973Y757985D01*
X-219999Y757263D01*
X-219512Y756541D01*
X-219024Y755097D01*
Y752210D01*
X-219512Y750767D01*
X-219999Y750045D01*
X-220973Y749323D01*
G01X-236564D02*
X-237051D01*
Y750045D01*
X-236564Y749323D01*
G01X-179808Y251606D02*
Y260268D01*
X-177372D01*
X-176398Y259546D01*
X-175911Y258825D01*
Y257381D01*
X-176398Y256659D01*
X-177372Y255937D01*
X-179808D01*
G01X-175911Y273260D02*
Y266042D01*
X-176398Y265321D01*
X-177372Y264599D01*
X-178347D01*
X-179321Y265321D01*
X-179808Y266042D01*
Y273260D01*
G01X-201245D02*
Y264599D01*
G01X-187604D02*
Y273260D01*
X-183706Y264599D01*
Y273260D01*
G01X-200379Y275425D02*
X-193161Y288418D01*
G01X-203681Y273260D02*
X-198809D01*
G01X-177859Y277591D02*
X-178347D01*
Y278313D01*
X-177859Y277591D01*
G01X-201101Y281921D02*
X-200379Y284087D01*
X-198936Y285530D01*
X-196770Y286252D01*
X-194605Y285530D01*
X-193161Y284087D01*
X-192440Y281921D01*
X-193161Y279756D01*
X-194605Y278313D01*
X-196770Y277591D01*
X-198936Y278313D01*
X-200379Y279756D01*
X-201101Y281921D01*
G01X-187604Y280478D02*
X-187117Y281921D01*
X-185655Y282643D01*
X-184193Y281921D01*
X-183706Y280478D01*
X-184193Y279034D01*
X-184680Y278313D01*
X-185655Y277591D01*
X-186629Y278313D01*
X-187117Y279034D01*
X-187604Y280478D01*
Y283365D01*
X-187117Y284809D01*
X-186629Y285530D01*
X-185655Y286252D01*
X-184680Y285530D01*
X-184193Y284809D01*
G01X-174900Y328791D02*
X-170028D01*
G01X-197798Y320130D02*
Y328791D01*
X-193900Y320130D01*
Y328791D01*
G01X-189516Y320851D02*
X-190490Y322295D01*
X-190977Y324460D01*
X-190490Y326626D01*
X-190003Y327347D01*
X-189516Y328069D01*
X-188541Y328791D01*
X-187567D01*
X-186593Y328069D01*
G01D02*
X-185618Y326626D01*
X-185131Y324460D01*
X-185618Y322295D01*
X-186105Y321573D01*
G01X-203157Y328791D02*
X-204132Y327347D01*
X-204619Y325182D01*
Y323738D01*
X-204132Y321573D01*
X-203157Y320130D01*
G01X-186105Y321573D02*
X-186593Y320851D01*
X-187567Y320130D01*
X-188541D01*
X-189516Y320851D01*
G01X-181997Y736331D02*
Y744993D01*
G01X-192228Y736331D02*
X-189792Y744993D01*
X-187356Y736331D01*
G01X-191254Y739218D02*
X-188331D01*
G01X-183459Y741384D02*
X-180535D01*
G01X-69903Y774519D02*
X-176728D01*
G01X-183459Y754376D02*
X-182484Y755097D01*
G01X-191254Y754376D02*
X-188331D01*
G01X-182484Y755097D02*
X-181510D01*
X-180535Y753654D01*
Y749323D01*
G01X-189792D02*
Y757985D01*
G01X-183459Y749323D02*
Y757985D01*
G01X-195639Y751488D02*
X-196613Y750045D01*
X-197587Y749323D01*
X-198562Y750045D01*
X-199537Y751488D01*
Y752932D01*
X-198562Y754376D01*
X-197587Y755097D01*
X-196613Y754376D01*
X-195639Y752932D01*
Y751488D01*
G01X-152130Y-1126314D02*
X-151655Y-1125364D01*
X-150704Y-1124413D01*
X-149754D01*
X-148803Y-1125364D01*
X-148328Y-1126314D01*
Y-1128215D01*
X-148803Y-1129166D01*
X-149754Y-1130117D01*
X-150704Y-1131067D01*
X-151655Y-1132968D01*
X-152130Y-1135820D01*
X-148328D01*
G01X-146678Y257381D02*
Y256659D01*
X-147166Y257381D01*
X-146678D01*
G01X-138883Y251606D02*
X-139857Y252329D01*
X-140345Y253050D01*
X-140832Y254494D01*
Y257381D01*
X-140345Y258825D01*
X-139857Y259546D01*
X-138883Y260268D01*
X-137909Y259546D01*
X-137422Y258825D01*
X-136934Y257381D01*
Y254494D01*
X-137422Y253050D01*
X-137909Y252329D01*
X-138883Y251606D01*
G01X-146678D02*
X-147166D01*
Y252329D01*
X-146678Y251606D01*
G01X-170064Y273260D02*
Y264599D01*
G01X-164218Y251606D02*
Y260268D01*
X-160320Y251606D01*
Y260268D01*
G01X-148627Y264599D02*
Y273260D01*
X-144730Y264599D01*
Y273260D01*
G01X-152038Y271095D02*
X-151550Y268929D01*
X-152038Y266764D01*
X-152525Y266042D01*
G01X-171526Y251606D02*
X-168603Y260268D01*
G01X-152525Y266042D02*
X-153012Y265321D01*
X-153987Y264599D01*
X-154961D01*
X-155935Y265321D01*
X-156422Y266042D01*
X-156910Y266764D01*
X-157397Y268929D01*
X-156910Y271095D01*
X-156422Y271817D01*
X-155935Y272538D01*
X-154961Y273260D01*
X-153987D01*
X-153012Y272538D01*
X-152038Y271095D01*
G01X-172500Y273260D02*
X-167628D01*
G01X-137909Y282643D02*
X-137422Y283365D01*
Y285530D01*
X-137909Y286252D01*
X-141319D01*
G01Y282643D02*
X-137909D01*
G01X-141319Y286252D02*
Y277591D01*
X-137909D01*
X-137422Y278313D01*
X-136934Y279034D01*
Y281200D01*
X-137909Y282643D01*
G01X-146191Y286252D02*
X-147166Y284809D01*
X-147653Y282643D01*
Y281200D01*
X-147166Y279034D01*
X-146191Y277591D01*
G01X-162269D02*
X-163243Y278313D01*
X-163731Y279034D01*
X-164218Y280478D01*
Y283365D01*
X-163731Y284809D01*
X-163243Y285530D01*
X-162269Y286252D01*
X-161294Y285530D01*
X-160807Y284809D01*
X-160320Y283365D01*
Y280478D01*
X-160807Y279034D01*
X-161294Y278313D01*
X-162269Y277591D01*
G01X-168115Y286252D02*
X-171039D01*
X-171526Y282643D01*
X-170552Y283365D01*
X-169577D01*
X-168603Y282643D01*
X-168115Y281921D01*
X-167628Y280478D01*
X-168115Y279034D01*
X-168603Y278313D01*
X-169577Y277591D01*
X-170552D01*
X-171526Y278313D01*
X-172013Y279034D01*
G01X-139333Y320130D02*
X-143231D01*
Y328791D01*
X-139333D01*
G01X-143231Y324460D02*
X-140795D01*
G01X-172463Y328791D02*
Y320130D01*
G01X-166617D02*
Y328791D01*
X-164181D01*
X-163207Y328069D01*
X-162719Y327347D01*
Y325904D01*
X-163207Y325182D01*
X-164181Y324460D01*
X-166617D01*
G01X-164181D02*
X-162719Y320130D01*
G01X-159309D02*
X-156873Y328791D01*
X-154437Y320130D01*
G01X-150539Y320851D02*
X-151514Y322295D01*
X-152001Y324460D01*
X-151514Y326626D01*
X-151026Y327347D01*
X-150539Y328069D01*
X-149565Y328791D01*
X-148591D01*
X-147616Y328069D01*
X-147129Y327347D01*
G01Y321573D02*
X-147616Y320851D01*
X-148591Y320130D01*
X-149565D01*
X-150539Y320851D01*
G01X-158335Y323017D02*
X-155411D01*
G01X-168843Y736331D02*
X-166407Y744993D01*
X-163970Y736331D01*
G01X-158611D02*
Y744993D01*
G01X-150816Y736331D02*
Y744993D01*
G01X-167868Y739218D02*
X-164945D01*
G01X-139465Y779571D02*
X-138491Y781015D01*
X-137517Y781737D01*
X-136542D01*
X-135568Y781015D01*
G01X-138491Y777406D02*
X-139465Y778850D01*
Y779571D01*
G01X-144824Y776684D02*
X-145312D01*
Y777406D01*
X-144824Y776684D01*
G01X-141559Y750767D02*
X-142046Y750045D01*
X-143020Y749323D01*
X-143995Y750045D01*
X-144969Y751488D01*
Y752932D01*
X-143995Y754376D01*
X-143020Y755097D01*
X-142046Y754376D01*
X-141559Y752932D01*
X-144969D01*
G01X-168066Y781015D02*
X-167344Y783180D01*
X-165901Y784624D01*
X-163735Y785346D01*
X-161570Y784624D01*
X-160126Y783180D01*
X-159405Y781015D01*
X-160126Y778850D01*
X-161570Y777406D01*
X-163735Y776684D01*
X-165901Y777406D01*
X-167344Y778850D01*
X-168066Y781015D01*
G01X-167344Y774519D02*
X-160126Y787511D01*
G01X-158611Y757985D02*
Y757263D01*
G01X-154081Y784624D02*
X-153107Y785346D01*
X-152133D01*
X-151158Y784624D01*
X-150671Y783903D01*
Y783180D01*
X-151158Y782459D01*
X-152133Y781737D01*
X-151158Y781015D01*
X-150671Y780293D01*
X-150184Y779571D01*
Y778850D01*
X-150671Y778128D01*
X-151158Y777406D01*
X-152133Y776684D01*
X-153107D01*
X-154081Y777406D01*
X-154569Y778128D01*
G01X-153107Y781737D02*
X-152133D01*
G01X-148867Y751488D02*
X-149842Y750045D01*
X-150816Y749323D01*
X-151790Y750045D01*
X-152765Y751488D01*
Y752932D01*
X-151790Y754376D01*
X-150816Y755097D01*
X-149842Y754376D01*
X-148867Y752932D01*
G01X-158611Y755097D02*
Y749323D01*
G01X-148867Y757985D02*
Y749323D01*
G01X-164457Y756541D02*
X-164945Y757263D01*
X-165919Y757985D01*
X-166894D01*
X-167868Y757263D01*
X-168355Y756541D01*
Y755819D01*
X-167868Y755097D01*
X-165919Y753654D01*
X-164945Y752932D01*
X-164457Y752210D01*
Y750767D01*
X-164945Y750045D01*
X-165919Y749323D01*
X-166894D01*
X-167868Y750045D01*
X-168843Y751488D01*
G01X-137517Y781737D02*
X-138491Y782459D01*
X-138978Y783180D01*
Y783903D01*
X-138491Y784624D01*
X-137517Y785346D01*
X-136542D01*
X-135568Y784624D01*
X-135080Y783903D01*
Y783180D01*
X-135568Y782459D01*
X-136542Y781737D01*
G01X-152130Y2165399D02*
X-151655Y2166349D01*
X-150704Y2167300D01*
X-149754D01*
X-148803Y2166349D01*
X-148328Y2165399D01*
Y2163497D01*
X-148803Y2162547D01*
X-150704Y2160645D01*
X-151655Y2158744D01*
X-152130Y2155892D01*
X-148328D01*
G01X-106428Y-46130D02*
Y-46851D01*
X-106915Y-47573D01*
X-107402Y-48295D01*
X-108377Y-49017D01*
X-109351D01*
X-110326Y-48295D01*
X-110813Y-47573D01*
G01X-109351Y-43964D02*
X-108377D01*
G01X-110326Y-41077D02*
X-109351Y-40355D01*
X-108377D01*
X-107402Y-41077D01*
X-106915Y-41799D01*
Y-42521D01*
X-107402Y-43243D01*
X-108377Y-43964D01*
X-107402Y-44686D01*
X-106428Y-46130D01*
G01X-116659Y-40355D02*
Y-49017D01*
G01X-108864Y2164D02*
X-109838Y2886D01*
X-110326Y3608D01*
X-110813Y5051D01*
Y7938D01*
X-110326Y9382D01*
X-109838Y10104D01*
X-108864Y10826D01*
X-107889Y10104D01*
X-107402Y9382D01*
X-106915Y7938D01*
Y5051D01*
X-107402Y3608D01*
X-107889Y2886D01*
X-108864Y2164D01*
G01X-110813Y107453D02*
X-110326Y108897D01*
X-108864Y109618D01*
X-107402Y108897D01*
X-106915Y107453D01*
X-107402Y106009D01*
X-107889Y105288D01*
X-108864Y104566D01*
X-109838Y105288D01*
X-110326Y106009D01*
X-110813Y107453D01*
Y110340D01*
X-110326Y111784D01*
X-109838Y112505D01*
X-108864Y113227D01*
X-107889Y112505D01*
X-107402Y111784D01*
G01X-117146Y108175D02*
X-118121Y106731D01*
X-118608Y104566D01*
X-114710D01*
G01X-118608Y111784D02*
X-118121Y112505D01*
X-117146Y113227D01*
X-116172D01*
X-115198Y112505D01*
X-114710Y111784D01*
Y110340D01*
X-115198Y109618D01*
X-117146Y108175D01*
G01X-108378Y207866D02*
X-101160Y220858D01*
G01X-18732Y207866D02*
X-117761D01*
G01X-109100Y214362D02*
X-108378Y216528D01*
X-106934Y217971D01*
X-104769Y218693D01*
X-102604Y217971D01*
X-101160Y216528D01*
X-100438Y214362D01*
X-101160Y212197D01*
X-102604Y210753D01*
X-104769Y210032D01*
X-106934Y210753D01*
X-108378Y212197D01*
X-109100Y214362D01*
G01X-109651Y264599D02*
Y273260D01*
X-107215D01*
X-106241Y272538D01*
X-105753Y271817D01*
Y270373D01*
X-106241Y269651D01*
X-107215Y268929D01*
X-109651D01*
G01X-107702Y251606D02*
X-107215Y255216D01*
X-106728Y257381D01*
G01D02*
X-105753Y260268D01*
X-109651D01*
G01X-117933Y264599D02*
Y273260D01*
X-115497Y266042D01*
X-113061Y273260D01*
Y264599D01*
G01X-120857Y271095D02*
X-120369Y268929D01*
X-120857Y266764D01*
X-121831Y265321D01*
G01X-123293Y251606D02*
X-122806Y255216D01*
X-122318Y257381D01*
G01X-132550Y252329D02*
X-133524Y253772D01*
Y254494D01*
X-133037Y255216D01*
X-132550Y255937D01*
X-131575Y256659D01*
X-130601D01*
X-129626Y255937D01*
G01D02*
X-128652Y254494D01*
Y253772D01*
X-129139Y253050D01*
X-129626Y252329D01*
X-130601Y251606D01*
X-131575D01*
G01X-124754Y265321D02*
X-125729Y266764D01*
X-126216Y268929D01*
X-125729Y271095D01*
X-125241Y271817D01*
X-124754Y272538D01*
X-123780Y273260D01*
X-122806D01*
X-121831Y272538D01*
X-120857Y271095D01*
G01X-122318Y257381D02*
X-121344Y260268D01*
X-125241D01*
G01X-131575Y251606D02*
X-132550Y252329D01*
G01X-129139Y266042D02*
X-129626Y265321D01*
X-130601Y264599D01*
X-131575D01*
X-132550Y265321D01*
X-133037Y266042D01*
X-133524Y266764D01*
X-134011Y268929D01*
X-133524Y271095D01*
X-133037Y271817D01*
X-132550Y272538D01*
X-131575Y273260D01*
X-130601D01*
X-129626Y272538D01*
X-129139Y271817D01*
G01X-131575Y256659D02*
X-132550Y257381D01*
X-133037Y258103D01*
Y258825D01*
X-132550Y259546D01*
X-131575Y260268D01*
X-130601D01*
X-129626Y259546D01*
X-129139Y258825D01*
Y258103D01*
X-129626Y257381D01*
X-130601Y256659D01*
G01X-121831Y265321D02*
X-122806Y264599D01*
X-123780D01*
X-124754Y265321D01*
G01X-115497Y251606D02*
X-115985D01*
Y252329D01*
X-115497Y251606D01*
G01X-116959Y282643D02*
X-115985Y283365D01*
G01X-124754Y282643D02*
X-121831D01*
G01X-115985Y283365D02*
X-115010D01*
X-114036Y281921D01*
Y277591D01*
G01X-123293D02*
Y286252D01*
G01X-116959Y277591D02*
Y286252D01*
G01X-129139Y279756D02*
X-130113Y278313D01*
X-131088Y277591D01*
X-132062Y278313D01*
X-133037Y279756D01*
Y281200D01*
X-132062Y282643D01*
X-131088Y283365D01*
X-130113Y282643D01*
X-129139Y281200D01*
Y279756D01*
G01X-117896Y328791D02*
Y320130D01*
G01X-128128D02*
X-125692Y328791D01*
X-123256Y320130D01*
G01X-127154Y323017D02*
X-124230D01*
G01X-120333Y328791D02*
X-115461D01*
G01X-110378Y737775D02*
X-110865Y737053D01*
X-111839Y736331D01*
X-112814Y737053D01*
X-113788Y738497D01*
Y739940D01*
X-112814Y741384D01*
X-111839Y742105D01*
X-110865Y741384D01*
X-110378Y739940D01*
X-113788D01*
G01X-105506Y740662D02*
X-104531Y742105D01*
X-103557D01*
X-103070Y741384D01*
G01X-105506Y736331D02*
Y742105D01*
G01X-119635Y737053D02*
X-117686Y742105D01*
G01X-137174Y744993D02*
Y736331D01*
X-133276D01*
G01X-125481Y742105D02*
Y736331D01*
G01Y738497D02*
X-126456Y737053D01*
X-127430Y736331D01*
X-128404Y737053D01*
X-129379Y738497D01*
Y739940D01*
X-128404Y741384D01*
X-127430Y742105D01*
X-126456Y741384D01*
X-125481Y739940D01*
G01X-121583Y742105D02*
X-119635Y737053D01*
X-120122Y734888D01*
X-121096Y733444D01*
X-122071D01*
G01X-107797Y776684D02*
Y785346D01*
X-105361D01*
X-104387Y784624D01*
X-103899Y783903D01*
Y782459D01*
X-104387Y781737D01*
X-105361Y781015D01*
X-107797D01*
G01X-105993Y757985D02*
X-104044D01*
X-103070Y757263D01*
X-102095Y755819D01*
G01X-114276Y749323D02*
X-111839Y757985D01*
X-109404Y749323D01*
G01X-102095Y755819D02*
X-101608Y753654D01*
X-102095Y751488D01*
X-102583Y750767D01*
X-103070Y750045D01*
X-104044Y749323D01*
X-105993D01*
Y757985D01*
G01X-113301Y752210D02*
X-110378D01*
G01X-120952Y785346D02*
X-121926Y783903D01*
X-122413Y781737D01*
Y780293D01*
X-121926Y778128D01*
X-120952Y776684D01*
G01X-115592D02*
Y785346D01*
X-111694Y776684D01*
Y785346D01*
G01X-135568Y781015D02*
X-134593Y779571D01*
Y778850D01*
X-135080Y778128D01*
X-135568Y777406D01*
X-136542Y776684D01*
X-137517D01*
G01D02*
X-138491Y777406D01*
G01X-129234Y776684D02*
X-130208Y777406D01*
X-130696Y778128D01*
X-131183Y779571D01*
Y782459D01*
X-130696Y783903D01*
X-130208Y784624D01*
X-129234Y785346D01*
X-128259Y784624D01*
X-127772Y783903D01*
X-127285Y782459D01*
Y779571D01*
X-127772Y778128D01*
X-128259Y777406D01*
X-129234Y776684D01*
G01X-121583Y749323D02*
Y757985D01*
X-119148D01*
X-118173Y757263D01*
X-117686Y756541D01*
Y755097D01*
X-118173Y754376D01*
X-119148Y753654D01*
X-121583D01*
G01X-134251Y754376D02*
X-134738Y755097D01*
X-135713D01*
X-136200Y754376D01*
Y753654D01*
X-135225Y752932D01*
X-134251Y752210D01*
X-133764Y751488D01*
Y750767D01*
X-134251Y750045D01*
X-134738Y749323D01*
X-135713D01*
G01D02*
X-136687Y750767D01*
G01X-114728Y851377D02*
Y842716D01*
G01X-108395Y850655D02*
X-107420Y851377D01*
X-106446D01*
X-105472Y850655D01*
X-104984Y849933D01*
Y849212D01*
X-105472Y848490D01*
X-106446Y847768D01*
X-105472Y847046D01*
X-104497Y845603D01*
G01D02*
Y844881D01*
X-104984Y844159D01*
X-105472Y843437D01*
X-106446Y842716D01*
X-107420D01*
X-108395Y843437D01*
X-108882Y844159D01*
G01X-107420Y847768D02*
X-106446D01*
G01X-124472Y849933D02*
X-123985Y850655D01*
X-123011Y851377D01*
X-122037D01*
X-121062Y850655D01*
X-120575Y849933D01*
Y848490D01*
X-121062Y847768D01*
X-123011Y846324D01*
G01D02*
X-123985Y844881D01*
X-124472Y842716D01*
X-120575D01*
G01X-109369Y902689D02*
X-108395Y904133D01*
X-107420Y904855D01*
X-106446D01*
X-105472Y904133D01*
X-104984Y903411D01*
X-104497Y902689D01*
Y901968D01*
X-104984Y901245D01*
X-105472Y900524D01*
X-106446Y899802D01*
X-107420D01*
G01X-108395Y900524D02*
X-109369Y901968D01*
Y902689D01*
G01X-107420Y899802D02*
X-108395Y900524D01*
G01X-107420Y904855D02*
X-108395Y905576D01*
X-108882Y906298D01*
Y907020D01*
X-108395Y907742D01*
X-107420Y908464D01*
X-106446D01*
X-105472Y907742D01*
X-104984Y907020D01*
Y906298D01*
X-105472Y905576D01*
X-106446Y904855D01*
G01X-124472Y907020D02*
X-123985Y907742D01*
X-123011Y908464D01*
X-122037D01*
X-121062Y907742D01*
X-120575Y907020D01*
Y905576D01*
X-121062Y904855D01*
X-123011Y903411D01*
G01D02*
X-123985Y901968D01*
X-124472Y899802D01*
X-120575D01*
G01X-116677Y907020D02*
X-116190Y907742D01*
X-115216Y908464D01*
X-114241D01*
X-113267Y907742D01*
X-112780Y907020D01*
Y905576D01*
X-113267Y904855D01*
X-115216Y903411D01*
G01D02*
X-116190Y901968D01*
X-116677Y899802D01*
X-112780D01*
G01X-33322Y-51182D02*
X-77250D01*
G01X-93273Y-49017D02*
X-94248Y-48295D01*
X-94735Y-47573D01*
X-95222Y-46130D01*
Y-43243D01*
X-94735Y-41799D01*
X-94248Y-41077D01*
X-93273Y-40355D01*
X-92299Y-41077D01*
X-91812Y-41799D01*
X-91324Y-43243D01*
Y-46130D01*
X-91812Y-47573D01*
X-92299Y-48295D01*
X-93273Y-49017D01*
G01X-85478D02*
X-86452Y-48295D01*
X-86940Y-47573D01*
X-87427Y-46130D01*
Y-43243D01*
X-86940Y-41799D01*
X-86452Y-41077D01*
X-85478Y-40355D01*
X-84504Y-41077D01*
X-84017Y-41799D01*
X-83529Y-43243D01*
Y-46130D01*
X-84017Y-47573D01*
X-84504Y-48295D01*
X-85478Y-49017D01*
G01X-101069D02*
X-101556D01*
Y-48295D01*
X-101069Y-49017D01*
G01X-3937Y-1D02*
X-77250D01*
G01X-93273Y2164D02*
X-94248Y2886D01*
X-94735Y3608D01*
X-95222Y5051D01*
Y7938D01*
X-94735Y9382D01*
X-94248Y10104D01*
X-93273Y10826D01*
X-92299Y10104D01*
X-91812Y9382D01*
X-91324Y7938D01*
Y5051D01*
X-91812Y3608D01*
X-92299Y2886D01*
X-93273Y2164D01*
G01X-85478D02*
X-86452Y2886D01*
X-86940Y3608D01*
X-87427Y5051D01*
Y7938D01*
X-86940Y9382D01*
X-86452Y10104D01*
X-85478Y10826D01*
X-84504Y10104D01*
X-84017Y9382D01*
X-83529Y7938D01*
Y5051D01*
X-84017Y3608D01*
X-84504Y2886D01*
X-85478Y2164D01*
G01X-101069D02*
X-101556D01*
Y2886D01*
X-101069Y2164D01*
G01X112205Y102401D02*
X-77250D01*
G01X-85478Y113227D02*
Y104566D01*
G01X-93273D02*
X-94248Y105288D01*
X-94735Y106009D01*
X-95222Y107453D01*
Y110340D01*
X-94735Y111784D01*
X-94248Y112505D01*
X-93273Y113227D01*
X-92299Y112505D01*
X-91812Y111784D01*
X-91324Y110340D01*
Y107453D01*
X-91812Y106009D01*
X-92299Y105288D01*
X-93273Y104566D01*
G01X-101069D02*
X-101556D01*
Y105288D01*
X-101069Y104566D01*
G01X-80011Y217250D02*
X-79524Y217971D01*
X-78550Y218693D01*
X-77576D01*
X-76601Y217971D01*
X-76114Y217250D01*
Y215806D01*
X-76601Y215084D01*
G01X-70267Y210032D02*
X-71242Y210753D01*
X-71729Y211475D01*
X-72216Y212919D01*
Y215806D01*
X-71729Y217250D01*
X-71242Y217971D01*
X-70267Y218693D01*
X-69293Y217971D01*
X-68806Y217250D01*
X-68319Y215806D01*
Y212919D01*
X-68806Y211475D01*
X-69293Y210753D01*
X-70267Y210032D01*
G01X-76601Y215084D02*
X-78550Y213641D01*
X-79524Y212197D01*
X-80011Y210032D01*
X-76114D01*
G01X-92192D02*
Y218693D01*
X-95602Y212197D01*
X-91217D01*
G01X-85858Y210032D02*
X-86345D01*
Y210753D01*
X-85858Y210032D01*
G01X-78470Y264599D02*
Y273260D01*
X-74572Y264599D01*
Y273260D01*
G01X-78470Y258825D02*
X-77983Y259546D01*
X-77008Y260268D01*
X-76034D01*
X-75059Y259546D01*
X-74572Y258825D01*
Y257381D01*
X-75059Y256659D01*
G01D02*
X-77008Y255216D01*
X-77983Y253772D01*
X-78470Y251606D01*
X-74572D01*
G01X-97471Y271095D02*
X-96983Y268929D01*
X-97471Y266764D01*
X-97958Y266042D01*
G01X-99907Y260268D02*
Y251606D01*
G01X-94060Y264599D02*
Y273260D01*
X-90163Y264599D01*
Y273260D01*
G01X-82855Y251606D02*
Y260268D01*
X-86265Y253772D01*
X-81880D01*
G01X-101369Y265321D02*
X-102343Y266764D01*
X-102830Y268929D01*
X-102343Y271095D01*
X-101856Y271817D01*
X-101369Y272538D01*
X-100394Y273260D01*
X-99420D01*
X-98445Y272538D01*
X-97471Y271095D01*
G01X-97958Y266042D02*
X-98445Y265321D01*
X-99420Y264599D01*
X-100394D01*
X-101369Y265321D01*
G01X-94060Y258825D02*
X-93573Y259546D01*
X-92599Y260268D01*
X-91624D01*
X-90650Y259546D01*
X-90163Y258825D01*
Y257381D01*
X-90650Y256659D01*
G01D02*
X-92599Y255216D01*
X-93573Y253772D01*
X-94060Y251606D01*
X-90163D01*
G01X-82367Y264599D02*
X-86265D01*
Y273260D01*
X-82367D01*
G01X-86265Y268929D02*
X-83829D01*
G01X-75059Y279034D02*
X-75546Y278313D01*
X-76521Y277591D01*
X-77495Y278313D01*
X-78470Y279756D01*
Y281200D01*
X-77495Y282643D01*
X-76521Y283365D01*
X-75546Y282643D01*
X-75059Y281200D01*
X-78470D01*
G01X-92111Y286252D02*
Y285530D01*
G01Y283365D02*
Y277591D01*
G01X-82367Y286252D02*
Y277591D01*
G01X-97958Y284809D02*
X-98445Y285530D01*
X-99420Y286252D01*
X-100394D01*
X-101369Y285530D01*
X-101856Y284809D01*
Y284087D01*
X-101369Y283365D01*
X-100394Y282643D01*
X-99420Y281921D01*
X-98445Y281200D01*
X-97958Y280478D01*
Y279034D01*
X-98445Y278313D01*
X-99420Y277591D01*
X-100394D01*
X-101369Y278313D01*
X-102343Y279756D01*
G01X-82367D02*
X-83342Y278313D01*
X-84316Y277591D01*
X-85291Y278313D01*
X-86265Y279756D01*
Y281200D01*
X-85291Y282643D01*
X-84316Y283365D01*
X-83342Y282643D01*
X-82367Y281200D01*
G01X-73074Y328791D02*
Y320130D01*
X-69176D01*
G01X-96459Y328791D02*
Y320130D01*
X-92562D01*
G01X-88664Y328791D02*
Y320130D01*
X-84767D01*
G01X-104742D02*
X-102306Y328791D01*
X-99870Y320130D01*
G01X-103768Y323017D02*
X-100844D01*
G01X25012Y794711D02*
X-80540Y747158D01*
G01D02*
X-83690D01*
G01X-96736Y744993D02*
X-95762Y743549D01*
X-95275Y741384D01*
Y739940D01*
X-95762Y737775D01*
X-96736Y736331D01*
G01X-98053Y785346D02*
Y776684D01*
G01X-92206Y785346D02*
Y776684D01*
G01X-88309Y785346D02*
Y776684D01*
G01X-82950Y785346D02*
X-81975Y783903D01*
X-81488Y781737D01*
Y780293D01*
X-81975Y778128D01*
X-82950Y776684D01*
G01X-92206Y781015D02*
X-88309D01*
G01X-96736Y757985D02*
X-95762Y756541D01*
X-95275Y754376D01*
Y752932D01*
X-95762Y750767D01*
X-96736Y749323D01*
G01X-100489Y785346D02*
X-95617D01*
G01X0Y840550D02*
X-75319D01*
G01X-83547Y842716D02*
X-84522Y843437D01*
X-85009Y844159D01*
X-85496Y845603D01*
Y848490D01*
X-85009Y849933D01*
X-84522Y850655D01*
X-83547Y851377D01*
X-82573Y850655D01*
X-82086Y849933D01*
X-81598Y848490D01*
Y845603D01*
X-82086Y844159D01*
X-82573Y843437D01*
X-83547Y842716D01*
G01X-99138D02*
X-99625D01*
Y843437D01*
X-99138Y842716D01*
G01X-89394Y851377D02*
X-92317D01*
X-92804Y847768D01*
X-91830Y848490D01*
X-90856D01*
X-89881Y847768D01*
X-89394Y847046D01*
X-88907Y845603D01*
X-89394Y844159D01*
X-89881Y843437D01*
X-90856Y842716D01*
X-91830D01*
X-92804Y843437D01*
X-93291Y844159D01*
G01X112205Y897637D02*
X-75319D01*
G01X-91343Y899802D02*
X-92317Y900524D01*
X-92804Y901245D01*
X-93291Y902689D01*
Y905576D01*
X-92804Y907020D01*
X-92317Y907742D01*
X-91343Y908464D01*
X-90368Y907742D01*
X-89881Y907020D01*
X-89394Y905576D01*
Y902689D01*
X-89881Y901245D01*
X-90368Y900524D01*
X-91343Y899802D01*
G01X-83547D02*
X-84522Y900524D01*
X-85009Y901245D01*
X-85496Y902689D01*
Y905576D01*
X-85009Y907020D01*
X-84522Y907742D01*
X-83547Y908464D01*
X-82573Y907742D01*
X-82086Y907020D01*
X-81598Y905576D01*
Y902689D01*
X-82086Y901245D01*
X-82573Y900524D01*
X-83547Y899802D01*
G01X-99138D02*
X-99625D01*
Y900524D01*
X-99138Y899802D01*
G01X-39958Y-1120610D02*
Y-1139623D01*
G01X-39819Y-108736D02*
X-40540Y-107762D01*
Y-106787D01*
X-39819Y-105812D01*
X-38375Y-104838D01*
G01X-37653Y-109710D02*
X-38375D01*
X-39819Y-108736D01*
G01X-38375Y-104838D02*
X-37653D01*
X-36209Y-105812D01*
G01X-40540Y-107762D02*
X-41262Y-108736D01*
X-41984Y-109223D01*
X-42706D01*
X-43427Y-108736D01*
X-44149Y-107762D01*
Y-106787D01*
X-43427Y-105812D01*
X-42706Y-105325D01*
X-41984D01*
X-41262Y-105812D01*
X-40540Y-106787D01*
G01X-35488Y-107762D02*
X-36209Y-108736D01*
X-37653Y-109710D01*
G01X-38375Y-85837D02*
X-39819Y-85350D01*
X-40540Y-83888D01*
X-39819Y-82427D01*
X-38375Y-81940D01*
X-36931Y-82427D01*
X-36209Y-82914D01*
X-35488Y-83888D01*
X-36209Y-84863D01*
X-36931Y-85350D01*
X-38375Y-85837D01*
X-41262D01*
X-42706Y-85350D01*
X-43427Y-84863D01*
X-44149Y-83888D01*
X-43427Y-82914D01*
X-42706Y-82427D01*
G01X-35488Y-90222D02*
X-44149D01*
X-37653Y-93632D01*
Y-89248D01*
G01X-41765Y45140D02*
Y50914D01*
G01Y49471D02*
X-40791Y50914D01*
X-39816D01*
X-39329Y50192D01*
G01X-57843Y45140D02*
Y53801D01*
X-53945D01*
G01X-46150Y47305D02*
X-47124Y45862D01*
X-48098Y45140D01*
X-49073Y45862D01*
X-50047Y47305D01*
Y48749D01*
X-49073Y50192D01*
X-48098Y50914D01*
X-47124Y50192D01*
X-46150Y48749D01*
Y47305D01*
G01X-57843Y49471D02*
X-55407D01*
G01X-41035Y214362D02*
X-37137D01*
G01X-46881Y218693D02*
Y210032D01*
G01X-41035Y218693D02*
Y210032D01*
G01X-49318Y218693D02*
X-44446D01*
G01X-56626Y210032D02*
Y218693D01*
X-54190D01*
X-53215Y217971D01*
X-52728Y217250D01*
Y215806D01*
X-53215Y215084D01*
X-54190Y214362D01*
X-56626D01*
G01X-61985Y218693D02*
X-62959Y217250D01*
X-63446Y215084D01*
Y213641D01*
X-62959Y211475D01*
X-61985Y210032D01*
G01X-35596Y271095D02*
X-35109Y268929D01*
X-35596Y266764D01*
X-36083Y266042D01*
X-36570Y265321D01*
X-37544Y264599D01*
X-39493D01*
Y273260D01*
G01X-45340D02*
Y264599D01*
G01X-35596Y260268D02*
X-38519D01*
X-39006Y256659D01*
X-38032Y257381D01*
X-37057D01*
X-36083Y256659D01*
X-35596Y255937D01*
X-35109Y254494D01*
X-35596Y253050D01*
X-36083Y252329D01*
X-37057Y251606D01*
X-38032D01*
X-39006Y252329D01*
X-39493Y253050D01*
G01Y273260D02*
X-37544D01*
X-36570Y272538D01*
X-35596Y271095D01*
G01X-68726Y273260D02*
Y264599D01*
G01X-51674Y251606D02*
Y260268D01*
X-55084Y253772D01*
X-50699D01*
G01X-51186Y271817D02*
X-51674Y272538D01*
X-52648Y273260D01*
X-53622D01*
X-54597Y272538D01*
X-55084Y271817D01*
Y271095D01*
X-54597Y270373D01*
X-53622Y269651D01*
X-52648Y268929D01*
X-51674Y268208D01*
X-51186Y267486D01*
Y266042D01*
X-51674Y265321D01*
X-52648Y264599D01*
X-53622D01*
X-54597Y265321D01*
X-55084Y266042D01*
X-55571Y266764D01*
G01X-47289Y254494D02*
X-46802Y255937D01*
X-45340Y256659D01*
X-43878Y255937D01*
X-43391Y254494D01*
X-43878Y253050D01*
X-44365Y252329D01*
X-45340Y251606D01*
X-46314Y252329D01*
X-46802Y253050D01*
X-47289Y254494D01*
Y257381D01*
X-46802Y258825D01*
X-46314Y259546D01*
X-45340Y260268D01*
X-44365Y259546D01*
X-43878Y258825D01*
G01X-60930Y251606D02*
X-61905Y252329D01*
X-62392Y253050D01*
X-62879Y254494D01*
Y257381D01*
X-62392Y258825D01*
X-61905Y259546D01*
X-60930Y260268D01*
X-59956Y259546D01*
X-59469Y258825D01*
X-58981Y257381D01*
Y254494D01*
X-59469Y253050D01*
X-59956Y252329D01*
X-60930Y251606D01*
G01X-68726D02*
X-69213D01*
Y252329D01*
X-68726Y251606D01*
G01X-71162Y273260D02*
X-66290D01*
G01X-39493Y286252D02*
X-37544D01*
X-36570Y285530D01*
G01D02*
X-35596Y284087D01*
X-35109Y281921D01*
X-35596Y279756D01*
X-36083Y279034D01*
X-36570Y278313D01*
X-37544Y277591D01*
X-39493D01*
Y286252D01*
G01X-46802Y280478D02*
X-43878D01*
G01X-55084Y277591D02*
Y286252D01*
X-52648D01*
X-51674Y285530D01*
X-51186Y284809D01*
Y283365D01*
X-51674Y282643D01*
X-52648Y281921D01*
X-55084D01*
G01X-69213Y277591D02*
X-70187Y279034D01*
G01X-67751Y282643D02*
X-68239Y283365D01*
X-69213D01*
X-69700Y282643D01*
Y281921D01*
X-67751Y280478D01*
X-67264Y279756D01*
Y279034D01*
X-67751Y278313D01*
X-68239Y277591D01*
X-69213D01*
G01X-47776D02*
X-45340Y286252D01*
X-42904Y277591D01*
G01X-41893Y320130D02*
Y328791D01*
X-39457D01*
X-38482Y328069D01*
X-37995Y327347D01*
Y325904D01*
X-38482Y325182D01*
X-39457Y324460D01*
X-41893D01*
G01X-39457D02*
X-37995Y320130D01*
G01X-65766D02*
X-63330Y328791D01*
X-60894Y320130D01*
G01X-57483Y328791D02*
X-55534Y324460D01*
Y320130D01*
G01Y324460D02*
X-53585Y328791D01*
G01X-45790Y320130D02*
X-49688D01*
Y328791D01*
X-45790D01*
G01X-64791Y323017D02*
X-61868D01*
G01X-49688Y324460D02*
X-47252D01*
G01X32115Y799357D02*
X-66754Y774519D01*
G01D02*
X-69903D01*
G01X-39958Y2171102D02*
Y2152090D01*
G01X-2165Y-107274D02*
X-2887Y-108249D01*
X-3609Y-108736D01*
X-5052Y-109223D01*
X-7939D01*
X-9383Y-108736D01*
X-10105Y-108249D01*
X-10827Y-107274D01*
X-10105Y-106300D01*
X-9383Y-105812D01*
X-7939Y-105325D01*
X-5052D01*
X-3609Y-105812D01*
X-2887Y-106300D01*
X-2165Y-107274D01*
G01X-36209Y-105812D02*
X-35488Y-106787D01*
Y-107762D01*
G01Y-99479D02*
Y-99966D01*
X-36209D01*
X-35488Y-99479D01*
G01X-2165Y-83888D02*
X-2887Y-84863D01*
X-3609Y-85350D01*
X-5052Y-85837D01*
X-7939D01*
X-9383Y-85350D01*
X-10105Y-84863D01*
X-10827Y-83888D01*
X-10105Y-82914D01*
X-9383Y-82427D01*
X-7939Y-81940D01*
X-5052D01*
X-3609Y-82427D01*
X-2887Y-82914D01*
X-2165Y-83888D01*
G01Y-91684D02*
X-2887Y-92658D01*
X-3609Y-93145D01*
X-5052Y-93632D01*
X-7939D01*
X-9383Y-93145D01*
X-10105Y-92658D01*
X-10827Y-91684D01*
X-10105Y-90709D01*
X-9383Y-90222D01*
X-7939Y-89735D01*
X-5052D01*
X-3609Y-90222D01*
X-2887Y-90709D01*
X-2165Y-91684D01*
G01X-33322Y-51182D02*
Y-75660D01*
G01X-8148Y45862D02*
X-9122Y45140D01*
X-10096Y45862D01*
X-11071Y47305D01*
Y48749D01*
X-10096Y50192D01*
X-9122Y50914D01*
X-8148Y50192D01*
G01X-22764Y52358D02*
X-23251Y53079D01*
X-24226Y53801D01*
X-25200D01*
X-26174Y53079D01*
X-26661Y52358D01*
Y51636D01*
X-26174Y50914D01*
X-24226Y49471D01*
X-23251Y48749D01*
X-22764Y48027D01*
Y46583D01*
X-23251Y45862D01*
X-24226Y45140D01*
X-25200D01*
X-26174Y45862D01*
X-27149Y47305D01*
G01X-14969D02*
X-15943Y45862D01*
X-16917Y45140D01*
X-17892Y45862D01*
X-18866Y47305D01*
Y48749D01*
X-17892Y50192D01*
X-16917Y50914D01*
X-15943Y50192D01*
X-14969Y48749D01*
Y47305D01*
G01X46761Y234185D02*
X-15582Y207866D01*
G01D02*
X-18732D01*
G01X-37137Y218693D02*
Y210032D01*
G01X-31778Y218693D02*
X-30804Y217250D01*
X-30317Y215084D01*
Y213641D01*
X-30804Y211475D01*
X-31778Y210032D01*
G01X43194Y243616D02*
X-14041Y275425D01*
G01D02*
X-17190D01*
G01X-27800Y264599D02*
X-31698D01*
Y273260D01*
X-27800D01*
G01X-31698Y268929D02*
X-29262D01*
G01X44631Y248489D02*
X-16440Y317964D01*
G01X-30237Y286252D02*
X-29262Y284809D01*
X-28775Y282643D01*
Y281200D01*
X-29262Y279034D01*
X-30237Y277591D01*
G01X-16440Y317964D02*
X-19589D01*
G01X-32636Y328791D02*
X-31661Y327347D01*
X-31174Y325182D01*
Y323738D01*
X-31661Y321573D01*
X-32636Y320130D01*
G01X-2165Y-99479D02*
Y-99966D01*
X-2887D01*
X-2165Y-99479D01*
G01X0Y-3938D02*
Y-75660D01*
G01X31803Y47305D02*
X30829Y45862D01*
X29854Y45140D01*
X28880Y45862D01*
X27906Y47305D01*
Y48749D01*
X28880Y50192D01*
X29854Y50914D01*
X30829Y50192D01*
X31803Y48749D01*
Y47305D01*
G01X-2789Y45140D02*
Y53801D01*
G01X14264Y45140D02*
Y53801D01*
G01X-1814Y48749D02*
X135Y45140D01*
G01X7930Y46583D02*
X7443Y45862D01*
X6469Y45140D01*
X5494Y45862D01*
X4520Y47305D01*
Y48749D01*
X5494Y50192D01*
X6469Y50914D01*
X7443Y50192D01*
X7930Y48749D01*
X4520D01*
G01X-2789Y48027D02*
X135Y50914D01*
G01X12802Y50192D02*
X15725D01*
G01X28040Y101219D02*
X28827Y100432D01*
G01X26859Y101180D02*
Y193081D01*
G01X27646Y101180D02*
Y193081D01*
G01X28040Y194093D02*
Y101219D01*
G01X28433Y142433D02*
Y100530D01*
G01X28827Y100432D02*
Y194656D01*
G01X28877Y111192D02*
Y105253D01*
G01X28433Y99605D02*
X94772D01*
G01X33748Y99743D02*
X29221D01*
G01X34142Y100010D02*
X28630D01*
G01X94772Y100393D02*
X28433D01*
G01X27070D02*
X28433D01*
G01X94378Y100432D02*
X28827D01*
G01X34536Y100530D02*
X28729D01*
G01D02*
X28433D01*
G01X29221Y101180D02*
X34142D01*
G01X26859D02*
X27646D01*
G01X26859Y101574D02*
X27646D01*
G01X26859Y101968D02*
X27646D01*
G01Y102361D02*
X26859D01*
G01Y103149D02*
X31977D01*
G01X34831Y105253D02*
X28877D01*
G01X28433Y100530D02*
G03X29221Y99743I788J1D01*
G01X26859Y101180D02*
G03X28433Y99605I1575J0D01*
G01X27646Y101180D02*
G03X28446Y100393I787J0D01*
G01X28433Y101968D02*
G03X29221Y101180I788J0D01*
G01X196654Y102401D02*
X7874D01*
G01D02*
X196654D01*
G01X0Y110275D02*
G03X7874Y102401I7874J0D01*
G01X0Y110275D02*
G03X7874Y102401I7874J0D01*
G01X28266Y120412D02*
Y132814D01*
G01X29743Y139408D02*
Y134093D01*
G01Y113818D02*
Y133109D01*
G01X30727Y119133D02*
X29743Y120117D01*
G01Y139408D02*
X30727Y138424D01*
G01X34270Y113818D02*
X29743D01*
G01Y120117D02*
X28040D01*
G01X35746Y120412D02*
X28266D01*
G01X28433Y123660D02*
X34536D01*
G01X35746Y132814D02*
X28266D01*
G01X34536Y132912D02*
X28433D01*
G01X29743Y133109D02*
X28040D01*
G01X30727Y134093D02*
X28040D01*
G01X29743Y139408D02*
X34270D01*
G01X27646Y140781D02*
X26859D01*
G01X29743Y133109D02*
X30727Y134093D01*
G01Y114802D02*
X29743Y113818D01*
G01X26859Y111023D02*
X28877D01*
G01X34831Y111192D02*
X28877D01*
G01X27646Y111810D02*
X26859D01*
G01X27646Y112597D02*
X26859D01*
G01X0Y836613D02*
Y110275D01*
G01D02*
Y836613D01*
G01X29221Y192952D02*
Y164408D01*
G01X26859Y146438D02*
X27646D01*
G01X26859Y147046D02*
X27646D01*
G01Y147171D02*
X26859D01*
G01Y147244D02*
X27646D01*
G01Y147834D02*
X26859D01*
G01X27646Y147977D02*
X26859D01*
G01Y149408D02*
X27646D01*
G01X26859Y150332D02*
X27646D01*
G01Y152815D02*
X26859D01*
G01X27646Y153739D02*
X26859D01*
G01Y155314D02*
X27646D01*
G01Y156101D02*
X26859D01*
G01Y157282D02*
X27646D01*
G01Y158070D02*
X26859D01*
G01Y158857D02*
X31977D01*
G01X29221Y164408D02*
X28040D01*
G01X26859Y166731D02*
X31977D01*
G01X27646Y167519D02*
X26859D01*
G01X33089Y167558D02*
X28040D01*
G01X27646Y168306D02*
X26859D01*
G01X28827Y168503D02*
X26859D01*
G01X30067Y151613D02*
G03I-3090J0D01*
G01X28433Y192716D02*
Y142433D01*
G01D02*
X28132Y142510D01*
X27876Y142587D01*
X27706Y142664D01*
X27646Y142741D01*
G01X28433Y142433D02*
X27946Y142495D01*
X27507Y142556D01*
X27159Y142618D01*
X26936Y142679D01*
X26859Y142741D01*
G01Y141515D02*
X27646D01*
G01X26859Y142741D02*
X27646D01*
G01Y192223D02*
X27669Y192407D01*
X27732Y192572D01*
X27829Y192716D01*
G01X28433Y192558D02*
X28827Y192164D01*
G01X26859Y192223D02*
X26902Y192403D01*
X27028Y192570D01*
X27224Y192716D01*
G01Y194090D02*
X27829Y193586D01*
G01X28040Y190156D02*
X26859Y186613D01*
G01X27646D02*
X28827Y190156D01*
G01X28748Y189920D02*
X28040Y190156D01*
G01X28827Y192952D02*
X28040Y192164D01*
G01X26859Y180179D02*
X27646D01*
G01Y180742D02*
X26859D01*
G01X27646Y181073D02*
X26859D01*
G01Y181311D02*
X27646D01*
G01Y185207D02*
X26859D01*
G01X27646Y185798D02*
X26859D01*
G01X28827Y186219D02*
X28040D01*
G01X27646Y186613D02*
X26859D01*
G01X27646Y189341D02*
X26859D01*
G01X27646Y189932D02*
X26859D01*
G01X28040Y190156D02*
X28827D01*
G01X94378Y192164D02*
X28827D01*
G01X27646Y192223D02*
X26859D01*
G01X28827Y192716D02*
X27224D01*
G01X28827Y192952D02*
X94378D01*
G01X26859Y193081D02*
X27646D01*
G01X28040Y193306D02*
X28827D01*
G01X35006Y193475D02*
X28827D01*
G01X28433Y193869D02*
X94772D01*
G01X28040Y194093D02*
X28827D01*
G01X94772Y194656D02*
X28433D01*
G01D02*
G03X26859Y193081I1J-1575D01*
G01X27646Y180272D02*
G03X28040Y180954I-393J682D01*
G01X28433Y193869D02*
G03X27646Y193081I1J-788D01*
G01X28777Y176180D02*
Y175983D01*
G01X28827Y177204D02*
X28040Y176416D01*
G01X28777Y175983D02*
X26859D01*
G01X28040Y176180D02*
X28827D01*
G01X26859D02*
X27646D01*
G01X29221Y177204D02*
X28827D01*
G01X27646Y180272D02*
G03X26859Y178908I788J-1364D01*
G01X28040Y179590D02*
G03X27646Y178908I393J-682D01*
G01X28040Y179590D02*
G03X28827Y180954I-788J1364D01*
G01X15748Y303149D02*
Y840550D01*
G01X34685Y301180D02*
X0D01*
G01Y303149D02*
X352607D01*
G01X1575Y478030D02*
Y479507D01*
G01X13386D02*
Y478030D01*
G01D02*
X1575D01*
G01Y486397D02*
Y487873D01*
G01X5344Y489842D02*
Y493779D01*
G01Y506574D02*
Y507804D01*
G01Y509034D02*
Y510019D01*
G01X1826Y501653D02*
X1575Y500176D01*
G01X3083Y501406D02*
X2831Y500176D01*
G01X6350Y509527D02*
Y509034D01*
G01Y493779D02*
Y489842D01*
G01X8360D02*
Y493779D01*
G01X9365D02*
Y489842D01*
G01X13386Y507804D02*
Y506574D01*
G01Y511741D02*
Y510511D01*
G01Y487873D02*
Y486397D01*
G01X13135Y498700D02*
X13386Y500176D01*
G01X11878Y498946D02*
X12130Y500176D01*
G01X5344Y510019D02*
X5596Y510757D01*
G01X6601Y510019D02*
X6350Y509527D01*
G01X2831Y500176D02*
X3083Y498946D01*
G01X12130Y500176D02*
X11878Y501406D01*
G01X1575Y500176D02*
X1826Y498700D01*
G01X13386Y500176D02*
X13135Y501653D01*
G01X2580Y502883D02*
X1826Y501653D01*
G01X12381Y497469D02*
X13135Y498700D01*
G01X3585Y502145D02*
X3083Y501406D01*
G01X11376Y498208D02*
X11878Y498946D01*
G01X6350Y512725D02*
X6601Y512233D01*
G01X5596Y508296D02*
X5344Y509034D01*
G01X6350D02*
X6601Y508296D01*
G01X5596Y512233D02*
X5344Y512971D01*
G01X5596Y510757D02*
X6350Y511495D01*
G01X6852Y510265D02*
X6601Y510019D01*
G01X3334Y503621D02*
X2580Y502883D01*
G01X11627Y496731D02*
X12381Y497469D01*
G01X3083Y498946D02*
X3585Y498208D01*
G01X11878Y501406D02*
X11376Y502145D01*
G01X1826Y498700D02*
X2580Y497469D01*
G01X13135Y501653D02*
X12381Y502883D01*
G01X5093Y503129D02*
X3585Y502145D01*
G01X9868Y497223D02*
X11376Y498208D01*
G01X2580Y497469D02*
X3334Y496731D01*
G01X6098Y507804D02*
X5596Y508296D01*
G01X6601D02*
X7104Y507804D01*
G01X12381Y502883D02*
X11627Y503621D01*
G01X6350Y511495D02*
X5596Y512233D01*
G01X6601D02*
X6852Y511987D01*
G01X7355Y510511D02*
X6852Y510265D01*
G01X4339Y504113D02*
X3334Y503621D01*
G01X10622Y496239D02*
X11627Y496731D01*
G01X5093Y504359D02*
X4339Y504113D01*
G01X3585Y498208D02*
X5093Y497223D01*
G01X11376Y502145D02*
X9868Y503129D01*
G01Y495993D02*
X10622Y496239D01*
G01X3334Y496731D02*
X4339Y496239D01*
G01X11627Y503621D02*
X10622Y504113D01*
G01X6852Y511987D02*
X7355Y511741D01*
G01X4339Y496239D02*
X5093Y495993D01*
G01X10622Y504113D02*
X9868Y504359D01*
G01X5093Y495993D02*
X6350Y495747D01*
G01X9868Y504359D02*
X8611Y504605D01*
G01X5093Y497223D02*
X6601Y496977D01*
G01X9868Y503129D02*
X8360Y503375D01*
G01X13386Y486397D02*
X7857D01*
G01X6350D02*
X1575D01*
G01Y487873D02*
X13386D01*
G01X9365Y489842D02*
X8360D01*
G01X6350D02*
X5344D01*
G01Y493779D02*
X6350D01*
G01X8360D02*
X9365D01*
G01X6350Y495747D02*
X8611D01*
G01X6601Y496977D02*
X8360D01*
G01Y503375D02*
X6601D01*
G01X8611Y504605D02*
X6350D01*
G01X13386Y506574D02*
X5344D01*
G01Y507804D02*
X6098D01*
G01X7104D02*
X13386D01*
G01Y510511D02*
X7355D01*
G01Y511741D02*
X13386D01*
G01X8360Y496977D02*
X9868Y497223D01*
G01X8611Y495747D02*
X9868Y495993D01*
G01X6350Y504605D02*
X5093Y504359D01*
G01X6601Y503375D02*
X5093Y503129D01*
G01X6350Y479507D02*
Y486397D01*
G01X7857D02*
Y479507D01*
G01X1575D02*
X6350D01*
G01X7857D02*
X13386D01*
G01X5344Y517647D02*
Y518877D01*
G01Y520107D02*
Y521092D01*
G01Y524044D02*
Y525029D01*
G01X6350Y524536D02*
Y523798D01*
G01Y520599D02*
Y520107D01*
G01X13386Y526751D02*
Y525521D01*
G01Y522814D02*
Y521584D01*
G01Y518877D02*
Y517647D01*
G01X5344Y525029D02*
X5596Y525767D01*
G01X5344Y521092D02*
X5596Y521830D01*
G01X6601Y525029D02*
X6350Y524536D01*
G01X6601Y521092D02*
X6350Y520599D01*
G01X5596Y519369D02*
X5344Y520107D01*
G01X6350D02*
X6601Y519369D01*
G01X5596Y523306D02*
X5344Y524044D01*
G01X5596Y525767D02*
X6098Y526259D01*
G01X6852Y525275D02*
X6601Y525029D01*
G01X5596Y521830D02*
X6350Y522568D01*
G01X6852Y521338D02*
X6601Y521092D01*
G01X6350Y523798D02*
X6601Y523306D01*
G01X6098Y518877D02*
X5596Y519369D01*
G01X6601D02*
X7104Y518877D01*
G01X6350Y522568D02*
X5596Y523306D01*
G01X6601D02*
X6852Y523060D01*
G01X7355Y525521D02*
X6852Y525275D01*
G01X7355Y521584D02*
X6852Y521338D01*
G01X6098Y526259D02*
X7355Y526751D01*
G01X6852Y523060D02*
X7355Y522814D01*
G01X13386Y517647D02*
X5344D01*
G01Y518877D02*
X6098D01*
G01X7104D02*
X13386D01*
G01Y521584D02*
X7355D01*
G01Y522814D02*
X13386D01*
G01Y525521D02*
X7355D01*
G01Y526751D02*
X13386D01*
G01X5344Y512971D02*
Y513956D01*
G01X6350Y513464D02*
Y512725D01*
G01X13386Y515678D02*
Y514448D01*
G01X5344Y513956D02*
X5596Y514694D01*
G01X6601Y513956D02*
X6350Y513464D01*
G01X5596Y514694D02*
X6098Y515186D01*
G01X6852Y514202D02*
X6601Y513956D01*
G01X7355Y514448D02*
X6852Y514202D01*
G01X6098Y515186D02*
X7355Y515678D01*
G01X13386Y514448D02*
X7355D01*
G01Y515678D02*
X13386D01*
G01X55118Y801180D02*
G03I-15748J0D01*
G01X100000Y840550D02*
X3937D01*
G01D02*
X921819D01*
G01X3937D02*
G03X0Y836613I0J-3937D01*
G01X3937Y840550D02*
G03X0Y836613I0J-3937D01*
G01X61035Y53801D02*
Y53079D01*
G01Y50914D02*
Y45140D01*
G01X51778D02*
Y50914D01*
G01X35701Y48749D02*
X36675Y50192D01*
X37650Y50914D01*
X38624Y50192D01*
X39598Y48749D01*
Y47305D01*
X38624Y45862D01*
X37650Y45140D01*
X36675D01*
X35701Y47305D01*
G01X46906Y46583D02*
X46419Y45862D01*
X45445Y45140D01*
X44470Y45862D01*
X43496Y47305D01*
Y48749D01*
X44470Y50192D01*
X45445Y50914D01*
X46419Y50192D01*
X46906Y48749D01*
X43496D01*
G01X51778Y49471D02*
X52753Y50914D01*
X53727D01*
X54702Y49471D01*
Y45140D01*
G01X35701Y50914D02*
Y42253D01*
G01X54398Y104960D02*
Y125038D01*
G01X54831Y107469D02*
Y135965D01*
G01X56406D02*
Y107468D01*
G01X56760Y104960D02*
Y125038D01*
G01X58414Y104960D02*
Y125038D01*
G01X58847Y107469D02*
Y135965D01*
G01X60422D02*
Y107468D01*
G01X60776Y104960D02*
Y125038D01*
G01X62430Y104960D02*
Y125038D01*
G01X62863Y107469D02*
Y135965D01*
G01X64792Y104960D02*
X62430D01*
G01X60776D02*
X58414D01*
G01X56760D02*
X54398D01*
G01Y107322D02*
X56760D01*
G01X58414D02*
X60776D01*
G01X62430D02*
X64792D01*
G01X54831Y107464D02*
X56406D01*
G01X58847D02*
X60422D01*
G01X62863D02*
X64437D01*
G01X43148Y100826D02*
X43542Y100432D01*
G01X45766D02*
X45372Y100826D01*
G01X32764Y105253D02*
Y103936D01*
G01X33089Y147354D02*
Y103385D01*
G01X34142Y100010D02*
Y99605D01*
G01X34536Y105253D02*
Y100530D01*
G01X34831Y105253D02*
Y100432D01*
G01X34930Y100393D02*
Y99605D01*
G01X35143Y100393D02*
Y99605D01*
G01X35536Y100393D02*
Y99605D01*
G01X36111Y117991D02*
Y101219D01*
G01X36209Y100393D02*
Y99605D01*
G01X36996D02*
Y103385D01*
G01X37784Y100393D02*
Y99605D01*
G01X37981Y101219D02*
Y144133D01*
G01X38168Y100826D02*
Y124054D01*
G01X40392Y100826D02*
Y122086D01*
G01X40727Y101548D02*
Y114044D01*
G01X43148Y107125D02*
Y100826D01*
G01X43876Y106731D02*
Y100432D01*
G01X45372Y124054D02*
Y100826D01*
G01X45451Y100747D02*
Y100432D01*
G01X45559D02*
Y122086D01*
G01X46367Y104960D02*
Y125038D01*
G01X46800Y135965D02*
Y107469D01*
G01X47036Y100393D02*
Y99605D01*
G01X47823Y100393D02*
Y99605D01*
G01X48374Y107468D02*
Y135965D01*
G01X48611Y100393D02*
Y99605D01*
G01X48729Y104960D02*
Y125038D01*
G01X49201Y144133D02*
Y101810D01*
G01X50382Y104960D02*
Y125038D01*
G01X50815Y135965D02*
Y107469D01*
G01X50973Y100393D02*
Y99605D01*
G01X51760Y100786D02*
Y99605D01*
G01X52390Y107468D02*
Y135965D01*
G01X52744Y104960D02*
Y125038D01*
G01X53630Y100432D02*
Y107519D01*
G01X37917Y110144D02*
X36312Y101043D01*
G01X37087Y100906D02*
X38692Y110007D01*
G01X34319Y99988D02*
X34232Y100004D01*
X34142Y100010D01*
G01X86209Y100786D02*
X36996D01*
G01X38168Y100826D02*
X45372D01*
G01X34142Y101180D02*
X51866D01*
G01X34831Y101219D02*
X88374D01*
G01X40727Y101546D02*
X38168D01*
G01X70658Y101574D02*
X52548D01*
G01X45559Y101810D02*
X53630D01*
G01X40727Y102334D02*
X38168D01*
G01X40727Y102432D02*
X38168D01*
G01Y102794D02*
X40392D01*
G01X40727Y102826D02*
X38168D01*
G01Y102991D02*
X40392D01*
G01X38168Y103318D02*
X40727D01*
G01X90117Y103385D02*
X33089D01*
G01X38168Y103903D02*
X40392D01*
G01Y103975D02*
X38168D01*
G01X52744Y104960D02*
X50382D01*
G01X48729D02*
X46367D01*
G01X43148Y106731D02*
X40392D01*
G01X43148Y107125D02*
X40392D01*
G01X46367Y107322D02*
X48729D01*
G01X50382D02*
X52744D01*
G01X46800Y107464D02*
X48374D01*
G01X50815D02*
X52390D01*
G01X53630Y107519D02*
X49201D01*
G01X36111Y101219D02*
X35323Y100432D01*
G01X37981Y101219D02*
X37193Y100432D01*
G01X38168Y100826D02*
X37774Y100432D01*
G01X40392Y100826D02*
X39998Y100432D01*
G01X49201Y101810D02*
X47823Y100432D01*
G01X33748Y99743D02*
G03X34536Y100530I1J787D01*
G01X34930Y100393D02*
G03X34142Y101180I-788J-1D01*
G01X52548Y101574D02*
G03X51760Y100786I0J-788D01*
G01X35536Y99605D02*
G03X37087Y100906I0J1575D01*
G01X35536Y100393D02*
G03X36312Y101043I1J787D01*
G01X31977Y103149D02*
G03X32764Y103936I0J787D01*
G01X37311Y103385D02*
G03X36996Y102755I473J-630D01*
G01X43876Y106731D02*
G03X40727I-1575J0D01*
G01X56406Y135471D02*
X56209Y135839D01*
G01X56406Y135965D02*
X56209Y136332D01*
G01X60422Y135471D02*
X60225Y135839D01*
G01X60422Y135965D02*
X60225Y136332D01*
G01X54595Y116000D02*
X54617Y115635D01*
G01X54425Y120734D02*
X54403Y121099D01*
G01X56192Y115635D02*
X56170Y116000D01*
G01X55978Y121099D02*
X56000Y120734D01*
G01X54425Y120308D02*
X54595Y116000D01*
G01X54425Y120734D02*
X54595Y116425D01*
G01X56170Y116000D02*
X56000Y120308D01*
G01X56170Y116425D02*
X56000Y120734D01*
G01X54897Y149940D02*
X55978Y121099D01*
G01X55370Y148464D02*
X56426Y119330D01*
G01X56820D02*
X55763Y148464D01*
G01X54425Y120308D02*
X54403Y121099D01*
G01X55978D02*
X56000Y120308D01*
G01X56170Y116425D02*
X56192Y115635D01*
G01X54617D02*
X54595Y116425D01*
G01X58764Y116000D02*
X58772Y115635D01*
G01X58704Y120734D02*
X58697Y121099D01*
G01X60346Y115635D02*
X60339Y116000D01*
G01X60272Y121099D02*
X60279Y120734D01*
G01X58704Y120308D02*
X58764Y116000D01*
G01X58704Y120734D02*
X58764Y116425D01*
G01X60339Y116000D02*
X60279Y120308D01*
G01X60339Y116425D02*
X60279Y120734D01*
G01X58318Y149940D02*
X58697Y121099D01*
G01X59893Y149940D02*
X60272Y121099D01*
G01X57557Y148464D02*
X57909Y119330D01*
G01X58302D02*
X57950Y148464D01*
G01X60313D02*
X60665Y119330D01*
G01X60706Y148464D02*
X61058Y119330D01*
G01X58704Y120308D02*
X58697Y121099D01*
G01X60272D02*
X60279Y120308D01*
G01X58772Y115635D02*
X58764Y116425D01*
G01X60339D02*
X60346Y115635D01*
G01X54398Y146889D02*
Y140196D01*
G01X54425Y120734D02*
Y120308D01*
G01X54595Y116425D02*
Y116000D01*
G01X55028Y143500D02*
Y135839D01*
G01X56000Y120308D02*
Y120734D01*
G01X56170Y116000D02*
Y116425D01*
G01X56209Y135839D02*
Y143500D01*
G01X56760Y146889D02*
Y140196D01*
G01X58414Y146889D02*
Y140196D01*
G01X58704Y120734D02*
Y120308D01*
G01X58764Y116425D02*
Y116000D01*
G01X59044Y143500D02*
Y135839D01*
G01X60225D02*
Y143500D01*
G01X60279Y120308D02*
Y120734D01*
G01X60339Y116000D02*
Y116425D01*
G01X60776Y146889D02*
Y140196D01*
G01X62430Y146889D02*
Y140196D01*
G01X62933Y116425D02*
Y116000D01*
G01X62984Y120734D02*
Y120308D01*
G01X63059Y143500D02*
Y135839D01*
G01X62984Y120308D02*
X62991Y121099D01*
G01X63313Y149940D02*
X62991Y121099D01*
G01X62984Y120734D02*
X62933Y116425D01*
G01X62984Y120308D02*
X62933Y116000D01*
G01X62500Y148464D02*
X62147Y119330D01*
G01X62893Y148464D02*
X62541Y119330D01*
G01X62984Y120734D02*
X62991Y121099D01*
G01X62933Y116000D02*
X62927Y115635D01*
G01X55028Y136332D02*
X54831Y135965D01*
G01X55028Y135839D02*
X54831Y135471D01*
G01X59044Y136332D02*
X58847Y135965D01*
G01X59044Y135839D02*
X58847Y135471D01*
G01X63059Y136332D02*
X62863Y135965D01*
G01X63059Y135839D02*
X62863Y135471D01*
G01X54617Y115635D02*
X56192D01*
G01X58772D02*
X60346D01*
G01X62927D02*
X64502D01*
G01X54611Y115841D02*
X56186D01*
G01X58770D02*
X60344D01*
G01X62928D02*
X64503D01*
G01X64508Y116000D02*
X62933D01*
G01X60339D02*
X58764D01*
G01X56170D02*
X54595D01*
G01X64508Y116425D02*
X62933D01*
G01X60339D02*
X58764D01*
G01X56170D02*
X54595D01*
G01X62430Y118739D02*
X60776D01*
G01X58414D02*
X56760D01*
G01X64559Y120308D02*
X62984D01*
G01X60279D02*
X58704D01*
G01X56000D02*
X54425D01*
G01X64559Y120734D02*
X62984D01*
G01X60279D02*
X58704D01*
G01X56000D02*
X54425D01*
G01X54403Y121099D02*
X55978D01*
G01X58697D02*
X60272D01*
G01X62991D02*
X64565D01*
G01X64792Y125038D02*
X62430D01*
G01X60776D02*
X58414D01*
G01X56760D02*
X54398D01*
G01X54827Y110023D02*
X54831Y109958D01*
G01X56406D02*
X56402Y110023D01*
G01X54617Y115635D02*
X54827Y110023D01*
G01X56192Y115635D02*
X56402Y110023D01*
G01X54831Y109882D02*
X54827Y110023D01*
G01X56402D02*
X56406Y109882D01*
G01X58846Y110023D02*
X58847Y109958D01*
G01X60422D02*
X60420Y110023D01*
G01X58772Y115635D02*
X58846Y110023D01*
G01X60346Y115635D02*
X60420Y110023D01*
G01X58847Y109882D02*
X58846Y110023D01*
G01X60420D02*
X60422Y109882D01*
G01X62933Y116425D02*
X62863Y109882D01*
G01X62864Y110023D02*
X62927Y115635D01*
G01X62864Y110023D02*
X62863Y109958D01*
G01X54831Y108842D02*
X56406D01*
G01X58847D02*
X60422D01*
G01X62863D02*
X64437D01*
G01X54831Y109817D02*
X56406D01*
G01X58847D02*
X60422D01*
G01X62863D02*
X64437D01*
G01X54827Y110023D02*
X56406D01*
G01X58846D02*
X60422D01*
G01X62863D02*
X64439D01*
G01X54831Y111757D02*
X56406D01*
G01X58847D02*
X60422D01*
G01X62863D02*
X64437D01*
G01Y111969D02*
X62863D01*
G01X56406D02*
X54831D01*
G01X60422D02*
X58847D01*
G01X64437Y112462D02*
X62863D01*
G01X56406D02*
X54831D01*
G01X60422D02*
X58847D01*
G01X48374Y135471D02*
X48178Y135839D01*
G01X48374Y135965D02*
X48178Y136332D01*
G01X52390Y135471D02*
X52193Y135839D01*
G01X52390Y135965D02*
X52193Y136332D01*
G01X50426Y116000D02*
X50462Y115635D01*
G01X52037D02*
X52000Y116000D01*
G01X51684Y121099D02*
X51720Y120734D01*
G01X50109Y121099D02*
X50146Y120716D01*
G01X45866Y120308D02*
X46008Y118739D01*
G01X47831Y116000D02*
X47441Y120308D01*
G01X47831Y116425D02*
X47441Y120734D01*
G01X43330Y149940D02*
X45815Y121099D01*
G01X44905Y149940D02*
X47390Y121099D01*
G01X45192Y119330D02*
X42726Y148464D01*
G01X43122D02*
X45587Y119330D01*
G01X45484Y148464D02*
X47949Y119330D01*
G01X48344D02*
X45879Y148464D01*
G01X46028Y118739D02*
X45866Y120716D01*
G01X50146Y120308D02*
X50248Y118739D01*
G01X50382Y116668D02*
X50426Y116000D01*
G01X50382Y117093D02*
X50426Y116425D01*
G01X52000Y116000D02*
X51720Y120308D01*
G01X52000Y116425D02*
X51720Y120734D01*
G01X45866Y120308D02*
X45815Y121099D01*
G01X47390D02*
X47441Y120308D01*
G01X47831Y116425D02*
X47882Y115635D01*
G01X48326Y149940D02*
X50109Y121099D01*
G01X49901Y149940D02*
X51684Y121099D01*
G01X47670Y148464D02*
X49431Y119330D01*
G01X49826D02*
X48065Y148464D01*
G01X50427D02*
X52188Y119330D01*
G01X52582D02*
X50821Y148464D01*
G01X50262Y118739D02*
X50146Y120716D01*
G01X52003Y115635D02*
X52002Y115664D01*
G01X50146Y120308D02*
X50109Y121099D01*
G01X51684D02*
X51720Y120308D01*
G01X50462Y115635D02*
X50426Y116425D01*
G01X52000D02*
X52037Y115635D01*
G01X53322Y149940D02*
X54403Y121099D01*
G01X52613Y148464D02*
X53670Y119330D01*
G01X54064D02*
X53007Y148464D01*
G01X30727Y138424D02*
Y114802D01*
G01X30924Y127893D02*
Y125334D01*
G01Y115334D02*
Y118877D01*
G01Y134349D02*
Y137893D01*
G01X31120Y137597D02*
Y129566D01*
G01Y127597D02*
Y125629D01*
G01Y115629D02*
Y123660D01*
G01X32892Y137597D02*
Y129566D01*
G01Y127597D02*
Y125629D01*
G01Y123660D02*
Y115629D01*
G01X33286Y138424D02*
Y114802D01*
G01X34270Y113818D02*
Y133109D01*
G01Y134093D02*
Y139408D01*
G01X34831Y134093D02*
Y133109D01*
G01X35422Y146889D02*
Y118739D01*
G01X35717Y147354D02*
Y119330D01*
G01X35746Y132814D02*
Y120412D01*
G01X35914Y133109D02*
Y120117D01*
G01X36701D02*
Y133109D01*
G01X43483Y123267D02*
Y113621D01*
G01X43886Y136259D02*
Y140196D01*
G01X45451Y113650D02*
Y116692D01*
G01X45866Y120716D02*
Y120308D01*
G01X46367Y146889D02*
Y140196D01*
G01X46996Y143500D02*
Y135839D01*
G01X47441Y120308D02*
Y120734D01*
G01X47831Y116000D02*
Y116425D01*
G01X48178Y135839D02*
Y143500D01*
G01X48729Y146889D02*
Y140196D01*
G01X50146Y120716D02*
Y120308D01*
G01X50382Y146889D02*
Y140196D01*
G01X50426Y116425D02*
Y116000D01*
G01X51012Y143500D02*
Y135839D01*
G01X51720Y120308D02*
Y120734D01*
G01X52000Y116000D02*
Y116425D01*
G01X52193Y135839D02*
Y143500D01*
G01X52744Y146889D02*
Y140196D01*
G01X51904Y118168D02*
Y117800D01*
G01X52137Y112873D02*
Y114146D01*
G01X34270Y113818D02*
X33286Y114802D01*
G01Y134093D02*
X34270Y133109D01*
G01X47882Y115635D02*
X47831Y116000D01*
G01X47390Y121099D02*
X47441Y120734D01*
G01X45815Y121099D02*
X45841Y120907D01*
X45866Y120716D01*
G01X46996Y136332D02*
X46800Y135965D01*
G01X46996Y135839D02*
X46800Y135471D01*
G01X51012Y136332D02*
X50815Y135965D01*
G01X51012Y135839D02*
X50815Y135471D01*
G01X45372Y113621D02*
X43483D01*
G01X40727Y113650D02*
X45451D01*
G01Y114044D02*
X40727D01*
G01X33286Y114802D02*
X30727D01*
G01X33089Y115334D02*
X30924D01*
G01X32892Y115629D02*
X31120D01*
G01X46367Y115635D02*
X47882D01*
G01X50462D02*
X52037D01*
G01X46367Y115841D02*
X47869D01*
G01X50453D02*
X52028D01*
G01X52000Y116000D02*
X50426D01*
G01X47831D02*
X46367D01*
G01X38168Y116299D02*
X45451D01*
G01X52000Y116425D02*
X50426D01*
G01X47831D02*
X46367D01*
G01X31120Y116613D02*
X32892D01*
G01X45451Y116692D02*
X38168D01*
G01X32892Y117597D02*
X31120D01*
G01X33089Y117893D02*
X30924D01*
G01X37981Y117991D02*
X36111D01*
G01X54398Y118739D02*
X52744D01*
G01X50382D02*
X48729D01*
G01X46367D02*
X35422D01*
G01X32892Y118820D02*
X31120D01*
G01X30924Y118877D02*
X33089D01*
G01X87489Y119330D02*
X35717D01*
G01X74004Y119527D02*
X49201D01*
G01X34270Y120117D02*
X36701D01*
G01X51720Y120308D02*
X50146D01*
G01X47441D02*
X45866D01*
G01X31120Y120708D02*
X32892D01*
G01X51720Y120734D02*
X50382D01*
G01X47441D02*
X46367D01*
G01X45815Y121099D02*
X47390D01*
G01X50109D02*
X51684D01*
G01X32892Y121692D02*
X31120D01*
G01Y121774D02*
X32892D01*
G01X45559Y122086D02*
X37981D01*
G01X45372Y124054D02*
X38168D01*
G01X52744Y125038D02*
X50382D01*
G01X48729D02*
X46367D01*
G01X33089Y125334D02*
X30924D01*
G01X32892Y125629D02*
X31120D01*
G01X32892Y127597D02*
X31120D01*
G01X33089Y127893D02*
X30924D01*
G01X32892Y129566D02*
X31120D01*
G01X32892Y131453D02*
X31120D01*
G01X32892Y131534D02*
X31120D01*
G01X32892Y132519D02*
X31120D01*
G01X34270Y133109D02*
X88935D01*
G01X34831Y134093D02*
X33286D01*
G01X49201Y134290D02*
X37981D01*
G01X33089Y134349D02*
X30924D01*
G01X32892Y134406D02*
X31120D01*
G01X33089Y135334D02*
X30924D01*
G01X31120Y135629D02*
X32892D01*
G01X43886Y136259D02*
X37981D01*
G01X32892Y136613D02*
X31120D01*
G01X32892Y137597D02*
X31120D01*
G01X33089Y137893D02*
X30924D01*
G01X33286Y138424D02*
X30727D01*
G01X43886Y139212D02*
X37981D01*
G01X85225Y140196D02*
X37981D01*
G01X33286Y138424D02*
X34270Y139408D01*
G01Y120117D02*
X33286Y119133D01*
G01X37520Y115078D02*
X36780Y114808D01*
G01X37789Y114338D02*
X37049Y114068D01*
G01X33975Y116751D02*
G03I-1969J0D01*
G01Y126751D02*
G03I-1969J0D01*
G01X43483Y123267D02*
G03X42695Y124054I-787J0D01*
G01X38955D02*
G03X38168Y123267I0J-787D01*
G01X36780Y114808D02*
X37739Y112174D01*
G01X38479Y112443D02*
X37520Y115078D01*
G01X50809Y110023D02*
X50815Y109958D01*
G01X52390D02*
X52384Y110023D01*
G01X46367Y114946D02*
X46791Y110023D01*
G01X47882Y115635D02*
X48366Y110023D01*
G01X46800Y109882D02*
X46791Y110023D01*
G01X48366D02*
X48374Y109882D01*
G01X50462Y115635D02*
X50809Y110023D01*
G01X52037Y115635D02*
X52384Y110023D01*
G01X50815Y109882D02*
X50809Y110023D01*
G01X52384D02*
X52390Y109882D01*
G01X34536Y111192D02*
Y132912D01*
G01X34831Y120117D02*
Y111192D01*
G01X46791Y110023D02*
X46800Y109958D01*
G01X48374D02*
X48366Y110023D01*
G01X45372Y108306D02*
X44467D01*
G01X46800Y108842D02*
X48374D01*
G01X50815D02*
X52390D01*
G01X46800Y109817D02*
X48374D01*
G01X50815D02*
X52390D01*
G01X45372Y109881D02*
X44467D01*
G01X46791Y110023D02*
X48374D01*
G01X50809D02*
X52390D01*
G01X46800Y111757D02*
X48374D01*
G01X50815D02*
X52390D01*
G01Y111969D02*
X50815D01*
G01X48374D02*
X46800D01*
G01X52390Y112462D02*
X50815D01*
G01X48374D02*
X46800D01*
G01X38692Y110007D02*
G03X38479Y112443I-4653J820D01*
G01X37917Y110144D02*
G03X37739Y112174I-3878J683D01*
G01X44467Y109881D02*
G03Y108306I0J-788D01*
G01X54897Y149940D02*
X54890Y150041D01*
G01X54897Y149940D02*
X54890Y150183D01*
G01X58315Y150041D02*
X58318Y149940D01*
G01X59893D02*
X59890Y150041D01*
G01X58315Y150183D02*
X58318Y149940D01*
G01X59893D02*
X59890Y150183D01*
G01X53971Y153459D02*
Y152081D01*
G01X53998D02*
Y153459D01*
G01X54024D02*
Y152081D01*
G01X54496Y150924D02*
Y152302D01*
G01X54733Y167322D02*
Y187007D01*
G01X54890Y152302D02*
Y150041D01*
G01X55008Y153459D02*
Y152081D01*
G01X55034Y153459D02*
Y152081D01*
G01X55061D02*
Y153459D01*
G01X55205Y152302D02*
Y163877D01*
G01X55278Y153459D02*
Y152081D01*
G01X55284Y146889D02*
Y152401D01*
G01X55304Y153459D02*
Y152081D01*
G01X55349D02*
Y153459D01*
G01X55402D02*
Y152081D01*
G01X55441Y150826D02*
Y152401D01*
G01X55993Y152302D02*
Y153459D01*
G01X56070Y153188D02*
Y150826D01*
G01X56071D02*
Y149645D01*
G01X57134D02*
Y150826D01*
G01X57135D02*
Y153188D01*
G01X57193Y176536D02*
Y167322D01*
G01X57764Y153459D02*
Y150826D01*
G01X57922Y152401D02*
Y148464D01*
G01X58315Y150041D02*
Y152302D01*
G01X58355Y153459D02*
Y152081D01*
G01X58407Y153459D02*
Y152081D01*
G01X58453Y153459D02*
Y152081D01*
G01X58479D02*
Y153459D01*
G01X58552Y152302D02*
Y163877D01*
G01X58689Y150924D02*
Y152081D01*
G01X58696Y153459D02*
Y152081D01*
G01X58709Y152302D02*
Y150924D01*
G01X58723Y152081D02*
Y153459D01*
G01X58748D02*
Y152081D01*
G01X59496Y150924D02*
Y152302D01*
G01X59733Y153459D02*
Y152081D01*
G01X59759Y153459D02*
Y152081D01*
G01X59785D02*
Y153459D01*
G01X59890Y150041D02*
Y152302D01*
G01X59930D02*
Y163877D01*
G01X60002Y153459D02*
Y152081D01*
G01X60028Y153459D02*
Y152081D01*
G01X60074D02*
Y153459D01*
G01X60126D02*
Y152081D01*
G01X60284Y146889D02*
Y152401D01*
G01X60441Y150826D02*
Y152401D01*
G01X60717Y152081D02*
Y153459D01*
G01X61070Y153188D02*
Y150826D01*
G01X61071D02*
Y149645D01*
G01X62134D02*
Y150826D01*
G01X62135D02*
Y153188D01*
G01X62489Y153459D02*
Y152081D01*
G01X62764Y152401D02*
Y150826D01*
G01X62922Y152401D02*
Y146889D01*
G01X63079Y153459D02*
Y152081D01*
G01X63132Y153459D02*
Y152081D01*
G01X63178Y153459D02*
Y152081D01*
G01X63204D02*
Y153459D01*
G01X63276Y152302D02*
Y163877D01*
G01X63315Y150041D02*
Y152302D01*
G01X63420Y153459D02*
Y152081D01*
G01X63447D02*
Y153459D01*
G01X63473D02*
Y152081D01*
G01X57135Y153188D02*
X57764Y152401D01*
G01X62135Y153188D02*
X62764Y152401D01*
G01X63315Y150183D02*
X63313Y149940D01*
G01X63315Y150041D02*
X63313Y149940D01*
G01X55441Y152401D02*
X56070Y153188D01*
G01X60441Y152401D02*
X61070Y153188D01*
G01X62893Y148464D02*
X60313D01*
G01X57950D02*
X55370D01*
G01X58318Y149940D02*
X59893D01*
G01X63313D02*
X64888D01*
G01X66065Y150826D02*
X62141D01*
G01X61065D02*
X57141D01*
G01X64851Y152081D02*
X62489D01*
G01X60717D02*
X58355D01*
G01X57764Y152401D02*
X60441D01*
G01X62764D02*
X65441D01*
G01X57135Y153188D02*
X61070D01*
G01X62135D02*
X66070D01*
G01X65441Y153459D02*
X62489D01*
G01X60717D02*
X57764D01*
G01X64654Y154443D02*
X63276D01*
G01X59930D02*
X58552D01*
G01X64654Y161515D02*
X63276D01*
G01X59930D02*
X58552D01*
G01X64654Y162499D02*
X63276D01*
G01X59930D02*
X58552D01*
G01X64654Y163877D02*
X63276D01*
G01X59930D02*
X58552D01*
G01X57193Y167322D02*
X54733D01*
G01X56209Y143006D02*
X56012Y143741D01*
G01X56209Y143500D02*
X56012Y144235D01*
G01X55225D02*
Y143741D01*
G01X56012Y144235D02*
Y143741D01*
G01X59241Y144235D02*
Y143741D01*
G01X60028Y144235D02*
Y143741D01*
G01X63256Y144235D02*
Y143741D01*
G01X60225Y143006D02*
X60028Y143741D01*
G01X60225Y143500D02*
X60028Y144235D01*
G01X55225D02*
X55028Y143500D01*
G01X55225Y143741D02*
X55028Y143006D01*
G01X59241Y144235D02*
X59044Y143500D01*
G01X59241Y143741D02*
X59044Y143006D01*
G01X63256Y144235D02*
X63059Y143500D01*
G01X63256Y143741D02*
X63059Y143006D01*
G01X62430Y143464D02*
X60776D01*
G01X58414D02*
X56760D01*
G01X64044Y143741D02*
X63256D01*
G01X56012D02*
X55225D01*
G01X60028D02*
X59241D01*
G01X55225Y144235D02*
X56012D01*
G01X59241D02*
X60028D01*
G01X63256D02*
X64044D01*
G01X48315Y150041D02*
X48326Y149940D01*
G01X49901D02*
X49890Y150041D01*
G01X53315D02*
X53322Y149940D01*
G01X43315Y150183D02*
X43330Y149940D01*
G01X44905D02*
X44890Y150183D01*
G01X48315D02*
X48326Y149940D01*
G01X49901D02*
X49890Y150183D01*
G01X53315D02*
X53322Y149940D01*
G01X31485Y146889D02*
Y192952D01*
G01X31681Y192164D02*
Y174842D01*
G01Y155550D02*
Y147676D01*
G01X32764Y165944D02*
Y159645D01*
G01X32921Y152801D02*
Y147354D01*
G01X33089Y167558D02*
Y152801D01*
G01X34142Y146889D02*
Y147354D01*
G01Y152801D02*
Y192952D01*
G01X34437Y192164D02*
Y174842D01*
G01Y155550D02*
Y152801D01*
G01X34733Y153459D02*
Y152801D01*
G01X34785Y153459D02*
Y152801D01*
G01X34831Y153459D02*
Y152801D01*
G01X34857D02*
Y153459D01*
G01X34930Y152801D02*
Y163877D01*
G01X35074Y153459D02*
Y152801D01*
G01X35101D02*
Y153459D01*
G01X35126D02*
Y152801D01*
G01X36012Y186173D02*
Y174842D01*
G01X36111Y153459D02*
Y152801D01*
G01X36137Y153459D02*
Y152801D01*
G01X36163D02*
Y153459D01*
G01X36307Y152801D02*
Y163877D01*
G01X36380Y153459D02*
Y152801D01*
G01X36406Y153459D02*
Y152801D01*
G01X36452D02*
Y153459D01*
G01X36504D02*
Y152801D01*
G01X37095D02*
Y153459D01*
G01X38367Y147354D02*
Y152801D01*
G01X38867Y153459D02*
Y152081D01*
G01X39457Y153459D02*
Y152081D01*
G01X39510Y153459D02*
Y152081D01*
G01X39556Y153459D02*
Y152081D01*
G01X39581D02*
Y153459D01*
G01X39654Y152081D02*
Y163877D01*
G01X39798Y153459D02*
Y152081D01*
G01X39825D02*
Y153459D01*
G01X39851D02*
Y152081D01*
G01X40835Y153459D02*
Y152081D01*
G01X40861Y153459D02*
Y152081D01*
G01X40888D02*
Y153459D01*
G01X41032Y152081D02*
Y163877D01*
G01X41105Y153459D02*
Y152081D01*
G01X41130Y153582D02*
Y149645D01*
G01X41176Y152081D02*
Y153459D01*
G01X41229D02*
Y152081D01*
G01X41642Y152302D02*
Y150924D01*
G01X41819Y152302D02*
Y153459D01*
G01X42115Y148464D02*
Y149645D01*
G01X42134D02*
Y150826D01*
G01X42135D02*
Y153188D01*
G01X42764Y152401D02*
Y150826D01*
G01X42922Y152401D02*
Y148464D01*
G01X43315Y152302D02*
Y150041D01*
G01X43591Y153459D02*
Y152302D01*
G01X43709D02*
Y150924D01*
G01X44181Y153459D02*
Y152081D01*
G01X44234Y153459D02*
Y152081D01*
G01X44280Y153459D02*
Y152081D01*
G01X44306D02*
Y153459D01*
G01X44378Y152302D02*
Y163877D01*
G01X44496Y150924D02*
Y152302D01*
G01X44522Y153459D02*
Y152081D01*
G01X44550D02*
Y153459D01*
G01X44575D02*
Y152081D01*
G01X44890Y152302D02*
Y150041D01*
G01X45284Y146889D02*
Y152401D01*
G01X45441Y150826D02*
Y152401D01*
G01X45559Y153459D02*
Y152081D01*
G01X45585Y153459D02*
Y152081D01*
G01X45612D02*
Y153459D01*
G01X45756Y152302D02*
Y163877D01*
G01X45829Y153459D02*
Y152081D01*
G01X45855Y153459D02*
Y152081D01*
G01X45900D02*
Y153459D01*
G01X45953D02*
Y152081D01*
G01X46070Y153188D02*
Y150826D01*
G01X46071D02*
Y149645D01*
G01X46544Y152302D02*
Y153459D01*
G01X47134Y149645D02*
Y150826D01*
G01X47135D02*
Y153188D01*
G01X47764Y152401D02*
Y150826D01*
G01X47922Y152401D02*
Y148464D01*
G01X48315Y153459D02*
Y150041D01*
G01X48709Y152302D02*
Y150924D01*
G01X48906Y153459D02*
Y152081D01*
G01X48959Y153459D02*
Y152081D01*
G01X49004Y153459D02*
Y152081D01*
G01X49030D02*
Y153459D01*
G01X49103Y152302D02*
Y163877D01*
G01X49247Y153459D02*
Y152081D01*
G01X49274D02*
Y153459D01*
G01X49300D02*
Y152081D01*
G01X49496Y150924D02*
Y152302D01*
G01X49890D02*
Y150041D01*
G01X50284Y146889D02*
Y153459D01*
G01X50310D02*
Y152081D01*
G01X50337D02*
Y153459D01*
G01X50441Y150826D02*
Y152401D01*
G01X50481Y152302D02*
Y163877D01*
G01X50554Y153459D02*
Y152081D01*
G01X50579Y153459D02*
Y152081D01*
G01X50625D02*
Y153459D01*
G01X50678D02*
Y152081D01*
G01X51070Y153188D02*
Y150826D01*
G01X51071D02*
Y149645D01*
G01X51268Y152302D02*
Y153459D01*
G01X52134Y149645D02*
Y150826D01*
G01X52135D02*
Y153188D01*
G01X52764Y152401D02*
Y150826D01*
G01X52922Y152401D02*
Y148464D01*
G01X53040Y153459D02*
Y152302D01*
G01X53315D02*
Y150041D01*
G01X53630Y153459D02*
Y152081D01*
G01X53683Y153459D02*
Y152081D01*
G01X53709Y152302D02*
Y150924D01*
G01X53729Y153459D02*
Y152081D01*
G01X53755D02*
Y153459D01*
G01X53827Y152302D02*
Y163877D01*
G01X42607Y158149D02*
X49142Y151613D01*
G01X42135Y153188D02*
X42764Y152401D01*
G01X47135Y153188D02*
X47764Y152401D01*
G01X52135Y153188D02*
X52764Y152401D01*
G01X43315Y150041D02*
X43330Y149940D01*
G01X44905D02*
X44890Y150041D01*
G01X45441Y152401D02*
X46070Y153188D01*
G01X50441Y152401D02*
X51070Y153188D01*
G01X42607Y158149D02*
X36071Y151613D01*
G01X91721Y146889D02*
X31485D01*
G01X32921Y147354D02*
X38367D01*
G01X85225Y147676D02*
X38367D01*
G01X32921D02*
X31681D01*
G01X53007Y148464D02*
X50427D01*
G01X48065D02*
X45484D01*
G01X43122D02*
X42115D01*
G01X32921D02*
X31681D01*
G01X82075Y149645D02*
X41130D01*
G01X43330Y149940D02*
X44905D01*
G01X48326D02*
X49901D01*
G01X53322D02*
X54897D01*
G01X56065Y150826D02*
X52141D01*
G01X51065D02*
X47141D01*
G01X46065D02*
X42141D01*
G01X81642Y150924D02*
X41642D01*
G01X55402Y152081D02*
X53630D01*
G01X50678D02*
X48906D01*
G01X45953D02*
X44181D01*
G01X38867D02*
X41642D01*
G01Y152302D02*
X81642D01*
G01X42764Y152401D02*
X45441D01*
G01X47764D02*
X50441D01*
G01X52764D02*
X55441D01*
G01X38367Y152801D02*
X32921D01*
G01X42135Y153188D02*
X46070D01*
G01X47135D02*
X51070D01*
G01X52135D02*
X56070D01*
G01X55993Y153459D02*
X53040D01*
G01X51268D02*
X48315D01*
G01X46544D02*
X43591D01*
G01X41819D02*
X38867D01*
G01X37095D02*
X34142D01*
G01X31681Y153582D02*
X91524D01*
G01X55205Y154443D02*
X53827D01*
G01X50481D02*
X49103D01*
G01X45756D02*
X44378D01*
G01X41032D02*
X39654D01*
G01X36307D02*
X34930D01*
G01X31681Y155550D02*
X91524D01*
G01X55205Y161515D02*
X53827D01*
G01X50481D02*
X49103D01*
G01X45756D02*
X44378D01*
G01X41032D02*
X39654D01*
G01X36307D02*
X34930D01*
G01X55205Y162499D02*
X53827D01*
G01X50481D02*
X49103D01*
G01X45756D02*
X44378D01*
G01X41032D02*
X39654D01*
G01X36307D02*
X34930D01*
G01X55205Y163877D02*
X53827D01*
G01X50481D02*
X49103D01*
G01X45756D02*
X44378D01*
G01X41032D02*
X39654D01*
G01X36307D02*
X34930D01*
G01X89063Y174645D02*
X34142D01*
G01X91524Y174842D02*
X31681D01*
G01X40157Y147527D02*
G03X45057I2450J4086D01*
G01X46692Y149163D02*
G03Y154063I-4085J2450D01*
G01X45057Y155699D02*
G03X40157I-2450J-4086D01*
G01X38521Y154063D02*
G03Y149163I4086J-2450D01*
G01X32764Y165944D02*
G03X31977Y166731I-787J0D01*
G01Y158857D02*
G03X32764Y159645I0J787D01*
G01X48178Y143006D02*
X47981Y143741D01*
G01X48178Y143500D02*
X47981Y144235D01*
G01X52193Y143006D02*
X51996Y143741D01*
G01X52193Y143500D02*
X51996Y144235D01*
G01X47193D02*
Y143741D01*
G01X47981Y144235D02*
Y143741D01*
G01X51209Y144235D02*
Y143741D01*
G01X51996Y144235D02*
Y143741D01*
G01X36071Y151613D02*
X42607Y145078D01*
G01X47193Y144235D02*
X46996Y143500D01*
G01X47193Y143741D02*
X46996Y143006D01*
G01X51209Y144235D02*
X51012Y143500D01*
G01X51209Y143741D02*
X51012Y143006D01*
G01X54398Y143464D02*
X52744D01*
G01X50382D02*
X48729D01*
G01X46367D02*
X35422D01*
G01X51996Y143741D02*
X51209D01*
G01X47981D02*
X47193D01*
G01X37981Y144133D02*
X85225D01*
G01X47193Y144235D02*
X47981D01*
G01X51209D02*
X51996D01*
G01X49142Y151613D02*
X42607Y145078D01*
G01X48985Y151613D02*
G03I-6378J0D01*
G01X55803Y197775D02*
X55804Y197755D01*
X55807Y197734D01*
X55813Y197713D01*
X55821Y197692D01*
X55830Y197672D01*
X55843Y197651D01*
G01X55803Y198457D02*
X55804Y198436D01*
X55807Y198416D01*
X55813Y198395D01*
X55821Y198374D01*
X55830Y198354D01*
X55843Y198333D01*
G01X54103Y186908D02*
Y189442D01*
G01X54137Y189506D02*
Y188378D01*
G01X54201Y188810D02*
Y189939D01*
G01X54300Y186908D02*
Y188286D01*
G01X54363Y189694D02*
Y188566D01*
G01X54398Y189826D02*
Y188630D01*
G01X54496Y188286D02*
Y186908D01*
G01X54792Y188286D02*
Y186908D01*
G01X55284D02*
Y188286D01*
G01X55803Y197775D02*
Y198457D01*
G01X55843Y198333D02*
Y197651D01*
G01X55914Y184905D02*
Y186283D01*
G01X56406Y184905D02*
Y186283D01*
G01X56485Y194656D02*
Y193869D01*
G01X56591Y198169D02*
Y198851D01*
G01X56800Y184905D02*
Y186283D01*
G01X57095D02*
Y184905D01*
G01X57491Y194656D02*
Y193869D01*
G01X57618Y193753D02*
Y194310D01*
G01X57684Y194869D02*
Y195551D01*
G01X58079Y186283D02*
Y184905D01*
G01X58374Y186283D02*
Y184905D01*
G01X58431Y195281D02*
Y194656D01*
G01X58768Y186283D02*
Y184905D01*
G01X59260Y186283D02*
Y184905D01*
G01X59634Y198759D02*
Y196791D01*
G01Y191377D02*
Y190590D01*
G01X60225Y193869D02*
Y190590D01*
G01Y195281D02*
Y194656D01*
G01X60815Y191377D02*
Y190590D01*
G01X62390D02*
Y191377D01*
G01X62981Y193869D02*
Y190590D01*
G01Y195281D02*
Y194656D01*
G01X57684Y194869D02*
X57717Y194827D01*
X57762Y194786D01*
X57815Y194747D01*
X57876Y194714D01*
X57946Y194683D01*
X58023Y194656D01*
G01X55843Y197651D02*
X57684Y194869D01*
G01X55843Y198333D02*
X57684Y195551D01*
G01X54398Y189758D02*
X54397Y189747D01*
X54394Y189736D01*
X54389Y189725D01*
X54382Y189714D01*
X54374Y189705D01*
X54363Y189694D01*
G01X54398Y188630D02*
X54397Y188619D01*
X54394Y188607D01*
X54389Y188596D01*
X54382Y188586D01*
X54374Y188576D01*
X54363Y188566D01*
G01X57684Y195551D02*
X57750Y195477D01*
X57847Y195410D01*
X57970Y195356D01*
X58110Y195315D01*
X58267Y195290D01*
X58431Y195281D01*
G01X57491Y193475D02*
X57573Y193842D01*
X57613Y194171D01*
Y194430D01*
X57572Y194598D01*
X57491Y194656D01*
G01Y193475D02*
X57572Y193596D01*
X57613Y193707D01*
Y193794D01*
X57572Y193850D01*
X57491Y193869D01*
G01X54137Y189506D02*
X54128Y189497D01*
X54119Y189487D01*
X54112Y189476D01*
X54107Y189465D01*
X54104Y189454D01*
X54103Y189442D01*
G01X54137Y188378D02*
X54128Y188368D01*
X54119Y188358D01*
X54112Y188347D01*
X54107Y188336D01*
X54104Y188325D01*
X54103Y188314D01*
G01X54363Y189694D02*
X54137Y189506D01*
G01X54363Y188566D02*
X54137Y188378D01*
G01X56701Y183921D02*
X58473D01*
G01X55914Y184905D02*
X59260D01*
G01X55914Y186283D02*
X59260D01*
G01X54733Y187007D02*
X57193D01*
G01X59634Y190590D02*
X63571D01*
G01X59634Y191377D02*
X63571D01*
G01X60225Y193214D02*
X62981D01*
G01X65715Y193475D02*
X57491D01*
G01X58431Y195281D02*
X60225D01*
G01X62981D02*
X64774D01*
G01X63571Y196791D02*
X59634D01*
G01X63571Y197184D02*
X59634D01*
G01Y197578D02*
X63571D01*
G01Y197972D02*
X59634D01*
G01X66615Y198169D02*
X56591D01*
G01X59634Y198548D02*
X63571D01*
G01Y198759D02*
X59634D01*
G01X56591Y198851D02*
X66615D01*
G01X59634Y196791D02*
X59481Y196798D01*
X59334Y196820D01*
X59198Y196856D01*
X59078Y196906D01*
X58980Y196966D01*
X58907Y197033D01*
X58863Y197106D01*
X58847Y197184D01*
X58862Y197261D01*
X58906Y197334D01*
X58978Y197402D01*
X59078Y197463D01*
X59196Y197512D01*
X59332Y197548D01*
X59479Y197570D01*
X59634Y197578D01*
G01Y197184D02*
X59369Y197197D01*
X59115Y197236D01*
X58880Y197298D01*
X58670Y197384D01*
X58501Y197487D01*
X58375Y197604D01*
X58297Y197732D01*
X58270Y197866D01*
X58296Y197999D01*
X58373Y198126D01*
X58498Y198243D01*
X58670Y198349D01*
X58876Y198433D01*
X59110Y198496D01*
X59365Y198535D01*
X59634Y198548D01*
G01X54201Y188810D02*
X54239Y188808D01*
X54276Y188802D01*
X54310Y188792D01*
X54341Y188777D01*
X54365Y188760D01*
X54383Y188741D01*
X54394Y188720D01*
X54398Y188697D01*
G01X54201Y189939D02*
X54239Y189937D01*
X54276Y189930D01*
X54310Y189920D01*
X54341Y189906D01*
X54365Y189889D01*
X54383Y189869D01*
X54394Y189849D01*
X54398Y189826D01*
G01X56591Y198169D02*
X56437Y198161D01*
X56290Y198139D01*
X56155Y198103D01*
X56033Y198053D01*
X55936Y197994D01*
X55863Y197926D01*
X55819Y197853D01*
X55803Y197775D01*
G01X56591Y198851D02*
X56437Y198843D01*
X56290Y198821D01*
X56155Y198785D01*
X56033Y198735D01*
X55936Y198676D01*
X55863Y198608D01*
X55819Y198535D01*
X55803Y198457D01*
G01X59634Y197972D02*
X59437Y197947D01*
X59238Y197865D01*
X59046Y197708D01*
X58901Y197471D01*
X58847Y197184D01*
G01X59634Y198759D02*
X59311Y198726D01*
X58987Y198620D01*
X58655Y198418D01*
X58348Y198093D01*
G01X56485Y192912D02*
G03X57491Y193475I-1J1181D01*
G01X56701Y176908D02*
Y186283D01*
G01X57193Y187007D02*
Y179049D01*
G01X58473Y186283D02*
Y176908D01*
G01X68676Y176536D02*
X57193D01*
G01X58473Y176908D02*
X56701D01*
G01Y178286D02*
X58473D01*
G01X57193Y179049D02*
X68676D01*
G01X56701Y179271D02*
X58473D01*
G01X67752Y177597D02*
G03I-2153J0D01*
G01X59760D02*
G03I-2153J0D01*
G01X58788D02*
G03I-1181J0D01*
G01X37134Y188314D02*
X37133Y188325D01*
X37130Y188336D01*
X37126Y188347D01*
X37119Y188358D01*
X37110Y188368D01*
X37100Y188378D01*
G01X37134Y189442D02*
X37133Y189453D01*
X37130Y189465D01*
X37126Y189476D01*
X37119Y189486D01*
X37110Y189496D01*
X37100Y189506D01*
G01X45126Y188314D02*
Y188325D01*
X45122Y188336D01*
X45118Y188347D01*
X45111Y188358D01*
X45102Y188368D01*
X45092Y188378D01*
G01X45126Y189442D02*
Y189453D01*
X45122Y189465D01*
X45118Y189476D01*
X45111Y189486D01*
X45102Y189496D01*
X45092Y189506D01*
G01X53119Y188314D02*
X53118Y188325D01*
X53115Y188336D01*
X53110Y188347D01*
X53103Y188358D01*
X53094Y188368D01*
X53084Y188378D01*
G01X53119Y189442D02*
X53118Y189453D01*
X53115Y189465D01*
X53110Y189476D01*
X53103Y189486D01*
X53094Y189496D01*
X53084Y189506D01*
G01X34536Y204723D02*
Y301180D01*
G01X34879Y194310D02*
Y193753D01*
G01X35006Y193869D02*
Y194656D01*
G01X35953Y188286D02*
Y186908D01*
G01X36012Y192164D02*
Y189022D01*
G01Y193869D02*
Y194656D01*
G01X36445Y188286D02*
Y186908D01*
G01X36741Y188286D02*
Y186908D01*
G01X36839Y189826D02*
Y188630D01*
G01X36874Y188566D02*
Y189694D01*
G01X36937Y188286D02*
Y186908D01*
G01X37036Y189939D02*
Y188810D01*
G01X37100Y188378D02*
Y189506D01*
G01X37134Y186908D02*
Y189442D01*
G01X38119Y186908D02*
Y189442D01*
G01X38153Y189506D02*
Y188378D01*
G01X38217Y188810D02*
Y189939D01*
G01X38315Y186908D02*
Y188286D01*
G01X38379Y189694D02*
Y188566D01*
G01X38414Y189826D02*
Y188630D01*
G01X38512Y188286D02*
Y186908D01*
G01X38807Y188286D02*
Y186908D01*
G01X39300D02*
Y188286D01*
G01X39930Y184905D02*
Y186283D01*
G01X40422Y184905D02*
Y186283D01*
G01X40815Y184905D02*
Y186283D01*
G01X41111D02*
Y184905D01*
G01X42095Y186283D02*
Y184905D01*
G01X42390Y186283D02*
Y184905D01*
G01X42784Y186283D02*
Y184905D01*
G01X43276Y186283D02*
Y184905D01*
G01X43945Y188286D02*
Y186908D01*
G01X44437Y188286D02*
Y186908D01*
G01X44733Y188286D02*
Y186908D01*
G01X44831Y189826D02*
Y188630D01*
G01X44866Y188566D02*
Y189694D01*
G01X44930Y188286D02*
Y186908D01*
G01X45028Y189939D02*
Y188810D01*
G01X45092Y188378D02*
Y189506D01*
G01X45126Y186908D02*
Y189442D01*
G01X46111Y186908D02*
Y189442D01*
G01X46145Y189506D02*
Y188378D01*
G01X46209Y188810D02*
Y189939D01*
G01X46307Y186908D02*
Y188286D01*
G01X46371Y189694D02*
Y188566D01*
G01X46406Y189826D02*
Y188630D01*
G01X46504Y188286D02*
Y186908D01*
G01X46800Y188286D02*
Y186908D01*
G01X47292D02*
Y188286D01*
G01X47922Y184905D02*
Y186283D01*
G01X48414Y184905D02*
Y186283D01*
G01X48807Y184905D02*
Y186283D01*
G01X49103D02*
Y184905D01*
G01X50087Y186283D02*
Y184905D01*
G01X50382Y186283D02*
Y184905D01*
G01X50776Y186283D02*
Y184905D01*
G01X51268Y186283D02*
Y184905D01*
G01X51937Y188286D02*
Y186908D01*
G01X52430Y188286D02*
Y186908D01*
G01X52725Y188286D02*
Y186908D01*
G01X52823Y189826D02*
Y188630D01*
G01X52858Y188566D02*
Y189694D01*
G01X52922Y188286D02*
Y186908D01*
G01X53020Y189939D02*
Y188810D01*
G01X53084Y188378D02*
Y189506D01*
G01X53119Y186908D02*
Y189442D01*
G01X38414Y189758D02*
X38413Y189747D01*
X38410Y189736D01*
X38405Y189725D01*
X38398Y189714D01*
X38390Y189705D01*
X38379Y189694D01*
G01X38414Y188630D02*
X38413Y188619D01*
X38410Y188607D01*
X38405Y188596D01*
X38398Y188586D01*
X38390Y188576D01*
X38379Y188566D01*
G01X46406Y189758D02*
X46405Y189747D01*
X46402Y189736D01*
X46397Y189725D01*
X46390Y189714D01*
X46382Y189705D01*
X46371Y189694D01*
G01X46406Y188630D02*
X46405Y188619D01*
X46402Y188607D01*
X46397Y188596D01*
X46390Y188586D01*
X46382Y188576D01*
X46371Y188566D01*
G01X36839Y189826D02*
X36843Y189848D01*
X36854Y189869D01*
X36872Y189889D01*
X36897Y189906D01*
X36926Y189920D01*
X36960Y189930D01*
X36997Y189937D01*
X37036Y189939D01*
G01X36839Y188697D02*
X36843Y188719D01*
X36854Y188740D01*
X36872Y188760D01*
X36897Y188777D01*
X36926Y188791D01*
X36960Y188802D01*
X36997Y188808D01*
X37036Y188810D01*
G01X44831Y189826D02*
X44835Y189848D01*
X44846Y189869D01*
X44864Y189889D01*
X44889Y189906D01*
X44919Y189920D01*
X44952Y189930D01*
X44989Y189937D01*
X45028Y189939D01*
G01X44831Y188697D02*
X44835Y188719D01*
X44846Y188740D01*
X44864Y188760D01*
X44889Y188777D01*
X44919Y188791D01*
X44952Y188802D01*
X44989Y188808D01*
X45028Y188810D01*
G01X52823Y189826D02*
X52827Y189848D01*
X52838Y189869D01*
X52856Y189889D01*
X52881Y189906D01*
X52911Y189920D01*
X52944Y189930D01*
X52981Y189937D01*
X53020Y189939D01*
G01X52823Y188697D02*
X52827Y188719D01*
X52838Y188740D01*
X52856Y188760D01*
X52881Y188777D01*
X52911Y188791D01*
X52944Y188802D01*
X52981Y188808D01*
X53020Y188810D01*
G01X36012Y186173D02*
X35788Y186340D01*
X35594Y186539D01*
X35433Y186769D01*
X35310Y187030D01*
X35232Y187313D01*
X35207Y187598D01*
X35233Y187882D01*
X35310Y188165D01*
X35433Y188426D01*
X35594Y188656D01*
X35788Y188855D01*
X36012Y189022D01*
G01X37100Y188378D02*
X36874Y188566D01*
G01X37100Y189506D02*
X36874Y189694D01*
G01X45092Y188378D02*
X44866Y188566D01*
G01X45092Y189506D02*
X44866Y189694D01*
G01X53084Y188378D02*
X52858Y188566D01*
G01X53084Y189506D02*
X52858Y189694D01*
G01X36874Y188566D02*
X36864Y188575D01*
X36855Y188585D01*
X36848Y188596D01*
X36843Y188607D01*
X36840Y188618D01*
X36839Y188630D01*
G01X36874Y189694D02*
X36864Y189704D01*
X36855Y189714D01*
X36848Y189725D01*
X36843Y189736D01*
X36840Y189747D01*
X36839Y189758D01*
G01X44866Y188566D02*
X44856Y188575D01*
X44847Y188585D01*
X44840Y188596D01*
X44835Y188607D01*
X44832Y188618D01*
X44831Y188630D01*
G01X44866Y189694D02*
X44856Y189704D01*
X44847Y189714D01*
X44840Y189725D01*
X44835Y189736D01*
X44832Y189747D01*
X44831Y189758D01*
G01X52858Y188566D02*
X52848Y188575D01*
X52839Y188585D01*
X52832Y188596D01*
X52827Y188607D01*
X52824Y188618D01*
X52823Y188630D01*
G01X52858Y189694D02*
X52848Y189704D01*
X52839Y189714D01*
X52832Y189725D01*
X52827Y189736D01*
X52824Y189747D01*
X52823Y189758D01*
G01X38153Y189506D02*
X38143Y189497D01*
X38134Y189487D01*
X38128Y189476D01*
X38122Y189465D01*
X38120Y189454D01*
X38119Y189442D01*
G01X38153Y188378D02*
X38143Y188368D01*
X38134Y188358D01*
X38128Y188347D01*
X38122Y188336D01*
X38120Y188325D01*
X38119Y188314D01*
G01X46145Y189506D02*
X46135Y189497D01*
X46126Y189487D01*
X46120Y189476D01*
X46115Y189465D01*
X46112Y189454D01*
X46111Y189442D01*
G01X46145Y188378D02*
X46135Y188368D01*
X46126Y188358D01*
X46120Y188347D01*
X46115Y188336D01*
X46112Y188325D01*
X46111Y188314D01*
G01X38379Y189694D02*
X38153Y189506D01*
G01X38379Y188566D02*
X38153Y188378D01*
G01X46371Y189694D02*
X46145Y189506D01*
G01X46371Y188566D02*
X46145Y188378D01*
G01X40717Y183921D02*
X42489D01*
G01X48709D02*
X50481D01*
G01X39930Y184905D02*
X43276D01*
G01X47922D02*
X51268D01*
G01X39930Y186283D02*
X43276D01*
G01X47922D02*
X51268D01*
G01X35953Y186908D02*
X39300D01*
G01X43945D02*
X47292D01*
G01X51937D02*
X55284D01*
G01X37134Y187158D02*
X38119D01*
G01X45126D02*
X46111D01*
G01X53119D02*
X54103D01*
G01X35953Y188286D02*
X39300D01*
G01X43945D02*
X47292D01*
G01X51937D02*
X55284D01*
G01X54201Y188810D02*
X53020D01*
G01X46209D02*
X45028D01*
G01X38217D02*
X37036D01*
G01Y189939D02*
X38217D01*
G01X45028D02*
X46209D01*
G01X53020D02*
X54201D01*
G01X56485Y192912D02*
X36012D01*
G01X38217Y188810D02*
X38255Y188808D01*
X38292Y188802D01*
X38326Y188792D01*
X38356Y188777D01*
X38381Y188760D01*
X38399Y188741D01*
X38410Y188720D01*
X38414Y188697D01*
G01X46209Y188810D02*
X46247Y188808D01*
X46284Y188802D01*
X46318Y188792D01*
X46348Y188777D01*
X46373Y188760D01*
X46391Y188741D01*
X46402Y188720D01*
X46406Y188697D01*
G01X38217Y189939D02*
X38255Y189937D01*
X38292Y189930D01*
X38326Y189920D01*
X38356Y189906D01*
X38381Y189889D01*
X38399Y189869D01*
X38410Y189849D01*
X38414Y189826D01*
G01X46209Y189939D02*
X46247Y189937D01*
X46284Y189930D01*
X46318Y189920D01*
X46348Y189906D01*
X46373Y189889D01*
X46391Y189869D01*
X46402Y189849D01*
X46406Y189826D01*
G01X35006Y194656D02*
X34924Y194597D01*
X34884Y194430D01*
Y194170D01*
X34924Y193842D01*
X35006Y193475D01*
G01X34536Y204723D02*
X100284D01*
G01X35006Y193869D02*
X34925Y193849D01*
X34884Y193793D01*
Y193706D01*
X34925Y193595D01*
X35006Y193475D01*
G01X36012Y186173D02*
G03Y189022I1614J1424D01*
G01X47772Y187597D02*
G03I-2153J0D01*
G01X55764D02*
G03I-2153J0D01*
G01X38807D02*
G03I-1181J0D01*
G01X46800D02*
G03I-1181J0D01*
G01X54792D02*
G03I-1181J0D01*
G01X35006Y193475D02*
G03X36012Y192912I1006J618D01*
G01X40717Y176908D02*
Y186283D01*
G01X42489D02*
Y176908D01*
G01X48709D02*
Y186283D01*
G01X50481D02*
Y176908D01*
G01D02*
X48709D01*
G01X42489D02*
X40717D01*
G01Y178286D02*
X42489D01*
G01X48709D02*
X50481D01*
G01X40717Y179271D02*
X42489D01*
G01X48709D02*
X50481D01*
G01X43776Y177597D02*
G03I-2154J0D01*
G01X42804D02*
G03I-1182J0D01*
G01X51768D02*
G03I-2153J0D01*
G01X50796D02*
G03I-1181J0D01*
G01X36268Y219684D02*
Y278739D01*
G01X175244Y219684D02*
X36268D01*
G01X69142Y237400D02*
G03I-14764J0D01*
G01X67174D02*
G03I-12796J0D01*
G01X62646D02*
G03I-8268J0D01*
G01D02*
G03I-8268J0D01*
G01X55032Y249294D02*
Y249640D01*
G01X55274Y249245D02*
Y249690D01*
G01X55661Y248306D02*
Y249888D01*
G01X55903D02*
Y249739D01*
G01Y249542D02*
Y248306D01*
G01X56435D02*
Y249492D01*
G01X56678D02*
Y248306D01*
G01X57210D02*
Y249492D01*
G01X57452D02*
Y248306D01*
G01X57839D02*
Y249888D01*
G01X58081D02*
Y249739D01*
G01Y249542D02*
Y248306D01*
G01X58613D02*
Y249492D01*
G01X58855D02*
Y248306D01*
G01X59387D02*
Y249492D01*
G01X59630D02*
Y248306D01*
G01X54984Y249937D02*
X54790Y250233D01*
G01X55177Y250085D02*
X55080Y250283D01*
G01X56435Y249492D02*
X56387Y249591D01*
G01X57210Y249492D02*
X57161Y249591D01*
G01X58613Y249492D02*
X58565Y249591D01*
G01X59387Y249492D02*
X59339Y249591D01*
G01X57355Y249739D02*
X57452Y249492D01*
G01X59533Y249739D02*
X59630Y249492D01*
G01X55226Y249937D02*
X55177Y250085D01*
G01X55274Y249690D02*
X55226Y249937D01*
G01X55032Y249640D02*
X54984Y249937D01*
G01Y248998D02*
X55032Y249294D01*
G01X55226Y248998D02*
X55274Y249245D01*
G01X55080Y250283D02*
X54935Y250431D01*
G01X56387Y249591D02*
X56339Y249640D01*
G01X56484Y249838D02*
X56629Y249690D01*
G01X57161Y249591D02*
X57113Y249640D01*
G01X57258Y249838D02*
X57355Y249739D01*
G01X58565Y249591D02*
X58517Y249640D01*
G01X58661Y249838D02*
X58807Y249690D01*
G01X59339Y249591D02*
X59291Y249640D01*
G01X59436Y249838D02*
X59533Y249739D01*
G01X55177Y248850D02*
X55226Y248998D01*
G01X55080Y248652D02*
X55177Y248850D01*
G01X56726Y249591D02*
X56678Y249492D01*
G01X58904Y249591D02*
X58855Y249492D01*
G01X54935Y250431D02*
X54693Y250579D01*
G01X54016Y248701D02*
X54161Y248603D01*
G01X54790Y250233D02*
X54645Y250332D01*
G01X54790Y248701D02*
X54984Y248998D01*
G01X56339Y249640D02*
X56242Y249690D01*
G01X57113Y249640D02*
X57016Y249690D01*
G01X58517Y249640D02*
X58420Y249690D01*
G01X59291Y249640D02*
X59194Y249690D01*
G01X56339Y249888D02*
X56484Y249838D01*
G01X57113Y249888D02*
X57258Y249838D01*
G01X58517Y249888D02*
X58661Y249838D01*
G01X59291Y249888D02*
X59436Y249838D01*
G01X55903Y249739D02*
X56000Y249838D01*
G01Y249640D02*
X55903Y249542D01*
G01X54935Y248504D02*
X55080Y248652D01*
G01X56629Y249690D02*
X56774Y249838D01*
G01Y249640D02*
X56726Y249591D01*
G01X58081Y249739D02*
X58178Y249838D01*
G01Y249640D02*
X58081Y249542D01*
G01X58807Y249690D02*
X58952Y249838D01*
G01Y249640D02*
X58904Y249591D01*
G01X54113Y248355D02*
X54403Y248306D01*
G01X54161Y248603D02*
X54403Y248553D01*
G01X54645Y250332D02*
X54403Y250382D01*
G01X54693Y250579D02*
X54403Y250629D01*
G01X54161Y250332D02*
X54016Y250233D01*
G01X54645Y248603D02*
X54790Y248701D01*
G01X54693Y248355D02*
X54935Y248504D01*
G01X55903Y248306D02*
X55661D01*
G01X57452D02*
X57210D01*
G01X56678D02*
X56435D01*
G01X58081D02*
X57839D01*
G01X59630D02*
X59387D01*
G01X58855D02*
X58613D01*
G01X57016Y249690D02*
X56871D01*
G01X56242D02*
X56145D01*
G01X59194D02*
X59049D01*
G01X58420D02*
X58323D01*
G01X55661Y249888D02*
X55903D01*
G01X56145D02*
X56339D01*
G01X56919D02*
X57113D01*
G01X57839D02*
X58081D01*
G01X58323D02*
X58517D01*
G01X59097D02*
X59291D01*
G01X56871Y249690D02*
X56774Y249640D01*
G01X59049Y249690D02*
X58952Y249640D01*
G01X54403Y248306D02*
X54693Y248355D01*
G01X54403Y250629D02*
X54113Y250579D01*
G01X56000Y249838D02*
X56145Y249888D01*
G01Y249690D02*
X56000Y249640D01*
G01X56774Y249838D02*
X56919Y249888D01*
G01X58178Y249838D02*
X58323Y249888D01*
G01Y249690D02*
X58178Y249640D01*
G01X58952Y249838D02*
X59097Y249888D01*
G01X54403Y248553D02*
X54645Y248603D01*
G01X54403Y250382D02*
X54161Y250332D01*
G01X50048Y248306D02*
Y250629D01*
G01X50338D02*
Y249690D01*
G01Y249393D02*
Y248306D01*
G01X51693D02*
Y249393D01*
G01Y249690D02*
Y250629D01*
G01X51983D02*
Y248306D01*
G01X52370Y249097D02*
Y249294D01*
G01Y249690D02*
Y249888D01*
G01X53145D02*
Y249690D01*
G01Y249294D02*
Y249097D01*
G01X53532Y249690D02*
Y249245D01*
G01X53774Y249640D02*
Y249294D01*
G01X53822Y248998D02*
X54016Y248701D01*
G01X53629Y248850D02*
X53726Y248652D01*
G01X53580Y248998D02*
X53629Y248850D01*
G01X53532Y249245D02*
X53580Y248998D01*
G01X53774Y249294D02*
X53822Y248998D01*
G01Y249937D02*
X53774Y249640D01*
G01X53580Y249937D02*
X53532Y249690D01*
G01X53726Y248652D02*
X53871Y248504D01*
G01X53629Y250085D02*
X53580Y249937D01*
G01X53726Y250283D02*
X53629Y250085D01*
G01X53871Y248504D02*
X54113Y248355D01*
G01X54016Y250233D02*
X53822Y249937D01*
G01X53871Y250431D02*
X53726Y250283D01*
G01X54113Y250579D02*
X53871Y250431D01*
G01X51983Y248306D02*
X51693D01*
G01X50338D02*
X50048D01*
G01X53145Y249097D02*
X52370D01*
G01Y249294D02*
X53145D01*
G01X51693Y249393D02*
X50338D01*
G01X53145Y249690D02*
X52370D01*
G01X50338D02*
X51693D01*
G01X52370Y249888D02*
X53145D01*
G01X50048Y250629D02*
X50338D01*
G01X51693D02*
X51983D01*
G01X36268Y278739D02*
X175244D01*
G01X54447Y342824D02*
Y348599D01*
G01X38369Y342824D02*
Y351486D01*
X42267D01*
G01X50062Y344990D02*
X49087Y343546D01*
X48113Y342824D01*
X47139Y343546D01*
X46164Y344990D01*
Y346433D01*
X47139Y347877D01*
X48113Y348599D01*
X49087Y347877D01*
X50062Y346433D01*
Y344990D01*
G01X54447Y347155D02*
X55421Y348599D01*
X56396D01*
X56883Y347877D01*
G01X38369Y347155D02*
X40805D01*
G01X46850Y801180D02*
G03I-7480J0D01*
G01D02*
G03I-7480J0D01*
G01X71500Y-1129166D02*
X72926D01*
G01X70074Y-1125364D02*
X71500Y-1124413D01*
X72926D01*
X74352Y-1125364D01*
X75065Y-1126314D01*
Y-1127265D01*
X74352Y-1128215D01*
X72926Y-1129166D01*
X74352Y-1130117D01*
X75065Y-1131067D01*
X75778Y-1132018D01*
Y-1132968D01*
G01D02*
X74352Y-1134870D01*
X72926Y-1135820D01*
X71500D01*
X70074Y-1134870D01*
X69361Y-1133919D01*
G01X96232Y-792136D02*
X97207D01*
G01X99156Y-795023D02*
X98181Y-796467D01*
X97207Y-797188D01*
X96232D01*
X95258Y-796467D01*
X94770Y-795745D01*
G01X95258Y-789249D02*
X96232Y-788527D01*
X97207D01*
X98181Y-789249D01*
X98668Y-789971D01*
Y-790692D01*
X98181Y-791414D01*
X97207Y-792136D01*
X98181Y-792858D01*
G01X198780Y-799354D02*
X84160D01*
G01X95859Y-179799D02*
X91962D01*
Y-171137D01*
X95859D01*
G01X91962Y-175468D02*
X94398D01*
G01X80269Y-172581D02*
X79781Y-171859D01*
X78807Y-171137D01*
X77833D01*
X76858Y-171859D01*
X76371Y-172581D01*
Y-173303D01*
X76858Y-174025D01*
X79781Y-176190D01*
X80269Y-176912D01*
Y-178355D01*
X79781Y-179077D01*
X78807Y-179799D01*
X77833D01*
X76858Y-179077D01*
G01D02*
X75884Y-177633D01*
G01X88064Y-179799D02*
X84167D01*
Y-171137D01*
X88064D01*
G01X84167Y-175468D02*
X86602D01*
G01X94165Y47305D02*
X93191Y45862D01*
X92217Y45140D01*
X91242Y45862D01*
X90268Y47305D01*
Y48749D01*
X91242Y50192D01*
X92217Y50914D01*
X93191Y50192D01*
X94165Y48749D01*
Y47305D01*
G01X67369Y45140D02*
Y50914D01*
G01Y49471D02*
X68343Y50914D01*
X69318D01*
X70292Y49471D01*
Y45140D01*
G01X78575Y47305D02*
X77600Y45862D01*
X76626Y45140D01*
X75652Y45862D01*
X74677Y47305D01*
Y48749D01*
X75652Y50192D01*
X76626Y50914D01*
X77600Y50192D01*
X78575Y48749D01*
G01Y50914D02*
Y44418D01*
X78087Y42974D01*
X77600Y42253D01*
X75652D01*
X75164Y42974D01*
G01X88063Y100393D02*
Y99605D01*
G01X88276Y100393D02*
Y99605D01*
G01X88374Y120117D02*
Y100432D01*
G01X89063Y99605D02*
Y100103D01*
G01X89144Y111210D02*
Y104983D01*
G01X90117Y103385D02*
Y167558D01*
G01X90441Y104983D02*
Y103936D01*
G01X94211Y104983D02*
Y111210D01*
G01X94378Y194656D02*
Y100432D01*
G01X94772Y142433D02*
Y101968D01*
G01X95166Y101219D02*
Y194093D01*
G01X95559Y193081D02*
Y101180D01*
G01X96347D02*
Y193081D01*
G01X89600Y133009D02*
X88389Y100650D01*
G01X94487Y100421D02*
X95559Y129090D01*
G01X93670Y99664D02*
X89146Y99834D01*
G01X94270Y99908D02*
X89063Y100103D01*
G01X94209Y100432D02*
X88389Y100650D01*
G01X94209Y100432D02*
X94487Y100421D01*
G01D02*
X94364Y100431D01*
G01X94772Y100393D02*
X96136D01*
G01X96347Y101180D02*
X95559D01*
G01X93985D02*
X89063D01*
G01X95559Y101968D02*
X96347D01*
G01Y102361D02*
X95559D01*
G01X91229Y103149D02*
X96347D01*
G01X89144Y104983D02*
X94211D01*
G01X89063Y100103D02*
X88858Y100082D01*
X88668Y100018D01*
G01X95166Y101219D02*
X94378Y100432D01*
G01X93670Y99664D02*
G03X94487Y100421I30J787D01*
G01X88389Y100650D02*
G03X89146Y99834I786J-30D01*
G01X89063Y101180D02*
G03X88276Y100393I0J-787D01*
G01X94772Y99605D02*
G03X96347Y101180I0J1575D01*
G01X94772Y100393D02*
G03X95559Y101180I0J787D01*
G01X93985D02*
G03X94772Y101968I0J787D01*
G01X90441Y103936D02*
G03X91229Y103149I787J0D01*
G01X64437Y135965D02*
Y107468D01*
G01X74004Y101810D02*
X75382Y100432D01*
G01X82813Y100826D02*
X83207Y100432D01*
G01X85038Y100826D02*
X85431Y100432D01*
G01X85225Y101219D02*
X86012Y100432D01*
G01X87882D02*
X87095Y101219D01*
G01X84514Y110007D02*
X86119Y100906D01*
G01X86894Y101043D02*
X85289Y110144D01*
G01X64792Y104960D02*
Y125038D01*
G01X66445Y104960D02*
Y125038D01*
G01X66878Y107469D02*
Y135965D01*
G01X68453D02*
Y107468D01*
G01X68807Y104960D02*
Y125038D01*
G01X69575Y100432D02*
Y107519D01*
G01X70461Y125038D02*
Y104960D01*
G01X70894Y135965D02*
Y107469D01*
G01X71445Y100786D02*
Y99605D01*
G01X72233D02*
Y100393D01*
G01X72469Y107468D02*
Y135965D01*
G01X72823Y104960D02*
Y125038D01*
G01X74004Y144133D02*
Y101810D01*
G01X74477Y104960D02*
Y125038D01*
G01X74595Y99605D02*
Y100393D01*
G01X74910Y135965D02*
Y107469D01*
G01X75382Y100393D02*
Y99605D01*
G01X76170D02*
Y100393D01*
G01X76485Y107468D02*
Y135965D01*
G01X76839Y104960D02*
Y125038D01*
G01X77646Y100432D02*
Y122086D01*
G01X77754Y100747D02*
Y100432D01*
G01X77833Y100826D02*
Y124054D01*
G01X79329Y100432D02*
Y106731D01*
G01X80057Y107125D02*
Y100432D01*
G01X82479Y101548D02*
Y114044D01*
G01X82813Y122086D02*
Y100826D01*
G01X85038Y124054D02*
Y100826D01*
G01X85225Y100639D02*
Y144133D01*
G01X85422Y100393D02*
Y99605D01*
G01X86209D02*
Y103385D01*
G01X86996Y100393D02*
Y99605D01*
G01X87095Y117991D02*
Y101219D01*
G01X87669Y100393D02*
Y99605D01*
G01X77833Y100826D02*
X85038D01*
G01X85225Y101145D02*
X85299D01*
G01X71340Y101180D02*
X89063D01*
G01X85038Y101546D02*
X82479D01*
G01X69575Y101810D02*
X77646D01*
G01X85038Y102334D02*
X82479D01*
G01X85038Y102432D02*
X82479D01*
G01X85038Y102794D02*
X82813D01*
G01X85038Y102826D02*
X82479D01*
G01X85038Y103145D02*
X82813D01*
G01X82479Y103318D02*
X85038D01*
G01Y103664D02*
X82813D01*
G01X85038Y103975D02*
X82813D01*
G01X76839Y104960D02*
X74477D01*
G01X72823D02*
X70461D01*
G01X68807D02*
X66445D01*
G01X82813Y106731D02*
X80057D01*
G01Y107125D02*
X82813D01*
G01X66445Y107322D02*
X68807D01*
G01X70461D02*
X72823D01*
G01X74477D02*
X76839D01*
G01X66878Y107464D02*
X68453D01*
G01X70894D02*
X72469D01*
G01X74910D02*
X76485D01*
G01X74004Y107519D02*
X69575D01*
G01X77833Y100826D02*
X77439Y100432D01*
G01X80057Y100826D02*
X79664Y100432D01*
G01X71445Y100786D02*
G03X70658Y101574I-787J1D01*
G01X86119Y100906D02*
G03X87669Y99605I1551J274D01*
G01X86894Y101043D02*
G03X87669Y100393I775J137D01*
G01X86209Y102755D02*
G03X85894Y103385I-787J0D01*
G01X82479Y106731D02*
G03X79329I-1575J0D01*
G01X93463Y113818D02*
X92479Y114802D01*
G01X88935Y120117D02*
X89920Y119133D01*
G01X92479Y134093D02*
X93463Y133109D01*
G01X88935Y139408D02*
X89920Y138424D01*
G01X87784Y146889D02*
Y118739D01*
G01X88374Y134093D02*
Y133109D01*
G01X88935Y139408D02*
Y134093D01*
G01Y113818D02*
Y133109D01*
G01X89920Y114802D02*
Y138424D01*
G01X90313Y127597D02*
Y125629D01*
G01Y115629D02*
Y123660D01*
G01X92085Y127597D02*
Y125629D01*
G01Y123660D02*
Y115629D01*
G01X92282Y127893D02*
Y125334D01*
G01Y115334D02*
Y118877D01*
G01Y134349D02*
Y137893D01*
G01X92479Y138424D02*
Y114802D01*
G01X93463Y113818D02*
Y133109D01*
G01Y134093D02*
Y139408D01*
G01X94939Y120412D02*
Y132814D01*
G01X88935Y113818D02*
X93463D01*
G01X92479Y114802D02*
X89920D01*
G01X92282Y115334D02*
X90117D01*
G01X92085Y115629D02*
X90313D01*
G01Y116613D02*
X92085D01*
G01Y117597D02*
X90313D01*
G01X92282Y117893D02*
X90117D01*
G01X90313Y118385D02*
X92085D01*
G01X90117Y118877D02*
X92282D01*
G01X95166Y120117D02*
X93463D01*
G01X90313Y120708D02*
X92085D01*
G01X90313Y121646D02*
X92085D01*
G01Y121692D02*
X90313D01*
G01X92085Y123660D02*
X90313D01*
G01X92282Y125334D02*
X90117D01*
G01X92085Y125629D02*
X90313D01*
G01X92085Y127597D02*
X90313D01*
G01X92282Y127893D02*
X90117D01*
G01X93463Y133109D02*
X95166D01*
G01X89920Y134093D02*
X88374D01*
G01X92479D02*
X95166D01*
G01X92282Y134349D02*
X90117D01*
G01X92282Y135334D02*
X90117D01*
G01X92282Y137893D02*
X90117D01*
G01X92479Y138424D02*
X89920D01*
G01X88935Y139408D02*
X93463D01*
G01X96347Y140781D02*
X95559D01*
G01X89254Y123764D02*
X95352Y123535D01*
G01X94815Y132814D02*
X89600Y133009D01*
G01X95559Y132786D02*
X94939Y132812D01*
G01X92479Y138424D02*
X93463Y139408D01*
G01X89920Y134093D02*
X88935Y133109D01*
G01X92479Y119133D02*
X93463Y120117D01*
G01X88935Y113818D02*
X89920Y114802D01*
G01X93168Y116751D02*
G03I-1969J0D01*
G01Y126751D02*
G03I-1969J0D01*
G01Y136613D02*
G03I-1969J0D01*
G01X94211Y111023D02*
X96347D01*
G01X94211Y111210D02*
X89144D01*
G01X96347Y111810D02*
X95559D01*
G01X64437Y135471D02*
X64241Y135839D01*
G01X64437Y135965D02*
X64241Y136332D01*
G01X68453Y135471D02*
X68256Y135839D01*
G01X68453Y135965D02*
X68256Y136332D01*
G01X64241Y135839D02*
Y143500D01*
G01X64508Y116000D02*
Y116425D01*
G01X64559Y120308D02*
Y120734D01*
G01X72469Y135471D02*
X72272Y135839D01*
G01X72469Y135965D02*
X72272Y136332D01*
G01X76485Y135471D02*
X76288Y135839D01*
G01X76485Y135965D02*
X76288Y136332D01*
G01X64792Y146889D02*
Y140196D01*
G01X66445Y146889D02*
Y140196D01*
G01X67075Y143500D02*
Y135839D01*
G01X67102Y116425D02*
Y116000D01*
G01X67263Y120734D02*
Y120308D01*
G01X68256Y135839D02*
Y143500D01*
G01X68677Y116000D02*
Y116425D01*
G01X68807Y146889D02*
Y140196D01*
G01X68838Y120308D02*
Y120716D01*
G01X70461Y146889D02*
Y140196D01*
G01X71091Y143500D02*
Y135839D01*
G01X71272Y116425D02*
Y116000D01*
G01X71543Y120734D02*
Y120308D01*
G01X72272Y135839D02*
Y143500D01*
G01X72823Y146889D02*
Y140196D01*
G01X73118Y120308D02*
Y120716D01*
G01X74477Y146889D02*
Y140196D01*
G01X75107Y143500D02*
Y135839D01*
G01X75441Y116425D02*
Y116000D01*
G01X75822Y120734D02*
Y120308D01*
G01X76288Y135839D02*
Y143500D01*
G01X76839Y146889D02*
Y140196D01*
G01X77397Y120308D02*
Y120716D01*
G01X77951Y116692D02*
Y113650D01*
G01X79319Y136259D02*
Y140196D01*
G01X79723Y123267D02*
Y113621D01*
G01X86504Y133109D02*
Y120117D01*
G01X87292D02*
Y133109D01*
G01X87459Y132814D02*
Y120412D01*
G01X87489Y119330D02*
Y147317D01*
G01X64565Y121099D02*
X64559Y120308D01*
G01X64888Y149940D02*
X64565Y121099D01*
G01X64508Y116425D02*
X64559Y120734D01*
G01X64508Y116000D02*
X64559Y120308D01*
G01X65256Y148464D02*
X64903Y119330D01*
G01X65649Y148464D02*
X65297Y119330D01*
G01X64565Y121099D02*
X64559Y120734D01*
G01X64502Y115635D02*
X64508Y116000D01*
G01X67263Y120308D02*
X67284Y121099D01*
G01X68859D02*
X68838Y120308D01*
G01X68656Y115635D02*
X68677Y116425D01*
G01X67102D02*
X67081Y115635D01*
G01X68807Y119808D02*
X68838Y120716D01*
G01X68309Y149940D02*
X67284Y121099D01*
G01X69884Y149940D02*
X68859Y121099D01*
G01X66385Y119330D02*
X67442Y148464D01*
G01X67836D02*
X66780Y119330D01*
G01X70198Y148464D02*
X69142Y119330D01*
G01X70592Y148464D02*
X69535Y119330D01*
G01X67263Y120734D02*
X67102Y116425D01*
G01X67263Y120308D02*
X67102Y116000D01*
G01X68677Y116425D02*
X68807Y119914D01*
G01X68677Y116000D02*
X68838Y120308D01*
G01X71543D02*
X71578Y121099D01*
G01X73153D02*
X73118Y120308D01*
G01X71272Y116425D02*
X71236Y115635D01*
G01X68838Y120716D02*
X68859Y121099D01*
G01X73005Y118739D02*
X73118Y120716D01*
G01X67263Y120734D02*
X67284Y121099D01*
G01X67102Y116000D02*
X67081Y115635D01*
G01X68656D02*
X68677Y116000D01*
G01X73305Y149940D02*
X71578Y121099D01*
G01X74880Y149940D02*
X73153Y121099D01*
G01X70624Y119330D02*
X72385Y148464D01*
G01X72779D02*
X71018Y119330D01*
G01X75141Y148464D02*
X73380Y119330D01*
G01X75535Y148464D02*
X73774Y119330D01*
G01X75822Y120308D02*
X75872Y121099D01*
G01X77446D02*
X77397Y120308D01*
G01X71543Y120734D02*
X71272Y116425D01*
G01X71543Y120308D02*
X71272Y116000D01*
G01X73019Y118739D02*
X73118Y120308D01*
G01X75441Y116425D02*
X75391Y115635D01*
G01X77239Y118739D02*
X77397Y120716D01*
G01X78301Y149940D02*
X75872Y121099D01*
G01X79876Y149940D02*
X77446Y121099D01*
G01X74861Y119330D02*
X77327Y148464D01*
G01X77722D02*
X75256Y119330D01*
G01X80084Y148464D02*
X77619Y119330D01*
G01X80479Y148464D02*
X78014Y119330D01*
G01X75822Y120734D02*
X75441Y116425D01*
G01X75822Y120308D02*
X75441Y116000D01*
G01X77258Y118739D02*
X77397Y120308D01*
G01X73118Y120716D02*
X73153Y121099D01*
G01X72811Y115635D02*
X72823Y115762D01*
G01X71543Y120734D02*
X71578Y121099D01*
G01X71272Y116000D02*
X71236Y115635D01*
G01X77397Y120716D02*
X77421Y120907D01*
X77446Y121099D01*
G01X75822Y120734D02*
X75872Y121099D01*
G01X75441Y116000D02*
X75391Y115635D01*
G01X86156Y114068D02*
X85417Y114338D01*
G01X85686Y115078D02*
X86426Y114808D01*
G01X67075Y136332D02*
X66878Y135965D01*
G01X67075Y135839D02*
X66878Y135471D01*
G01X71091Y136332D02*
X70894Y135965D01*
G01X71091Y135839D02*
X70894Y135471D01*
G01X75107Y136332D02*
X74910Y135965D01*
G01X75107Y135839D02*
X74910Y135471D01*
G01X79723Y113621D02*
X77833D01*
G01X77951Y113650D02*
X82479D01*
G01Y114044D02*
X77951D01*
G01X67081Y115635D02*
X68656D01*
G01X71236D02*
X72811D01*
G01X75391D02*
X76839D01*
G01X67087Y115841D02*
X68662D01*
G01X71245D02*
X72823D01*
G01X75404D02*
X76839D01*
G01Y116000D02*
X75441D01*
G01X72823D02*
X71272D01*
G01X68677D02*
X67102D01*
G01X77951Y116299D02*
X85038D01*
G01X76839Y116425D02*
X75441D01*
G01X72823D02*
X71272D01*
G01X68677D02*
X67102D01*
G01X85038Y116692D02*
X77951D01*
G01X87095Y117991D02*
X85225D01*
G01X66445Y118739D02*
X64792D01*
G01X70461D02*
X68807D01*
G01X72823D02*
X74477D01*
G01X76839D02*
X87784D01*
G01X86504Y120117D02*
X88935D01*
G01X77397Y120308D02*
X75822D01*
G01X73118D02*
X71543D01*
G01X68838D02*
X67263D01*
G01X94939Y120412D02*
X87459D01*
G01X76839Y120734D02*
X75822D01*
G01X72823D02*
X71543D01*
G01X68807D02*
X67263D01*
G01X67284Y121099D02*
X68859D01*
G01X71578D02*
X73153D01*
G01X75872D02*
X77446D01*
G01X85225Y122086D02*
X77646D01*
G01X77833Y124054D02*
X85038D01*
G01X76839Y125038D02*
X74477D01*
G01X72823D02*
X70461D01*
G01X68807D02*
X66445D01*
G01X87459Y132814D02*
X94939D01*
G01X85225Y134290D02*
X74004D01*
G01X85225Y136259D02*
X79319D01*
G01X85225Y139212D02*
X79319D01*
G01X80510Y124054D02*
G03X79723Y123267I0J-787D01*
G01X85038D02*
G03X84250Y124054I-787J0D01*
G01X64508Y116425D02*
X64437Y109882D01*
G01X64439Y110023D02*
X64502Y115635D01*
G01X64437Y109958D02*
X64439Y110023D01*
G01X66878Y109882D02*
X66882Y110023D01*
G01X68457D02*
X68453Y109882D01*
G01X67081Y115635D02*
X66882Y110023D01*
G01X68656Y115635D02*
X68457Y110023D01*
G01X70894Y109882D02*
X70900Y110023D01*
G01X72475D02*
X72469Y109882D01*
G01X66882Y110023D02*
X66878Y109958D01*
G01X68453D02*
X68457Y110023D01*
G01X71236Y115635D02*
X70900Y110023D01*
G01X72811Y115635D02*
X72475Y110023D01*
G01X74910Y109882D02*
X74919Y110023D01*
G01X76493D02*
X76485Y109882D01*
G01X75391Y115635D02*
X74919Y110023D01*
G01X76839Y114127D02*
X76493Y110023D01*
G01X70900D02*
X70894Y109958D01*
G01X72469D02*
X72475Y110023D01*
G01X74919D02*
X74910Y109958D01*
G01X76485D02*
X76493Y110023D01*
G01X85686Y115078D02*
X84727Y112443D01*
G01X85467Y112174D02*
X86426Y114808D01*
G01X77833Y108306D02*
X78739D01*
G01X66878Y108842D02*
X68453D01*
G01X70894D02*
X72469D01*
G01X74910D02*
X76485D01*
G01X66878Y109817D02*
X68453D01*
G01X70894D02*
X72469D01*
G01X74910D02*
X76485D01*
G01X77833Y109881D02*
X78739D01*
G01X66878Y110023D02*
X68457D01*
G01X70894D02*
X72475D01*
G01X74910D02*
X76493D01*
G01X66878Y111757D02*
X68453D01*
G01X70894D02*
X72469D01*
G01X74910D02*
X76485D01*
G01Y111969D02*
X74910D01*
G01X72469D02*
X70894D01*
G01X68453D02*
X66878D01*
G01X76485Y112462D02*
X74910D01*
G01X72469D02*
X70894D01*
G01X68453D02*
X66878D01*
G01X84727Y112443D02*
G03X84514Y110007I4439J-1615D01*
G01X85467Y112174D02*
G03X85289Y110144I3699J-1347D01*
G01X78739Y108306D02*
G03Y109881I0J788D01*
G01X89181Y171929D02*
X90002Y170672D01*
G01X88771Y173185D02*
X89181Y171929D01*
G01X88079Y153459D02*
Y152347D01*
G01X88105Y153459D02*
Y152347D01*
G01X88132D02*
Y153459D01*
G01X88276Y152347D02*
Y163877D01*
G01X88349Y153459D02*
Y152347D01*
G01X88374Y153459D02*
Y152347D01*
G01X88420D02*
Y153459D01*
G01X88473D02*
Y152347D01*
G01X88768Y192164D02*
Y174842D01*
G01Y152347D02*
Y155550D01*
G01X88771Y174442D02*
Y173185D01*
G01X89063Y192952D02*
Y152347D01*
G01Y147317D02*
Y146889D01*
G01X89957Y147317D02*
Y152347D01*
G01X90441Y165944D02*
Y159645D01*
G01X91524Y192164D02*
Y174842D01*
G01Y147676D02*
Y155550D01*
G01X91721Y192952D02*
Y146889D01*
G01X93985Y164408D02*
Y192952D01*
G01X88771Y168997D02*
X90822Y167741D01*
G01X90002Y170672D02*
X91232Y169835D01*
G01X89181Y175698D02*
X88771Y174442D01*
G01X91232Y169835D02*
X92462Y169416D01*
G01X90822Y167741D02*
X92872Y167322D01*
G01X95559Y146438D02*
X96347D01*
G01X95559Y147046D02*
X96347D01*
G01Y147171D02*
X95559D01*
G01Y147244D02*
X96347D01*
G01X91524Y147676D02*
X89957D01*
G01X95559Y147834D02*
X96347D01*
G01Y147977D02*
X95559D01*
G01X91524Y148464D02*
X89957D01*
G01X95559Y149408D02*
X96347D01*
G01X95559Y150332D02*
X96347D01*
G01Y152815D02*
X95559D01*
G01X96347Y153739D02*
X95559D01*
G01Y155314D02*
X96347D01*
G01Y156101D02*
X95559D01*
G01Y157282D02*
X96347D01*
G01X95559Y158070D02*
X96347D01*
G01X91229Y158857D02*
X96347D01*
G01X95166Y164408D02*
X93985D01*
G01X91229Y166731D02*
X96347D01*
G01X92872Y167322D02*
X94923D01*
G01X95559Y167519D02*
X96347D01*
G01X95166Y167558D02*
X90117D01*
G01X96347Y168306D02*
X95559D01*
G01X96347Y168503D02*
X94378D01*
G01X92462Y169416D02*
X95333D01*
G01X96563Y169835D02*
X97794Y170672D01*
G01X94923Y167322D02*
X96974Y167741D01*
G01D02*
X99024Y168997D01*
G01X95333Y169416D02*
X96563Y169835D01*
G01X99280Y151613D02*
G03I-3091J0D01*
G01X90441Y159645D02*
G03X91229Y158857I788J0D01*
G01Y166731D02*
G03X90441Y165944I-1J-787D01*
G01X94772Y142433D02*
Y192716D01*
G01X95559Y142741D02*
X95500Y142664D01*
X95328Y142587D01*
X95073Y142510D01*
X94772Y142433D01*
G01X95559Y141515D02*
X96347D01*
G01X95559Y142741D02*
X96347D01*
G01D02*
X96270Y142679D01*
X96046Y142618D01*
X95697Y142556D01*
X95258Y142495D01*
X94772Y142433D01*
G01X63709Y152302D02*
Y150924D01*
G01X64457Y153459D02*
Y152081D01*
G01X64483Y153459D02*
Y152081D01*
G01X64496Y150924D02*
Y152302D01*
G01X64510Y152081D02*
Y153459D01*
G01X64595Y150924D02*
Y152081D01*
G01X67764Y152401D02*
X67135Y153188D01*
G01X72135D02*
X72764Y152401D01*
G01X77135Y153188D02*
X77764Y152401D01*
G01X87541Y170672D02*
X88771Y168997D01*
G01X86721Y172766D02*
X87541Y170672D01*
G01X86311Y175698D02*
X86721Y172766D01*
G01X64654Y152302D02*
Y163877D01*
G01X64727Y153459D02*
Y152081D01*
G01X64752Y153459D02*
Y152081D01*
G01X64798D02*
Y153459D01*
G01X64851D02*
Y152081D01*
G01X64890Y150041D02*
Y152302D01*
G01X65284Y148464D02*
Y152401D01*
G01X65441Y150826D02*
Y153459D01*
G01X66070Y153188D02*
Y150826D01*
G01X66071D02*
Y149645D01*
G01X67134D02*
Y150826D01*
G01X67135D02*
Y153188D01*
G01X67213Y153459D02*
Y152302D01*
G01X67764Y152401D02*
Y150826D01*
G01X67804Y153459D02*
Y152081D01*
G01X67856Y153459D02*
Y152081D01*
G01X67902Y153459D02*
Y152081D01*
G01X67922Y146889D02*
Y152401D01*
G01X67928Y152081D02*
Y153459D01*
G01X68000Y152302D02*
Y163877D01*
G01X68144Y153459D02*
Y152081D01*
G01X68172D02*
Y153459D01*
G01X68197D02*
Y152081D01*
G01X68315Y152302D02*
Y150041D01*
G01X68676Y167322D02*
Y176536D01*
G01X68709Y152302D02*
Y150924D01*
G01X69181Y153459D02*
Y152081D01*
G01X69207Y153459D02*
Y152081D01*
G01X69234D02*
Y153459D01*
G01X69378Y152302D02*
Y163877D01*
G01X69451Y153459D02*
Y152081D01*
G01X69477Y153459D02*
Y152081D01*
G01X69496Y150924D02*
Y152302D01*
G01X69522Y152081D02*
Y153459D01*
G01X69575D02*
Y152081D01*
G01X69890Y152302D02*
Y150041D01*
G01X70166Y152302D02*
Y153459D01*
G01X70284Y148464D02*
Y152401D01*
G01X70441Y150826D02*
Y152401D01*
G01X71070Y153188D02*
Y150826D01*
G01X71071D02*
Y149645D01*
G01X71137Y187007D02*
Y167322D01*
G01X71937Y153459D02*
Y152302D01*
G01X72134Y149645D02*
Y150826D01*
G01X72135D02*
Y153188D01*
G01X72528Y153459D02*
Y152081D01*
G01X72581Y153459D02*
Y152081D01*
G01X72626Y153459D02*
Y152081D01*
G01X72652D02*
Y153459D01*
G01X72725Y152302D02*
Y163877D01*
G01X72764Y150826D02*
Y152401D01*
G01X72869Y153459D02*
Y152081D01*
G01X72896D02*
Y153459D01*
G01X72922D02*
Y146889D01*
G01X73315Y150041D02*
Y152302D01*
G01X73709D02*
Y150924D01*
G01X73906Y153459D02*
Y152081D01*
G01X73932Y153459D02*
Y152081D01*
G01X73959D02*
Y153459D01*
G01X74103Y152302D02*
Y163877D01*
G01X74176Y153459D02*
Y152081D01*
G01X74201Y153459D02*
Y152081D01*
G01X74247D02*
Y153459D01*
G01X74300D02*
Y152081D01*
G01X74496Y150924D02*
Y152302D01*
G01X74890Y150041D02*
Y153459D01*
G01X75284Y148464D02*
Y152401D01*
G01X75441Y150826D02*
Y152401D01*
G01X76070Y153188D02*
Y150826D01*
G01X76071D02*
Y149645D01*
G01X76662Y153459D02*
Y152302D01*
G01X77134Y149645D02*
Y150826D01*
G01X77135D02*
Y153188D01*
G01X77252Y153459D02*
Y152081D01*
G01X77305Y153459D02*
Y152081D01*
G01X77351Y153459D02*
Y152081D01*
G01X77377D02*
Y153459D01*
G01X77449Y152302D02*
Y163877D01*
G01X77593Y153459D02*
Y152081D01*
G01X77620D02*
Y153459D01*
G01X77646D02*
Y152081D01*
G01X77764Y152401D02*
Y150826D01*
G01X77922Y152401D02*
Y146889D01*
G01X78315Y150041D02*
Y152302D01*
G01X78630Y153459D02*
Y152081D01*
G01X78656Y153459D02*
Y152081D01*
G01X78683D02*
Y153459D01*
G01X78709Y152302D02*
Y150924D01*
G01X78827Y152302D02*
Y163877D01*
G01X78900Y153459D02*
Y152081D01*
G01X78926Y153459D02*
Y152081D01*
G01X78971D02*
Y153459D01*
G01X79024D02*
Y152081D01*
G01X79496Y150924D02*
Y152302D01*
G01X79615D02*
Y153459D01*
G01X79890Y150041D02*
Y152302D01*
G01X80284Y148464D02*
Y152401D01*
G01X80441Y150826D02*
Y152401D01*
G01X81070Y153188D02*
Y150826D01*
G01X81071D02*
Y149645D01*
G01X81091D02*
Y148464D01*
G01X81386Y153459D02*
Y152302D01*
G01X81642D02*
Y150924D01*
G01X81977Y153459D02*
Y152081D01*
G01X82030Y153459D02*
Y152081D01*
G01X82075Y153582D02*
Y149645D01*
G01X82101Y152081D02*
Y153459D01*
G01X82174Y152081D02*
Y163877D01*
G01X82318Y153459D02*
Y152081D01*
G01X82345D02*
Y153459D01*
G01X82370D02*
Y152081D01*
G01X83355Y153459D02*
Y152081D01*
G01X83381Y153459D02*
Y152081D01*
G01X83407D02*
Y153459D01*
G01X83552Y152081D02*
Y163877D01*
G01X83624Y153459D02*
Y152081D01*
G01X83650Y153459D02*
Y152081D01*
G01X83696D02*
Y153459D01*
G01X83748D02*
Y152081D01*
G01X84339D02*
Y153459D01*
G01X85225Y148464D02*
Y147676D01*
G01X85365Y152347D02*
Y147317D01*
G01X86111Y153459D02*
Y152347D01*
G01X86701Y153459D02*
Y152347D01*
G01X86754Y153459D02*
Y152347D01*
G01X86800Y153459D02*
Y152347D01*
G01X86826D02*
Y153459D01*
G01X86898Y152347D02*
Y163877D01*
G01X87042Y153459D02*
Y152347D01*
G01X87069D02*
Y153459D01*
G01X87095D02*
Y152347D01*
G01X87193Y186173D02*
Y174842D01*
G01X64888Y149940D02*
X64890Y150183D01*
G01X64888Y149940D02*
X64890Y150041D01*
G01X68315Y150183D02*
X68309Y149940D01*
G01X69884D02*
X69890Y150183D01*
G01X73315D02*
X73305Y149940D01*
G01X74880D02*
X74890Y150183D01*
G01X78315D02*
X78301Y149940D01*
G01X79876D02*
X79890Y150183D01*
G01X68315Y150041D02*
X68309Y149940D01*
G01X69884D02*
X69890Y150041D01*
G01X73315D02*
X73305Y149940D01*
G01X74880D02*
X74890Y150041D01*
G01X80599Y158149D02*
X87134Y151613D01*
G01X78315Y150041D02*
X78301Y149940D01*
G01X79876D02*
X79890Y150041D01*
G01X77289Y177374D02*
X83030Y174442D01*
G01X82210Y173185D02*
X74418Y177374D01*
G01X83030Y174442D02*
X82210Y173185D01*
G01X65441Y152401D02*
X66070Y153188D01*
G01X70441Y152401D02*
X71070Y153188D01*
G01X75441Y152401D02*
X76070Y153188D01*
G01X80441Y152401D02*
X81070Y153188D01*
G01X80599Y158149D02*
X74063Y151613D01*
G01X85365Y147317D02*
X89957D01*
G01X85365Y148464D02*
X85225D01*
G01X81091D02*
X80084D01*
G01X77722D02*
X75141D01*
G01X72779D02*
X70198D01*
G01X67836D02*
X65256D01*
G01X68309Y149940D02*
X69884D01*
G01X73305D02*
X74880D01*
G01X78301D02*
X79876D01*
G01X81065Y150826D02*
X77141D01*
G01X76065D02*
X72141D01*
G01X71065D02*
X67141D01*
G01X79024Y152081D02*
X77252D01*
G01X74300D02*
X72528D01*
G01X69575D02*
X67804D01*
G01X81642D02*
X84339D01*
G01X89957Y152347D02*
X85365D01*
G01X70441Y152401D02*
X67764D01*
G01X72764D02*
X75441D01*
G01X77764D02*
X80441D01*
G01X67135Y153188D02*
X71070D01*
G01X72135D02*
X76070D01*
G01X77135D02*
X81070D01*
G01X89063Y153459D02*
X86111D01*
G01X84339D02*
X81386D01*
G01X79615D02*
X76662D01*
G01X74890D02*
X71937D01*
G01X70166D02*
X67213D01*
G01X88276Y154443D02*
X86898D01*
G01X83552D02*
X82174D01*
G01X78827D02*
X77449D01*
G01X74103D02*
X72725D01*
G01X69378D02*
X68000D01*
G01X88276Y161515D02*
X86898D01*
G01X83552D02*
X82174D01*
G01X78827D02*
X77449D01*
G01X74103D02*
X72725D01*
G01X69378D02*
X68000D01*
G01X88276Y162499D02*
X86898D01*
G01X83552D02*
X82174D01*
G01X78827D02*
X77449D01*
G01X74103D02*
X72725D01*
G01X69378D02*
X68000D01*
G01X88276Y163877D02*
X86898D01*
G01X83552D02*
X82174D01*
G01X78827D02*
X77449D01*
G01X74103D02*
X72725D01*
G01X69378D02*
X68000D01*
G01X71137Y167322D02*
X68676D01*
G01X78149Y147527D02*
G03X83049I2450J4086D01*
G01X84684Y149163D02*
G03Y154063I-4085J2450D01*
G01X83049Y155699D02*
G03X78149I-2450J-4086D01*
G01X76513Y154063D02*
G03Y149163I4086J-2450D01*
G01X64044Y144235D02*
Y143741D01*
G01X74063Y151613D02*
X80599Y145078D01*
G01X64241Y143006D02*
X64044Y143741D01*
G01X64241Y143500D02*
X64044Y144235D01*
G01X68256Y143006D02*
X68059Y143741D01*
G01X68256Y143500D02*
X68059Y144235D01*
G01X72272Y143006D02*
X72075Y143741D01*
G01X72272Y143500D02*
X72075Y144235D01*
G01X76288Y143006D02*
X76091Y143741D01*
G01X76288Y143500D02*
X76091Y144235D01*
G01X67272D02*
Y143741D01*
G01X68059Y144235D02*
Y143741D01*
G01X71288Y144235D02*
Y143741D01*
G01X72075Y144235D02*
Y143741D01*
G01X75304Y144235D02*
Y143741D01*
G01X76091Y144235D02*
Y143741D01*
G01X67272Y144235D02*
X67075Y143500D01*
G01X67272Y143741D02*
X67075Y143006D01*
G01X71288Y144235D02*
X71091Y143500D01*
G01X71288Y143741D02*
X71091Y143006D01*
G01X75304Y144235D02*
X75107Y143500D01*
G01X75304Y143741D02*
X75107Y143006D01*
G01X87784Y143464D02*
X76839D01*
G01X74477D02*
X72823D01*
G01X66445D02*
X64792D01*
G01X70461D02*
X68807D01*
G01X76091Y143741D02*
X75304D01*
G01X72075D02*
X71288D01*
G01X68059D02*
X67272D01*
G01Y144235D02*
X68059D01*
G01X71288D02*
X72075D01*
G01X75304D02*
X76091D01*
G01X87134Y151613D02*
X80599Y145078D01*
G01X86977Y151613D02*
G03I-6378J0D01*
G01X94378Y190156D02*
X95559Y186613D01*
G01X96347D02*
X95166Y190156D01*
G01X88396Y194656D02*
Y193869D01*
G01X88524Y193753D02*
Y194310D01*
G01X95166Y192164D02*
X94378Y192952D01*
G01X95377Y192716D02*
X95474Y192572D01*
X95537Y192407D01*
X95559Y192223D01*
G01X88396Y193475D02*
X88478Y193842D01*
X88519Y194171D01*
Y194430D01*
X88478Y194598D01*
X88396Y194656D01*
G01X98614Y185331D02*
X96563Y186588D01*
G01X96153Y184494D02*
X97383Y183656D01*
G01X95981Y192716D02*
X96178Y192570D01*
X96304Y192403D01*
X96347Y192223D01*
G01X88771Y181143D02*
X89181Y182400D01*
G01X94923Y184913D02*
X96153Y184494D01*
G01X89181Y182400D02*
X90002Y183656D01*
G01X88396Y193475D02*
X88478Y193596D01*
X88519Y193707D01*
Y193794D01*
X88477Y193850D01*
X88396Y193869D01*
G01X96563Y186588D02*
X94513Y187007D01*
G01X94772Y192558D02*
X94378Y192164D01*
G01X95559Y180179D02*
X96347D01*
G01Y180742D02*
X95559D01*
G01X96347Y181073D02*
X95559D01*
G01Y181311D02*
X96347D01*
G01X92462Y184913D02*
X94923D01*
G01X95559Y185207D02*
X96347D01*
G01Y185798D02*
X95559D01*
G01X95166Y186219D02*
X94378D01*
G01X96347Y186613D02*
X95559D01*
G01X94513Y187007D02*
X92872D01*
G01X96347Y189341D02*
X95559D01*
G01Y189932D02*
X96347D01*
G01X94378Y190156D02*
X95166D01*
G01X95559Y192223D02*
X96347D01*
G01X95981Y192716D02*
X94378D01*
G01X96347Y193081D02*
X95559D01*
G01X94378Y193306D02*
X95166D01*
G01X94378Y193475D02*
X88396D01*
G01X94378Y194093D02*
X95166D01*
G01X95377Y193586D02*
X95981Y194090D01*
G01X90002Y183656D02*
X91232Y184494D01*
G01X90822Y186588D02*
X88771Y185331D01*
G01X92872Y187007D02*
X90822Y186588D01*
G01X91232Y184494D02*
X92462Y184913D01*
G01X95166Y190156D02*
X94457Y189920D01*
G01X96347Y193081D02*
G03X94772Y194656I-1575J0D01*
G01X95166Y180954D02*
G03X95559Y180272I787J-1D01*
G01Y193081D02*
G03X94772Y193869I-787J1D01*
G01X88361Y177792D02*
Y178630D01*
G01X94429Y175983D02*
Y176180D01*
G01X95166Y176416D02*
X94378Y177204D01*
G01X88361Y178630D02*
X88771Y181143D01*
G01X99024Y178211D02*
X96974Y179468D01*
G01X97794Y176536D02*
X96563Y177374D01*
G01D02*
X95333Y177792D01*
G01X96974Y179468D02*
X94923Y179887D01*
G01X90002Y176536D02*
X89181Y175698D01*
G01X96347Y175983D02*
X94429D01*
G01X94378Y176180D02*
X95166D01*
G01X95559D02*
X96347D01*
G01X94378Y177204D02*
X93985D01*
G01X95333Y177792D02*
X92462D01*
G01X94923Y179887D02*
X92872D01*
G01X90822Y179468D02*
X88361Y177792D01*
G01X91232Y177374D02*
X90002Y176536D01*
G01X92872Y179887D02*
X90822Y179468D01*
G01X92462Y177792D02*
X91232Y177374D01*
G01X96347Y178908D02*
G03X95559Y180272I-1575J0D01*
G01Y178908D02*
G03X95166Y179590I-787J1D01*
G01X94378Y180954D02*
G03X95166Y179590I1575J0D01*
G01X69103Y188314D02*
X69102Y188325D01*
X69099Y188336D01*
X69094Y188347D01*
X69087Y188358D01*
X69079Y188368D01*
X69068Y188378D01*
G01X69103Y189442D02*
X69102Y189453D01*
X69099Y189465D01*
X69094Y189476D01*
X69087Y189486D01*
X69079Y189496D01*
X69068Y189506D01*
G01X77095Y188314D02*
X77094Y188325D01*
X77091Y188336D01*
X77086Y188347D01*
X77079Y188358D01*
X77071Y188368D01*
X77060Y188378D01*
G01X77095Y189442D02*
X77094Y189453D01*
X77091Y189465D01*
X77086Y189476D01*
X77079Y189486D01*
X77071Y189496D01*
X77060Y189506D01*
G01X63571Y190590D02*
Y191377D01*
G01Y196791D02*
Y198759D01*
G01X63906Y184905D02*
Y186283D01*
G01X64398Y184905D02*
Y186283D01*
G01X82210Y181562D02*
X83030Y180305D01*
G01X64359Y197184D02*
X64306Y197469D01*
X64158Y197709D01*
X63966Y197866D01*
X63764Y197948D01*
X63571Y197972D01*
G01X85087Y188314D02*
X85086Y188325D01*
X85083Y188336D01*
X85078Y188347D01*
X85071Y188358D01*
X85063Y188368D01*
X85052Y188378D01*
G01X85087Y189442D02*
X85086Y189453D01*
X85083Y189465D01*
X85078Y189476D01*
X85071Y189486D01*
X85063Y189496D01*
X85052Y189506D01*
G01X64774Y194656D02*
Y195281D01*
G01X64792Y184905D02*
Y186283D01*
G01X65087D02*
Y184905D01*
G01X65522Y195551D02*
Y194869D01*
G01X65588Y194310D02*
Y193753D01*
G01X65715Y193869D02*
Y194656D01*
G01X66071Y186283D02*
Y184905D01*
G01X66367Y186283D02*
Y184905D01*
G01X66615Y198851D02*
Y198169D01*
G01X66721Y193869D02*
Y194656D01*
G01X66760Y186283D02*
Y184905D01*
G01X67252Y186283D02*
Y184905D01*
G01X67363Y197651D02*
Y198333D01*
G01X67403Y197775D02*
Y198457D01*
G01X67922Y188286D02*
Y186908D01*
G01X68414Y188286D02*
Y186908D01*
G01X68709Y188286D02*
Y186908D01*
G01X68807Y189826D02*
Y188630D01*
G01X68842Y188566D02*
Y189694D01*
G01X68906Y188286D02*
Y186908D01*
G01X69004Y189939D02*
Y188810D01*
G01X69068Y188378D02*
Y189506D01*
G01X69103Y186908D02*
Y189442D01*
G01X70087Y186908D02*
Y189442D01*
G01X70122Y189506D02*
Y188378D01*
G01X70185Y188810D02*
Y189939D01*
G01X70284Y186908D02*
Y188286D01*
G01X70348Y189694D02*
Y188566D01*
G01X70382Y189826D02*
Y188630D01*
G01X70481Y188286D02*
Y186908D01*
G01X70776Y188286D02*
Y186908D01*
G01X71268D02*
Y188286D01*
G01X71898Y184905D02*
Y186283D01*
G01X72390Y184905D02*
Y186283D01*
G01X72784Y184905D02*
Y186283D01*
G01X73079D02*
Y184905D01*
G01X74063Y186283D02*
Y184905D01*
G01X74359Y186283D02*
Y184905D01*
G01X74752Y186283D02*
Y184905D01*
G01X75244Y186283D02*
Y184905D01*
G01X75914Y188286D02*
Y186908D01*
G01X76406Y188286D02*
Y186908D01*
G01X76701Y188286D02*
Y186908D01*
G01X76800Y189826D02*
Y188630D01*
G01X76834Y188566D02*
Y189694D01*
G01X76898Y188286D02*
Y186908D01*
G01X76996Y189939D02*
Y188810D01*
G01X77060Y188378D02*
Y189506D01*
G01X77095Y186908D02*
Y189442D01*
G01X78079Y186908D02*
Y189442D01*
G01X78114Y189506D02*
Y188378D01*
G01X78178Y188810D02*
Y189939D01*
G01X78276Y186908D02*
Y188286D01*
G01X78340Y189694D02*
Y188566D01*
G01X78374Y189826D02*
Y188630D01*
G01X78473Y188286D02*
Y186908D01*
G01X78768Y188286D02*
Y186908D01*
G01X79260D02*
Y188286D01*
G01X79890Y184905D02*
Y186283D01*
G01X80382Y184905D02*
Y186283D01*
G01X80776Y184905D02*
Y186283D01*
G01X81071D02*
Y184905D01*
G01X82056Y186283D02*
Y184905D01*
G01X82351Y186283D02*
Y184905D01*
G01X82744Y186283D02*
Y184905D01*
G01X83237Y186283D02*
Y184905D01*
G01X83906Y188286D02*
Y186908D01*
G01X84398Y188286D02*
Y186908D01*
G01X84693Y188286D02*
Y186908D01*
G01X84792Y189826D02*
Y188630D01*
G01X84826Y188566D02*
Y189694D01*
G01X84890Y188286D02*
Y186908D01*
G01X84989Y189939D02*
Y188810D01*
G01X85052Y188378D02*
Y189506D01*
G01X85087Y186908D02*
Y189442D01*
G01X86071Y186908D02*
Y189442D01*
G01X86106Y189506D02*
Y188378D01*
G01X86170Y188810D02*
Y189939D01*
G01X86268Y186908D02*
Y188286D01*
G01X86332Y189694D02*
Y188566D01*
G01X86367Y189826D02*
Y188630D01*
G01X86465Y188286D02*
Y186908D01*
G01X86760Y188286D02*
Y186908D01*
G01X87193Y192164D02*
Y189022D01*
G01X87252Y186908D02*
Y188286D01*
G01X87390Y194656D02*
Y193869D01*
G01X70382Y189758D02*
X70381Y189747D01*
X70378Y189736D01*
X70374Y189725D01*
X70367Y189714D01*
X70358Y189705D01*
X70348Y189694D01*
G01X70382Y188630D02*
X70381Y188619D01*
X70378Y188607D01*
X70374Y188596D01*
X70367Y188586D01*
X70358Y188576D01*
X70348Y188566D01*
G01X78374Y189758D02*
Y189747D01*
X78370Y189736D01*
X78366Y189725D01*
X78359Y189714D01*
X78350Y189705D01*
X78340Y189694D01*
G01X78374Y188630D02*
Y188619D01*
X78370Y188607D01*
X78366Y188596D01*
X78359Y188586D01*
X78350Y188576D01*
X78340Y188566D01*
G01X86367Y189758D02*
X86366Y189747D01*
X86363Y189736D01*
X86358Y189725D01*
X86351Y189714D01*
X86343Y189705D01*
X86332Y189694D01*
G01X86367Y188630D02*
X86366Y188619D01*
X86363Y188607D01*
X86358Y188596D01*
X86351Y188586D01*
X86343Y188576D01*
X86332Y188566D01*
G01X68807Y189826D02*
X68811Y189848D01*
X68822Y189869D01*
X68841Y189889D01*
X68865Y189906D01*
X68895Y189920D01*
X68929Y189930D01*
X68965Y189937D01*
X69004Y189939D01*
G01X68807Y188697D02*
X68811Y188719D01*
X68822Y188740D01*
X68841Y188760D01*
X68865Y188777D01*
X68895Y188791D01*
X68929Y188802D01*
X68965Y188808D01*
X69004Y188810D01*
G01X69068Y188378D02*
X68842Y188566D01*
G01X69068Y189506D02*
X68842Y189694D01*
G01X77060Y188378D02*
X76834Y188566D01*
G01X77060Y189506D02*
X76834Y189694D01*
G01X85052Y188378D02*
X84826Y188566D01*
G01X85052Y189506D02*
X84826Y189694D01*
G01X68842Y188566D02*
X68832Y188575D01*
X68823Y188585D01*
X68817Y188596D01*
X68811Y188607D01*
X68809Y188618D01*
X68807Y188630D01*
G01X68842Y189694D02*
X68832Y189704D01*
X68823Y189714D01*
X68817Y189725D01*
X68811Y189736D01*
X68809Y189747D01*
X68807Y189758D01*
G01X76834Y188566D02*
X76824Y188575D01*
X76815Y188585D01*
X76809Y188596D01*
X76804Y188607D01*
X76801Y188618D01*
X76800Y188630D01*
G01X76834Y189694D02*
X76824Y189704D01*
X76815Y189714D01*
X76809Y189725D01*
X76804Y189736D01*
X76801Y189747D01*
X76800Y189758D01*
G01X84826Y188566D02*
X84817Y188575D01*
X84807Y188585D01*
X84801Y188596D01*
X84796Y188607D01*
X84793Y188618D01*
X84792Y188630D01*
G01X84826Y189694D02*
X84817Y189704D01*
X84807Y189714D01*
X84801Y189725D01*
X84796Y189736D01*
X84793Y189747D01*
X84792Y189758D01*
G01X64857Y198093D02*
X64553Y198416D01*
X64217Y198621D01*
X63887Y198727D01*
X63571Y198759D01*
G01X76800Y189826D02*
X76804Y189848D01*
X76815Y189869D01*
X76833Y189889D01*
X76857Y189906D01*
X76887Y189920D01*
X76921Y189930D01*
X76957Y189937D01*
X76996Y189939D01*
G01X76800Y188697D02*
X76804Y188719D01*
X76815Y188740D01*
X76833Y188760D01*
X76857Y188777D01*
X76887Y188791D01*
X76921Y188802D01*
X76957Y188808D01*
X76996Y188810D01*
G01X84792Y189826D02*
X84796Y189848D01*
X84807Y189869D01*
X84825Y189889D01*
X84850Y189906D01*
X84879Y189920D01*
X84913Y189930D01*
X84950Y189937D01*
X84989Y189939D01*
G01X84792Y188697D02*
X84796Y188719D01*
X84807Y188740D01*
X84825Y188760D01*
X84850Y188777D01*
X84879Y188791D01*
X84913Y188802D01*
X84950Y188808D01*
X84989Y188810D01*
G01X87541Y183656D02*
X86721Y181562D01*
G01X67363Y198333D02*
X67398Y198414D01*
X67399Y198496D01*
X67365Y198577D01*
X67299Y198652D01*
X67203Y198719D01*
X67079Y198775D01*
X66937Y198816D01*
X66780Y198842D01*
X66615Y198851D01*
G01X67363Y197651D02*
X67398Y197732D01*
X67399Y197814D01*
X67365Y197895D01*
X67299Y197970D01*
X67203Y198037D01*
X67079Y198093D01*
X66937Y198134D01*
X66780Y198160D01*
X66615Y198169D01*
G01X65522Y195551D02*
X67363Y198333D01*
G01X65522Y194869D02*
X67363Y197651D01*
G01X88771Y185331D02*
X87541Y183656D01*
G01X70122Y189506D02*
X70112Y189497D01*
X70103Y189487D01*
X70096Y189476D01*
X70091Y189465D01*
X70088Y189454D01*
X70087Y189442D01*
G01X70122Y188378D02*
X70112Y188368D01*
X70103Y188358D01*
X70096Y188347D01*
X70091Y188336D01*
X70088Y188325D01*
X70087Y188314D01*
G01X78114Y189506D02*
X78104Y189497D01*
X78095Y189487D01*
X78088Y189476D01*
X78083Y189465D01*
X78080Y189454D01*
X78079Y189442D01*
G01X78114Y188378D02*
X78104Y188368D01*
X78095Y188358D01*
X78088Y188347D01*
X78083Y188336D01*
X78080Y188325D01*
X78079Y188314D01*
G01X86106Y189506D02*
X86096Y189497D01*
X86087Y189487D01*
X86080Y189476D01*
X86075Y189465D01*
X86072Y189454D01*
X86071Y189442D01*
G01X86106Y188378D02*
X86096Y188368D01*
X86087Y188358D01*
X86080Y188347D01*
X86075Y188336D01*
X86072Y188325D01*
X86071Y188314D01*
G01X64693Y183921D02*
X66465D01*
G01X72685D02*
X74457D01*
G01X80678D02*
X82449D01*
G01X63906Y184905D02*
X67252D01*
G01X71898D02*
X75244D01*
G01X79890D02*
X83237D01*
G01X63906Y186283D02*
X67252D01*
G01X71898D02*
X75244D01*
G01X79890D02*
X83237D01*
G01X67922Y186908D02*
X71268D01*
G01X75914D02*
X79260D01*
G01X83906D02*
X87252D01*
G01X68676Y187007D02*
X71137D01*
G01X69103Y187158D02*
X70087D01*
G01X77095D02*
X78079D01*
G01X85087D02*
X86071D01*
G01X67922Y188286D02*
X71268D01*
G01X75914D02*
X79260D01*
G01X83906D02*
X87252D01*
G01X86170Y188810D02*
X84989D01*
G01X78178D02*
X76996D01*
G01X70185D02*
X69004D01*
G01Y189939D02*
X70185D01*
G01X76996D02*
X78178D01*
G01X84989D02*
X86170D01*
G01X87390Y192912D02*
X66721D01*
G01X63571Y197578D02*
X63724Y197571D01*
X63871Y197548D01*
X64007Y197512D01*
X64128Y197463D01*
X64226Y197403D01*
X64298Y197336D01*
X64343Y197262D01*
X64359Y197184D01*
X64344Y197108D01*
X64299Y197034D01*
X64227Y196967D01*
X64128Y196906D01*
X64009Y196857D01*
X63874Y196821D01*
X63727Y196799D01*
X63571Y196791D01*
G01Y198548D02*
X63836Y198535D01*
X64091Y198497D01*
X64326Y198434D01*
X64536Y198349D01*
X64705Y198246D01*
X64830Y198129D01*
X64908Y198001D01*
X64935Y197866D01*
X64909Y197734D01*
X64832Y197606D01*
X64707Y197489D01*
X64536Y197384D01*
X64330Y197300D01*
X64095Y197237D01*
X63841Y197198D01*
X63571Y197184D01*
G01X70185Y188810D02*
X70224Y188808D01*
X70261Y188802D01*
X70294Y188792D01*
X70325Y188777D01*
X70349Y188760D01*
X70367Y188741D01*
X70378Y188720D01*
X70382Y188697D01*
G01X78178Y188810D02*
X78216Y188808D01*
X78253Y188802D01*
X78287Y188792D01*
X78317Y188777D01*
X78341Y188760D01*
X78359Y188741D01*
X78370Y188720D01*
X78374Y188697D01*
G01X86170Y188810D02*
X86208Y188808D01*
X86245Y188802D01*
X86279Y188792D01*
X86309Y188777D01*
X86333Y188760D01*
X86352Y188741D01*
X86363Y188720D01*
X86367Y188697D01*
G01X70185Y189939D02*
X70224Y189937D01*
X70261Y189930D01*
X70294Y189920D01*
X70325Y189906D01*
X70349Y189889D01*
X70367Y189869D01*
X70378Y189849D01*
X70382Y189826D01*
G01X78178Y189939D02*
X78216Y189937D01*
X78253Y189930D01*
X78287Y189920D01*
X78317Y189906D01*
X78341Y189889D01*
X78359Y189869D01*
X78370Y189849D01*
X78374Y189826D01*
G01X86170Y189939D02*
X86208Y189937D01*
X86245Y189930D01*
X86279Y189920D01*
X86309Y189906D01*
X86333Y189889D01*
X86352Y189869D01*
X86363Y189849D01*
X86367Y189826D01*
G01X70348Y189694D02*
X70122Y189506D01*
G01X70348Y188566D02*
X70122Y188378D01*
G01X78340Y189694D02*
X78114Y189506D01*
G01X78340Y188566D02*
X78114Y188378D01*
G01X86332Y189694D02*
X86106Y189506D01*
G01X86332Y188566D02*
X86106Y188378D01*
G01X87193Y186173D02*
X87417Y186340D01*
X87611Y186539D01*
X87772Y186769D01*
X87896Y187029D01*
X87973Y187312D01*
X87998Y187597D01*
X87973Y187882D01*
X87896Y188165D01*
X87772Y188425D01*
X87611Y188656D01*
X87417Y188855D01*
X87193Y189022D01*
G01X65715Y194656D02*
X65633Y194597D01*
X65593Y194430D01*
Y194170D01*
X65633Y193842D01*
X65715Y193475D01*
G01X64774Y195281D02*
X64935Y195289D01*
X65092Y195314D01*
X65235Y195355D01*
X65356Y195409D01*
X65453Y195475D01*
X65522Y195551D01*
G01X65715Y193869D02*
X65633Y193849D01*
X65593Y193793D01*
Y193706D01*
X65634Y193595D01*
X65715Y193475D01*
G01X65182Y194656D02*
X65257Y194682D01*
X65327Y194712D01*
X65390Y194747D01*
X65442Y194784D01*
X65487Y194825D01*
X65522Y194869D01*
G01X87193Y189022D02*
G03Y186173I-1614J-1425D01*
G01X71748Y187597D02*
G03I-2153J0D01*
G01X79740D02*
G03I-2153J0D01*
G01X70776D02*
G03I-1181J0D01*
G01X78768D02*
G03I-1181J0D01*
G01X86760D02*
G03I-1181J0D01*
G01X87390Y192912D02*
G03X88396Y193475I0J1181D01*
G01X65715D02*
G03X66721Y192912I1006J618D01*
G01X64693Y176908D02*
Y186283D01*
G01X66465D02*
Y176908D01*
G01X68676Y179049D02*
Y187007D01*
G01X72685Y176908D02*
Y186283D01*
G01X74457D02*
Y176908D01*
G01X80678D02*
Y186283D01*
G01X82449D02*
Y176908D01*
G01X84672Y175444D02*
Y179750D01*
G01X85210D02*
Y176177D01*
G01X85748Y176819D02*
Y176086D01*
G01X86311Y178630D02*
Y175698D01*
G01X86721Y181562D02*
X86311Y178630D01*
G01X85210Y176177D02*
X85748Y176819D01*
G01Y176086D02*
X85210Y175444D01*
G01D02*
X84672D01*
G01X82449Y176908D02*
X80678D01*
G01X74457D02*
X72685D01*
G01X66465D02*
X64693D01*
G01Y178286D02*
X66465D01*
G01X72685D02*
X74457D01*
G01X80678D02*
X82449D01*
G01X64693Y179271D02*
X66465D01*
G01X72685D02*
X74457D01*
G01X80678D02*
X82449D01*
G01X84672Y179750D02*
X85210D01*
G01X74418Y177374D02*
X82210Y181562D01*
G01X83030Y180305D02*
X77289Y177374D01*
G01X83736Y177597D02*
G03I-2153J0D01*
G01X75744D02*
G03I-2153J0D01*
G01X83736D02*
G03I-2153J0D01*
G01X82764D02*
G03I-1181J0D01*
G01X74772D02*
G03I-1181J0D01*
G01X66780D02*
G03I-1181J0D01*
G01X90630Y237530D02*
Y258530D01*
G01X91180Y256280D02*
Y239780D01*
G01X93720Y242580D02*
Y241130D01*
G01X93742Y242438D02*
Y241888D01*
G01X93788Y234448D02*
Y236534D01*
G01X93870Y242438D02*
Y241888D01*
G01X94015D02*
Y242438D01*
G01X94049Y236312D02*
Y235646D01*
G01Y235380D02*
Y234448D01*
G01X94120Y246830D02*
Y242580D01*
G01X94223Y242438D02*
Y241888D01*
G01X94252Y242438D02*
Y241888D01*
G01X94263Y236838D02*
Y245683D01*
G01X94380Y239180D02*
Y238180D01*
G01X95135Y235913D02*
Y236046D01*
G01X95396D02*
Y235868D01*
G01X95744D02*
Y236223D01*
G01X95877Y245695D02*
Y236838D01*
G01X95880Y238180D02*
Y239180D01*
G01X95888Y241888D02*
Y242438D01*
G01X95917Y241888D02*
Y242438D01*
G01X96005Y234448D02*
Y236179D01*
G01X96020Y246830D02*
Y242580D01*
G01X96126Y242438D02*
Y241888D01*
G01X96266Y236534D02*
Y234448D01*
G01X96270Y241888D02*
Y242438D01*
G01X96399Y241888D02*
Y242438D01*
G01X96420Y242580D02*
Y241130D01*
G01X96320Y242056D02*
X95963Y242468D01*
G01X96338D02*
X96420Y242373D01*
G01X95222Y236357D02*
X95353Y236179D01*
G01X96356Y242448D02*
X96385Y242405D01*
X96397Y242374D01*
X96399Y242363D01*
G01X95135Y236046D02*
X95092Y236179D01*
G01X95353D02*
X95396Y236046D01*
G01X95877Y241892D02*
X95878Y241891D01*
Y241890D01*
X95880D01*
X95885Y241889D01*
X95888Y241888D01*
G01X93802Y242468D02*
X93785Y242580D01*
G01X96356D02*
X96338Y242468D01*
G01X93742Y242363D02*
X93743Y242374D01*
X93755Y242405D01*
X93785Y242448D01*
G01X95048Y236490D02*
X95222Y236357D01*
G01X93720Y242142D02*
X93820Y242056D01*
G01X94177Y242468D02*
X94045Y242580D01*
G01X95092Y236179D02*
X95005Y236268D01*
G01X95877Y242441D02*
X95878Y242440D01*
X95882Y242439D01*
X95888Y242438D01*
G01X95092Y235780D02*
X95135Y235913D01*
G01X95396Y235868D02*
X95353Y235735D01*
G01D02*
X95222Y235558D01*
G01X95005Y236268D02*
X94875Y236312D01*
G01X95744Y236223D02*
X96005Y236534D01*
G01Y236179D02*
X95744Y235868D01*
G01X93720Y242373D02*
X93802Y242468D01*
G01X94177D02*
X93820Y242056D01*
G01X95005Y235691D02*
X95092Y235780D01*
G01X96399Y242438D02*
X96381Y242442D01*
X96361Y242452D01*
X96338Y242468D01*
G01X94831Y236534D02*
X95048Y236490D01*
G01X95963Y242468D02*
X96095Y242580D01*
G01X96320Y242056D02*
X96420Y242142D01*
G01X94263Y242438D02*
X94232Y242442D01*
X94203Y242452D01*
X94177Y242468D01*
G01X94263Y241888D02*
X94104Y241908D01*
X93953Y241965D01*
X93820Y242056D01*
G01X95222Y235558D02*
X95048Y235425D01*
G01X93802Y242468D02*
X93780Y242452D01*
X93760Y242442D01*
X93742Y242438D01*
G01X96320Y242056D02*
X96187Y241965D01*
X96037Y241908D01*
X95877Y241888D01*
G01X94252D02*
X94256Y241889D01*
X94258D01*
X94260Y241890D01*
X94262D01*
X94263Y241891D01*
Y241892D01*
G01X94049Y234448D02*
X93788D01*
G01X96266D02*
X96005D01*
G01X94831Y235380D02*
X94049D01*
G01Y235646D02*
X94875D01*
G01Y236312D02*
X94049D01*
G01X93788Y236534D02*
X94831D01*
G01X96005D02*
X96266D01*
G01X95877Y236838D02*
X94263D01*
G01X98304Y238180D02*
X95880D01*
G01X95380Y239680D02*
X94880D01*
G01X91180Y240934D02*
X105940D01*
G01X94263Y240988D02*
X95877D01*
G01X93720Y241130D02*
X96420D01*
G01X94263Y241338D02*
X95877D01*
G01X105940Y241680D02*
X91180D01*
G01X94263Y241841D02*
X95877D01*
G01X91180Y241880D02*
X105940D01*
G01X93742Y241888D02*
X96399D01*
G01X93820Y242056D02*
X93720D01*
G01X96420D02*
X96320D01*
G01X96399Y242438D02*
X93742D01*
G01X94177Y242468D02*
X93802D01*
G01X96338D02*
X95963D01*
G01X94263Y242531D02*
X95877D01*
G01X98060Y242580D02*
X96020D01*
G01X94120D02*
X91180D01*
G01X93720Y241889D02*
X93742Y241888D01*
G01X95963Y242468D02*
X95937Y242452D01*
X95908Y242442D01*
X95877Y242438D01*
G01X94252D02*
X94258Y242439D01*
X94262Y242440D01*
X94263Y242441D01*
G01X96399Y241888D02*
X96420Y241889D01*
G01X95048Y235425D02*
X94831Y235380D01*
G01X94875Y235646D02*
X95005Y235691D01*
G01X94880Y239680D02*
G03X94380Y239180I0J-500D01*
G01X95880D02*
G03X95380Y239680I-500J0D01*
G01X84730Y242710D02*
Y238180D01*
G01X86130Y245530D02*
Y242082D01*
G01X86680Y254101D02*
Y241959D01*
G01X87130Y241430D02*
Y237530D01*
G01X87180Y242026D02*
Y245530D01*
G01X87390Y238180D02*
Y257880D01*
G01X87690Y256280D02*
Y239780D01*
G01X86680Y242558D02*
X86540Y242725D01*
X86442Y242908D01*
X86387Y243097D01*
X86370Y243281D01*
G01X85198Y242959D02*
X86680Y241959D01*
G01Y242082D02*
X86702Y242071D01*
X86767Y242061D01*
X86869Y242051D01*
X86998Y242041D01*
X87144Y242030D01*
G01X86130Y242082D02*
X86163Y242073D01*
X86258Y242065D01*
X86411Y242056D01*
X86611Y242047D01*
X86847Y242039D01*
X87104Y242030D01*
G01X90630Y237530D02*
X87130D01*
G01X94380Y238180D02*
X84730D01*
G01Y239780D02*
X105940D01*
G01X87144Y242030D02*
X87104D01*
G01X87143D02*
X87104D01*
G01X86130Y242082D02*
X86680D01*
G01Y242282D02*
X86130D01*
G01X87104Y242030D02*
X87116D01*
X87128D01*
X87140Y242029D01*
X87154D01*
X87167Y242027D01*
X87180Y242026D01*
G01X87144Y242030D02*
X87150D01*
X87156D01*
X87161Y242029D01*
X87168D01*
X87174Y242027D01*
X87180Y242026D01*
G01X87130Y241430D02*
G03X87180Y242026I1J300D01*
G01X88030Y265511D02*
Y269196D01*
G01Y270202D02*
Y273385D01*
G01X89328D02*
Y265511D01*
G01X94980Y256280D02*
Y254380D01*
G01Y254180D02*
Y250080D01*
G01X95660Y254930D02*
Y253480D01*
G01X95681Y254172D02*
Y253622D01*
G01X95810Y254172D02*
Y253622D01*
G01X95955D02*
Y254172D01*
G01X96060Y253480D02*
Y249230D01*
G01X96163Y254172D02*
Y253622D01*
G01X96192Y254172D02*
Y253622D01*
G01X96203Y250366D02*
Y259222D01*
G01X96649Y250131D02*
Y253095D01*
G01X95725Y253613D02*
X95695Y253656D01*
X95683Y253687D01*
X95681Y253697D01*
G01X96203Y254168D02*
Y254169D01*
X96202Y254170D01*
X96200Y254171D01*
X96198Y254172D01*
X96196D01*
X96192D01*
G01X95724Y253480D02*
X95742Y253593D01*
G01X96203Y253620D02*
X96202Y253621D01*
X96198Y253622D01*
X96192D01*
G01X95742Y253593D02*
X95660Y253687D01*
G01X95761Y254005D02*
X96117Y253593D01*
G01X95166Y271207D02*
X95599Y270704D01*
G01X96203Y250392D02*
X96270Y250345D01*
X96339Y250301D01*
X96412Y250261D01*
X96491Y250224D01*
X96567Y250193D01*
X96649Y250166D01*
G01X96203Y253280D02*
X96270Y253242D01*
X96339Y253206D01*
X96412Y253173D01*
X96491Y253142D01*
X96567Y253117D01*
X96649Y253095D01*
G01X95599Y268359D02*
X95166Y267856D01*
G01X96649Y250616D02*
X96570Y250643D01*
X96494Y250673D01*
X96419Y250708D01*
X96343Y250750D01*
X96273Y250793D01*
X96203Y250843D01*
G01X92571Y269531D02*
X95599Y268359D01*
G01X95166Y267856D02*
X91057Y269531D01*
G01X96649Y250340D02*
X96570Y250362D01*
X96494Y250387D01*
X96419Y250416D01*
X96343Y250450D01*
X96273Y250485D01*
X96203Y250526D01*
G01X95761Y254005D02*
X95660Y253919D01*
G01X96117Y253593D02*
X95985Y253480D01*
G01X95681Y253622D02*
X95700Y253619D01*
X95719Y253609D01*
X95742Y253593D01*
G01X95761Y254005D02*
X95893Y254096D01*
X96044Y254153D01*
X96203Y254172D01*
G01X96117Y253593D02*
X96143Y253609D01*
X96172Y253619D01*
X96203Y253622D01*
G01X97960Y249230D02*
X96060D01*
G01X94980Y250080D02*
X91180D01*
G01X97357Y250130D02*
X96649D01*
G01Y250166D02*
X97357D01*
G01Y250340D02*
X96649D01*
G01X96203Y250616D02*
X96649D01*
G01X97817Y250680D02*
X96203D01*
G01X96060D02*
X92195D01*
G01X96203Y250696D02*
X97817D01*
G01Y250775D02*
X96203D01*
G01X97817Y251225D02*
X96203D01*
G01X96060Y251680D02*
X92559D01*
G01X97817Y251755D02*
X96203D01*
G01X96649Y253095D02*
X97357D01*
G01X96060Y253266D02*
X94980D01*
G01Y253480D02*
X96060D01*
G01X97817Y253529D02*
X96203D01*
G01X95742Y253593D02*
X96117D01*
G01X95681Y253622D02*
X98339D01*
G01X95660Y254005D02*
X95761D01*
G01X95681Y254172D02*
X98339D01*
G01X94980Y254180D02*
X105940D01*
G01X97817Y254220D02*
X96203D01*
G01X94980Y254380D02*
X105940D01*
G01X97817Y254722D02*
X96203D01*
G01X98360Y254930D02*
X95660D01*
G01X97817Y255072D02*
X96203D01*
G01X105940Y255127D02*
X94980D01*
G01X97817Y259222D02*
X96203D01*
G01X95681Y254172D02*
X95660Y254171D01*
G01X89328Y265511D02*
X88030D01*
G01Y273385D02*
X89328D01*
G01X91057Y269531D02*
X95166Y271207D01*
G01X95599Y270704D02*
X92571Y269531D01*
G01X96203Y250366D02*
G03X96649Y250130I867J1099D01*
G01X94330Y252360D02*
G03I-1250J0D01*
G01X94723Y242966D02*
Y245929D01*
G01X95431D02*
Y242966D01*
G01X92559Y251680D02*
X90533Y246115D01*
G01X90311Y245506D02*
X89902Y244380D01*
G01X95877Y242780D02*
X95811Y242819D01*
X95741Y242855D01*
X95669Y242888D01*
X95590Y242918D01*
X95513Y242943D01*
X95431Y242966D01*
G01X95877Y245669D02*
X95811Y245716D01*
X95741Y245760D01*
X95669Y245800D01*
X95590Y245837D01*
X95513Y245868D01*
X95431Y245895D01*
G01Y245444D02*
X95510Y245418D01*
X95587Y245388D01*
X95661Y245353D01*
X95738Y245311D01*
X95808Y245267D01*
X95877Y245218D01*
G01X95431Y245721D02*
X95510Y245699D01*
X95587Y245674D01*
X95661Y245645D01*
X95738Y245611D01*
X95808Y245575D01*
X95877Y245535D01*
G01X94263Y245207D02*
X94329Y245255D01*
X94402Y245302D01*
X94478Y245345D01*
X94557Y245383D01*
X94638Y245416D01*
X94723Y245444D01*
G01X91180Y242795D02*
X94120D01*
G01X96020D02*
X98060D01*
G01X95431Y242966D02*
X94723D01*
G01X94263Y244305D02*
X95877D01*
G01X89902Y244380D02*
X94120D01*
G01X96020D02*
X98060D01*
G01X94263Y244836D02*
X95877D01*
G01X94263Y245286D02*
X95877D01*
G01Y245365D02*
X94263D01*
G01X98060Y245380D02*
X96020D01*
G01X94120D02*
X91180D01*
G01X94263D02*
X95877D01*
G01Y245444D02*
X95431D01*
G01X94723D02*
X94263D01*
G01X94723Y245721D02*
X95431D01*
G01Y245895D02*
X94723D01*
G01Y245930D02*
X95431D01*
G01X96020Y246830D02*
X94120D01*
G01X94263Y245526D02*
X94329Y245566D01*
X94402Y245604D01*
X94478Y245639D01*
X94557Y245670D01*
X94638Y245697D01*
X94723Y245721D01*
G01Y245895D02*
X94644Y245869D01*
X94563Y245836D01*
X94485Y245799D01*
X94408Y245757D01*
X94335Y245710D01*
X94263Y245658D01*
G01X94723Y242966D02*
X94644Y242945D01*
X94563Y242918D01*
X94485Y242887D01*
X94408Y242853D01*
X94335Y242814D01*
X94263Y242771D01*
G01X90533Y246115D02*
G03X91180Y245380I247J-435D01*
G01X95877Y245695D02*
G03X95431Y245930I-865J-1101D01*
G01X94723D02*
G03X94263Y245684I419J-1336D01*
G01X80678Y265511D02*
Y273385D01*
G01X81975D02*
Y270202D01*
G01Y269196D02*
Y265511D01*
G01X84730Y257880D02*
Y253350D01*
G01X86130Y253979D02*
Y250530D01*
G01D02*
Y250280D01*
G01X86370Y252779D02*
Y250280D01*
G01X87130Y258530D02*
Y254630D01*
G01X87180Y250530D02*
Y254034D01*
G01X86680Y253503D02*
X86540Y253337D01*
X86443Y253153D01*
X86387Y252965D01*
X86370Y252779D01*
G01X86680Y254101D02*
X85198Y253101D01*
G01X86680Y250280D02*
X86130D01*
G01X85680D02*
X86130D01*
G01X87630Y250530D02*
X86130D01*
G01X86370Y252779D02*
X86130D01*
G01Y253778D02*
X86680D01*
G01Y253979D02*
X86130D01*
G01X87104Y254030D02*
X87143D01*
G01X87104D02*
X87144D01*
G01X105940Y256280D02*
X84730D01*
G01X105940Y257880D02*
X84730D01*
G01X90630Y258530D02*
X87130D01*
G01X87180Y254034D02*
X87168Y254033D01*
X87156Y254032D01*
X87143D01*
X87129Y254031D01*
X87117Y254030D01*
X87104D01*
G01X87144D02*
X86998Y254020D01*
X86869Y254010D01*
X86767Y253999D01*
X86702Y253989D01*
X86680Y253979D01*
G01X87104Y254030D02*
X86847Y254022D01*
X86611Y254013D01*
X86411Y254005D01*
X86258Y253996D01*
X86163Y253988D01*
X86130Y253979D01*
G01X81975Y265511D02*
X80678D01*
G01X88030Y269196D02*
X81975D01*
G01Y270202D02*
X88030D01*
G01X80678Y273385D02*
X81975D01*
G01X87180Y254034D02*
X87174Y254033D01*
X87163Y254032D01*
X87156Y254031D01*
X87150Y254030D01*
X87144D01*
G01X84730Y253350D02*
G03X85198Y253101I300J0D01*
G01X87180Y254034D02*
G03X87130Y254630I-49J296D01*
G01X85680Y245780D02*
Y250280D01*
G01X85888Y245780D02*
Y250280D01*
G01X86057Y245780D02*
Y250280D01*
G01X86130D02*
Y245780D01*
G01Y245530D02*
Y245780D01*
G01X86311D02*
Y250280D01*
G01X86370Y245780D02*
Y243281D01*
G01X86533Y245780D02*
Y250280D01*
G01X87630Y250530D02*
Y245530D01*
G01X86130Y243281D02*
X86370D01*
G01X87630Y245530D02*
X86130D01*
G01X86680Y245780D02*
X86130D01*
G01D02*
X85680D01*
G01X85198Y242959D02*
G03X84730Y242710I-168J-249D01*
G01X93423Y342824D02*
Y351486D01*
G01X94398Y346433D02*
X96346Y342824D01*
G01X73448Y350042D02*
X72961Y350764D01*
X71986Y351486D01*
X71012D01*
X70037Y350764D01*
X69550Y350042D01*
Y349320D01*
X70037Y348599D01*
X71012Y347877D01*
X72961Y346433D01*
X73448Y345712D01*
Y344268D01*
X72961Y343546D01*
X71986Y342824D01*
X71012D01*
X70037Y343546D01*
X69063Y344990D01*
G01X81243D02*
X80269Y343546D01*
X79294Y342824D01*
X78320Y343546D01*
X77345Y344990D01*
Y346433D01*
X78320Y347877D01*
X79294Y348599D01*
X80269Y347877D01*
X81243Y346433D01*
Y344990D01*
G01X88064Y343546D02*
X87089Y342824D01*
X86115Y343546D01*
X85141Y344990D01*
Y346433D01*
X86115Y347877D01*
X87089Y348599D01*
X88064Y347877D01*
G01X93423Y345712D02*
X96346Y348599D01*
G01X88574Y518497D02*
Y502581D01*
G01X111540Y497555D02*
X88574D01*
G01Y502581D02*
X111540D01*
G01X88574Y497555D02*
Y479127D01*
G01X83652D02*
Y518497D01*
G01X88574Y479127D02*
X83652D01*
G01Y518497D02*
X88574D01*
G01X75778Y2158744D02*
X74352Y2156843D01*
X72926Y2155892D01*
X71500D01*
X70074Y2156843D01*
X69361Y2157793D01*
G01X70074Y2166349D02*
X71500Y2167300D01*
X72926D01*
X74352Y2166349D01*
X75065Y2165399D01*
Y2164448D01*
X74352Y2163497D01*
X72926Y2162547D01*
X74352Y2161596D01*
G01D02*
X75778Y2159695D01*
Y2158744D01*
G01X71500Y2162547D02*
X72926D01*
G01X125320Y-792858D02*
X126294Y-794301D01*
Y-795023D01*
G01X123371Y-792136D02*
X124346D01*
G01X126294Y-795023D02*
X125320Y-796467D01*
X124346Y-797188D01*
X123371D01*
X122397Y-796467D01*
X121910Y-795745D01*
G01X122397Y-789249D02*
X123371Y-788527D01*
X124346D01*
X125320Y-789249D01*
X125807Y-789971D01*
Y-790692D01*
X125320Y-791414D01*
X124346Y-792136D01*
X125320Y-792858D01*
G01X98181D02*
X99156Y-794301D01*
Y-795023D01*
G01X103053Y-791414D02*
X105976Y-797188D01*
G01X108413Y-792858D02*
X109134Y-790692D01*
X110578Y-789249D01*
X112743Y-788527D01*
X114909Y-789249D01*
X116352Y-790692D01*
X117074Y-792858D01*
X116352Y-795023D01*
X114909Y-796467D01*
X112743Y-797188D01*
X110578Y-796467D01*
X109134Y-795023D01*
X108413Y-792858D01*
G01X103053Y-797188D02*
X105976Y-791414D01*
G01X109134Y-799354D02*
X116352Y-786362D01*
G01X124520Y-674480D02*
X123133Y-666771D01*
G01X152162Y-727083D02*
X124520Y-674480D01*
G01X123133Y-539002D02*
Y-666771D01*
G01Y-539002D02*
Y-666771D01*
G01Y-539002D02*
X146407Y-490690D01*
G01X122656Y-171137D02*
X127528D01*
G01X125092D02*
Y-179799D01*
G01X130451D02*
X132887Y-171137D01*
X135323Y-179799D01*
G01X110476Y-171859D02*
X111450Y-173303D01*
X111937Y-175468D01*
X111450Y-177633D01*
X110963Y-178355D01*
X110476Y-179077D01*
X109501Y-179799D01*
X107552D01*
Y-171137D01*
G01X119245Y-179799D02*
X115348D01*
Y-171137D01*
X119245D01*
G01X115348Y-175468D02*
X117783D01*
G01X107552Y-171137D02*
X109501D01*
X110476Y-171859D01*
G01X131311Y49471D02*
X119500D01*
G01X98550Y45140D02*
Y50914D01*
G01X107807Y45140D02*
Y53801D01*
G01X115602Y45862D02*
X117551Y50914D01*
G01X98550Y49471D02*
X99524Y50914D01*
X100499D01*
X101473Y49471D01*
Y45140D01*
G01X113654Y50914D02*
X115602Y45862D01*
X115115Y43696D01*
X114141Y42253D01*
X113166D01*
G01X127756Y104920D02*
X126969Y105708D01*
G01X123425Y104763D02*
Y162479D01*
G01X125000Y104763D02*
Y155314D01*
G01X125787Y104920D02*
Y102401D01*
G01X126969Y105708D02*
Y155314D01*
G01X125787Y102401D02*
X170276D01*
G01X125787Y103975D02*
X170276D01*
G01X125787Y104763D02*
X170276D01*
G01X123425Y104920D02*
X172638D01*
G01X169094Y105708D02*
X126969D01*
G01X122638Y102401D02*
G03X125000Y104763I0J2362D01*
G01X122638Y103975D02*
G03X123425Y104763I0J787D01*
G01X119685Y102401D02*
Y103975D01*
G01X122638Y102401D02*
X119685D01*
G01Y103975D02*
X122638D01*
G01X127205Y147401D02*
Y138345D01*
G01X124213Y142873D02*
X123425Y140850D01*
G01Y129077D02*
X125000D01*
G01Y129789D02*
X123425D01*
G01Y129865D02*
X125000D01*
G01Y130576D02*
X123425D01*
G01X131363Y133030D02*
X130970D01*
G01D02*
G03X130774Y132819I0J-197D01*
G01D02*
X132649Y106568D01*
G01X125000Y110248D02*
X123425D01*
G01Y110411D02*
X125000D01*
G01X123425Y110426D02*
X125000D01*
G01X123425Y110464D02*
X125000D01*
G01X117126Y138345D02*
Y147401D01*
G01X127205Y138345D02*
X117126D01*
G01X126693Y142873D02*
G03I-4527J0D01*
G01X122400Y172348D02*
Y173604D01*
G01X124450D02*
X123630Y175698D01*
G01X124450Y172348D02*
Y173604D01*
G01X127731Y167322D02*
Y180724D01*
G01X129782Y177792D02*
Y167322D01*
G01X123630Y170253D02*
X124450Y172348D01*
G01X122400Y168997D02*
X123630Y170253D01*
G01X171063Y155314D02*
X125000D01*
G01X172638Y162479D02*
X123425D01*
G01X129782Y167322D02*
X127731D01*
G01X131228Y160459D02*
G03Y158097I0J-1181D01*
G01X124213Y145155D02*
X123425Y146755D01*
G01X124213Y145155D02*
Y142873D01*
G01X101074Y174861D02*
X100254Y176955D01*
G01X109687Y172348D02*
X110507Y170253D01*
G01X99024Y174442D02*
X98614Y175698D01*
G01X99024Y173185D02*
Y174442D01*
G01X101074Y172766D02*
Y174861D01*
G01X104356Y167322D02*
Y169416D01*
G01X106406D02*
Y167322D01*
G01X109687Y173604D02*
Y172348D01*
G01X111737Y173604D02*
Y172348D01*
G01X110507Y170253D02*
X111737Y168997D01*
G01Y172348D02*
X112968Y170672D01*
G01X122400Y173604D02*
X121170Y175279D01*
G01X111737Y168997D02*
X113788Y167741D01*
G01X98614Y171929D02*
X99024Y173185D01*
G01X100254Y170672D02*
X101074Y172766D01*
G01X112968Y170672D02*
X114608Y169835D01*
G01X110507Y175698D02*
X109687Y173604D01*
G01X97794Y170672D02*
X98614Y171929D01*
G01X113788Y167741D02*
X115838Y167322D01*
G01X114608Y169835D02*
X116248Y169416D01*
G01X99024Y168997D02*
X100254Y170672D01*
G01X112968Y175279D02*
X111737Y173604D01*
G01X121170Y170672D02*
X122400Y172348D01*
G01X117126Y147401D02*
X127205D01*
G01X106406Y167322D02*
X104356D01*
G01X115838D02*
X118299D01*
G01X104356Y169416D02*
X106406D01*
G01X116248D02*
X117889D01*
G01X118299Y167322D02*
X120350Y167741D01*
G01D02*
X122400Y168997D01*
G01X117889Y169416D02*
X119529Y169835D01*
G01D02*
X121170Y170672D01*
G01X121990Y181143D02*
Y181981D01*
G01X123220Y184075D02*
X121990Y185331D01*
G01X124041Y181981D02*
X123220Y184075D01*
G01X124041Y180724D02*
Y181981D01*
G01X127731Y180724D02*
X129782D01*
G01X130602Y180305D02*
X131832Y180724D01*
G01X129782D02*
Y179468D01*
G01X123630Y175698D02*
X121990Y176955D01*
G01X123220Y179049D02*
X124041Y180724D01*
G01X121990Y177792D02*
X123220Y179049D01*
G01X129782Y179468D02*
X130602Y180305D01*
G01Y178630D02*
X129782Y177792D01*
G01X131832Y179049D02*
X130602Y178630D01*
G01X97383Y183656D02*
X98204Y182400D01*
G01X100254D02*
X99844Y183656D01*
G01X100284Y204723D02*
Y196849D01*
G01X110097Y181981D02*
Y180724D01*
G01X112147Y181981D02*
Y181143D01*
G01X99844Y183656D02*
X98614Y185331D01*
G01X121990Y181981D02*
X121170Y183237D01*
G01D02*
X119529Y184494D01*
G01X121990Y185331D02*
X119939Y186588D01*
G01X110917Y184075D02*
X110097Y181981D01*
G01X112968Y183237D02*
X112147Y181981D01*
G01X119939Y186588D02*
X117889Y187007D01*
G01X119529Y184494D02*
X117889Y184913D01*
G01X112147Y185331D02*
X110917Y184075D01*
G01X98204Y182400D02*
X100254D01*
G01X117889Y184913D02*
X116248D01*
G01X117889Y187007D02*
X116248D01*
G01X100284Y196849D02*
X352607D01*
G01X114608Y184494D02*
X112968Y183237D01*
G01X116248Y187007D02*
X114198Y186588D01*
G01D02*
X112147Y185331D01*
G01X116248Y184913D02*
X114608Y184494D01*
G01X110097Y180724D02*
X110917Y179049D01*
G01X98614Y175698D02*
X97794Y176536D01*
G01X100254Y176955D02*
X99024Y178211D01*
G01X110917Y179049D02*
X112147Y177792D01*
G01Y181143D02*
X112968Y179887D01*
G01D02*
X114608Y178630D01*
G01X112147Y177792D02*
X112968Y177374D01*
G01X121170Y175279D02*
X119529Y176117D01*
G01X121990Y176955D02*
X121170Y177374D01*
G01Y179887D02*
X121990Y181143D01*
G01X119529Y176117D02*
X117889Y176536D01*
G01X114608Y178630D02*
X116248Y178211D01*
G01X117889Y176536D02*
X116248D01*
G01Y178211D02*
X117889D01*
G01X112147Y176955D02*
X110507Y175698D01*
G01X119529Y178630D02*
X121170Y179887D01*
G01X116248Y176536D02*
X114608Y176117D01*
G01X117889Y178211D02*
X119529Y178630D01*
G01X112968Y177374D02*
X112147Y176955D01*
G01X114608Y176117D02*
X112968Y175279D01*
G01X121170Y177374D02*
X121990Y177792D01*
G01X122210Y256280D02*
Y239780D01*
G01X122510Y257880D02*
Y238180D01*
G01X122720Y245530D02*
Y242026D01*
G01X122770Y241430D02*
Y237530D01*
G01X123220Y242082D02*
Y245530D01*
G01Y241959D02*
Y242082D01*
G01X123770D02*
Y245530D01*
G01X125170Y242710D02*
Y238180D01*
G01X123220Y242558D02*
X123360Y242724D01*
X123458Y242908D01*
X123513Y243096D01*
X123530Y243281D01*
G01X124702Y242959D02*
X123220Y241959D01*
G01X122797Y242030D02*
X122757D01*
G01X122797D02*
X122757D01*
G01X123220Y242082D02*
X123770D01*
G01Y242282D02*
X123220D01*
G01X122720Y242026D02*
X122744Y242029D01*
X122757D01*
X122771Y242030D01*
X122783D01*
X122797D01*
G01X122757D02*
X122902Y242041D01*
X123031Y242051D01*
X123133Y242061D01*
X123198Y242071D01*
X123220Y242082D01*
G01X122797Y242030D02*
X123054Y242039D01*
X123289Y242047D01*
X123489Y242056D01*
X123642Y242065D01*
X123738Y242073D01*
X123770Y242082D01*
G01X122720Y242026D02*
X122732Y242029D01*
X122738D01*
X122744Y242030D01*
X122750D01*
X122757D01*
G01X122720Y242026D02*
G03X122770Y241430I50J-296D01*
G01X97660Y242580D02*
Y241130D01*
G01X97681Y242438D02*
Y241888D01*
G01X97810Y242438D02*
Y241888D01*
G01X97955D02*
Y242438D01*
G01X98060Y246830D02*
Y242580D01*
G01X98163Y242438D02*
Y241888D01*
G01X98192Y242438D02*
Y241888D01*
G01X98203Y236838D02*
Y245683D01*
G01X98304Y239180D02*
Y238180D01*
G01X99804D02*
Y239180D01*
G01X99817Y245695D02*
Y236838D01*
G01X99828Y241888D02*
Y242438D01*
G01X99857Y241888D02*
Y242438D01*
G01X99960Y246830D02*
Y242580D01*
G01X100066Y242438D02*
Y241888D01*
G01X100210D02*
Y242438D01*
G01X100339Y241888D02*
Y242438D01*
G01X100360Y242580D02*
Y241130D01*
G01X101600Y242580D02*
Y241130D01*
G01X101622Y242438D02*
Y241888D01*
G01X101750Y242438D02*
Y241888D01*
G01X101895D02*
Y242438D01*
G01X102000Y246830D02*
Y242580D01*
G01X102103Y242438D02*
Y241888D01*
G01X102132Y242438D02*
Y241888D01*
G01X102143Y236838D02*
Y245683D01*
G01X102228Y239180D02*
Y238180D01*
G01X103728D02*
Y239180D01*
G01X103757Y245695D02*
Y236838D01*
G01X103768Y241888D02*
Y242438D01*
G01X103798Y241888D02*
Y242438D01*
G01X103900Y246830D02*
Y242580D01*
G01X104006Y242438D02*
Y241888D01*
G01X104150D02*
Y242438D01*
G01X104279Y241888D02*
Y242438D01*
G01X104300Y242580D02*
Y241130D01*
G01X105540Y242580D02*
Y241130D01*
G01X105561Y242438D02*
Y241888D01*
G01X105690Y242438D02*
Y241888D01*
G01X105835D02*
Y242438D01*
G01X105940Y253480D02*
Y242580D01*
G01Y241880D02*
Y238180D01*
G01X106043Y242438D02*
Y241888D01*
G01X106072Y242438D02*
Y241888D01*
G01X106083Y236838D02*
Y245683D01*
G01X107697Y245695D02*
Y236838D01*
G01X107708Y241888D02*
Y242438D01*
G01X107737Y241888D02*
Y242438D01*
G01X107840Y246830D02*
Y242580D01*
G01X107946Y242438D02*
Y241888D01*
G01X108090D02*
Y242438D01*
G01X108219Y241888D02*
Y242438D01*
G01X108240Y242580D02*
Y241130D01*
G01X109480Y242580D02*
Y241130D01*
G01X109502Y242438D02*
Y241888D01*
G01X109630Y242438D02*
Y241888D01*
G01X109775D02*
Y242438D01*
G01X109880Y246830D02*
Y242580D01*
G01X109983Y242438D02*
Y241888D01*
G01X110012Y242438D02*
Y241888D01*
G01X110023Y236838D02*
Y245683D01*
G01X111637Y245695D02*
Y236838D01*
G01X111648Y241888D02*
Y242438D01*
G01X111678Y241888D02*
Y242438D01*
G01X111780Y246830D02*
Y242580D01*
G01X111885Y242438D02*
Y241888D01*
G01X112030D02*
Y242438D01*
G01X112159Y241888D02*
Y242438D01*
G01X112180Y242580D02*
Y241130D01*
G01X113420Y242580D02*
Y241130D01*
G01X113442Y242438D02*
Y241888D01*
G01X113570Y242438D02*
Y241888D01*
G01X113715D02*
Y242438D01*
G01X113820Y246830D02*
Y242580D01*
G01X113923Y242438D02*
Y241888D01*
G01X113952Y242438D02*
Y241888D01*
G01X113963Y236838D02*
Y245683D01*
G01X115577Y245695D02*
Y236838D01*
G01X115588Y241888D02*
Y242438D01*
G01X115617Y241888D02*
Y242438D01*
G01X115720Y246830D02*
Y242580D01*
G01X115826Y242438D02*
Y241888D01*
G01X115970D02*
Y242438D01*
G01X116099Y241888D02*
Y242438D01*
G01X116120Y241130D02*
Y242580D01*
G01X118720Y256280D02*
Y239780D01*
G01X119270Y258530D02*
Y237530D01*
G01X100296Y242448D02*
X100325Y242405D01*
X100337Y242374D01*
X100339Y242363D01*
G01X104236Y242448D02*
X104265Y242405D01*
X104277Y242374D01*
X104279Y242363D01*
G01X108176Y242448D02*
X108206Y242405D01*
X108217Y242374D01*
X108219Y242363D01*
G01X112116Y242448D02*
X112145Y242405D01*
X112157Y242374D01*
X112159Y242363D01*
G01X116056Y242448D02*
X116085Y242405D01*
X116097Y242374D01*
X116099Y242363D01*
G01X99817Y241892D02*
X99818Y241891D01*
X99819Y241890D01*
X99820D01*
X99822Y241889D01*
X99825D01*
X99828Y241888D01*
G01X103757Y241892D02*
Y241891D01*
X103758Y241890D01*
X103760D01*
X103762Y241889D01*
X103765D01*
X103768Y241888D01*
G01X107697Y241892D02*
X107698Y241891D01*
Y241890D01*
X107700D01*
X107702Y241889D01*
X107705D01*
X107708Y241888D01*
G01X111637Y241892D02*
Y241891D01*
X111639Y241890D01*
X111640D01*
X111642Y241889D01*
X111645D01*
X111648Y241888D01*
G01X115577Y241892D02*
X115578Y241891D01*
Y241890D01*
X115580D01*
X115585Y241889D01*
X115588Y241888D01*
G01X97742Y242468D02*
X97724Y242580D01*
G01X101682Y242468D02*
X101665Y242580D01*
G01X105622Y242468D02*
X105605Y242580D01*
G01X109206Y242056D02*
X109148Y242425D01*
G01X109562Y242468D02*
X109504Y242838D01*
G01X113146Y242056D02*
X113087Y242425D01*
G01X113502Y242468D02*
X113444Y242838D01*
G01X100296Y242580D02*
X100278Y242468D01*
G01X104236Y242580D02*
X104218Y242468D01*
G01X108217Y242838D02*
X108158Y242468D01*
G01X108573Y242425D02*
X108515Y242056D01*
G01X112156Y242838D02*
X112098Y242468D01*
G01X112513Y242425D02*
X112455Y242056D01*
G01X116096Y242838D02*
X116038Y242468D01*
G01X116453Y242425D02*
X116395Y242056D01*
G01X97681Y242363D02*
X97683Y242374D01*
X97695Y242405D01*
X97725Y242448D01*
G01X101622Y242363D02*
X101623Y242374D01*
X101635Y242405D01*
X101665Y242448D01*
G01X105561Y242363D02*
X105563Y242374D01*
X105575Y242405D01*
X105605Y242448D01*
G01X109502Y242363D02*
X109503Y242374D01*
X109515Y242405D01*
X109544Y242448D01*
G01X113442Y242363D02*
X113443Y242374D01*
X113455Y242405D01*
X113485Y242448D01*
G01X97660Y242142D02*
X97761Y242056D01*
G01X98117Y242468D02*
X97985Y242580D01*
G01X101600Y242142D02*
X101700Y242056D01*
G01X102057Y242468D02*
X101926Y242580D01*
G01X105540Y242142D02*
X105641Y242056D01*
G01X105997Y242468D02*
X105865Y242580D01*
G01X109148Y242425D02*
X109580Y242056D01*
G01X109937Y242468D02*
X109504Y242838D01*
G01X113087Y242425D02*
X113520Y242056D01*
G01X113877Y242468D02*
X113444Y242838D01*
G01X109206Y242056D02*
X109290Y241965D01*
X109391Y241908D01*
X109502Y241888D01*
G01X113146Y242056D02*
X113230Y241965D01*
X113331Y241908D01*
X113442Y241888D01*
G01X99817Y242441D02*
X99819Y242440D01*
X99822Y242439D01*
X99828Y242438D01*
G01X103757Y242441D02*
X103759Y242440D01*
X103762Y242439D01*
X103768Y242438D01*
G01X107697Y242441D02*
X107698Y242440D01*
X107702Y242439D01*
X107708Y242438D01*
G01X111637Y242441D02*
X111639Y242440D01*
X111642Y242439D01*
X111648Y242438D01*
G01X115577Y242441D02*
X115578Y242440D01*
X115582Y242439D01*
X115588Y242438D01*
G01X100260Y242056D02*
X99904Y242468D01*
G01X100278D02*
X100360Y242373D01*
G01X104200Y242056D02*
X103843Y242468D01*
G01X104218D02*
X104300Y242373D01*
G01X108140Y242056D02*
X107783Y242468D01*
G01X108158D02*
X108515Y242056D01*
G01X108217Y242838D02*
X108573Y242425D01*
G01X112080Y242056D02*
X111724Y242468D01*
G01X112098D02*
X112455Y242056D01*
G01X112156Y242838D02*
X112513Y242425D01*
G01X116020Y242056D02*
X115663Y242468D01*
G01X116038D02*
X116395Y242056D01*
G01X116096Y242838D02*
X116453Y242425D01*
G01X97660Y242373D02*
X97742Y242468D01*
G01X98117D02*
X97761Y242056D01*
G01X101600Y242373D02*
X101682Y242468D01*
G01X102057D02*
X101700Y242056D01*
G01X105540Y242373D02*
X105622Y242468D01*
G01X105997D02*
X105641Y242056D01*
G01X109504Y242838D02*
X109148Y242425D01*
G01X109206Y242056D02*
X109562Y242468D01*
G01X109937D02*
X109580Y242056D01*
G01X113444Y242838D02*
X113087Y242425D01*
G01X113146Y242056D02*
X113502Y242468D01*
G01X113877D02*
X113520Y242056D01*
G01X100339Y242438D02*
X100321Y242442D01*
X100301Y242452D01*
X100278Y242468D01*
G01X104279Y242438D02*
X104261Y242442D01*
X104241Y242452D01*
X104218Y242468D01*
G01X108219Y242438D02*
X108201Y242442D01*
X108181Y242452D01*
X108158Y242468D01*
G01X112159Y242438D02*
X112141Y242442D01*
X112121Y242452D01*
X112098Y242468D01*
G01X116099Y242438D02*
X116081Y242442D01*
X116061Y242452D01*
X116038Y242468D01*
G01X99904D02*
X100035Y242580D01*
G01X100260Y242056D02*
X100360Y242142D01*
G01X103843Y242468D02*
X103975Y242580D01*
G01X104200Y242056D02*
X104300Y242142D01*
G01X107783Y242468D02*
X108217Y242838D01*
G01X108140Y242056D02*
X108573Y242425D01*
G01X111724Y242468D02*
X112156Y242838D01*
G01X112080Y242056D02*
X112513Y242425D01*
G01X115663Y242468D02*
X116096Y242838D01*
G01X116020Y242056D02*
X116453Y242425D01*
G01X98203Y242438D02*
X98172Y242442D01*
X98143Y242452D01*
X98117Y242468D01*
G01X102143Y242438D02*
X102112Y242442D01*
X102083Y242452D01*
X102057Y242468D01*
G01X106083Y242438D02*
X106052Y242442D01*
X106023Y242452D01*
X105997Y242468D01*
G01X110023Y242438D02*
X109992Y242442D01*
X109963Y242452D01*
X109937Y242468D01*
G01X113963Y242438D02*
X113932Y242442D01*
X113903Y242452D01*
X113877Y242468D01*
G01X98203Y241888D02*
X98044Y241908D01*
X97893Y241965D01*
X97761Y242056D01*
G01X102143Y241888D02*
X101983Y241908D01*
X101833Y241965D01*
X101700Y242056D01*
G01X106083Y241888D02*
X105924Y241908D01*
X105773Y241965D01*
X105641Y242056D01*
G01X110023Y241888D02*
X109864Y241908D01*
X109713Y241965D01*
X109580Y242056D01*
G01X113963Y241888D02*
X113804Y241908D01*
X113653Y241965D01*
X113520Y242056D01*
G01X97742Y242468D02*
X97719Y242452D01*
X97700Y242442D01*
X97681Y242438D01*
G01X101682Y242468D02*
X101659Y242452D01*
X101640Y242442D01*
X101622Y242438D01*
G01X105622Y242468D02*
X105599Y242452D01*
X105580Y242442D01*
X105561Y242438D01*
G01X109562Y242468D02*
X109539Y242452D01*
X109520Y242442D01*
X109502Y242438D01*
G01X113502Y242468D02*
X113480Y242452D01*
X113460Y242442D01*
X113442Y242438D01*
G01X100260Y242056D02*
X100127Y241965D01*
X99977Y241908D01*
X99817Y241888D01*
G01X104200Y242056D02*
X104067Y241965D01*
X103917Y241908D01*
X103757Y241888D01*
G01X108140Y242056D02*
X108007Y241965D01*
X107857Y241908D01*
X107697Y241888D01*
G01X112080Y242056D02*
X111947Y241965D01*
X111797Y241908D01*
X111637Y241888D01*
G01X116020Y242056D02*
X115887Y241965D01*
X115737Y241908D01*
X115577Y241888D01*
G01X113952D02*
X113956Y241889D01*
X113958D01*
X113960Y241890D01*
X113962D01*
X113963Y241891D01*
Y241892D01*
G01X110012Y241888D02*
X110015Y241889D01*
X110018D01*
X110020Y241890D01*
X110023Y241891D01*
Y241892D01*
G01X106072Y241888D02*
X106075Y241889D01*
X106078D01*
X106080Y241890D01*
X106082D01*
X106083Y241891D01*
Y241892D01*
G01X102132Y241888D02*
X102135Y241889D01*
X102138D01*
X102140Y241890D01*
X102142D01*
X102143Y241891D01*
Y241892D01*
G01X98192Y241888D02*
X98195Y241889D01*
X98198D01*
X98200Y241890D01*
X98202D01*
X98203Y241891D01*
Y241892D01*
G01X115577Y236838D02*
X113963D01*
G01X111637D02*
X110023D01*
G01X107697D02*
X106083D01*
G01X103757D02*
X102143D01*
G01X99817D02*
X98203D01*
G01X122770Y237530D02*
X119270D01*
G01X105940Y238180D02*
X103728D01*
G01X125170D02*
X105940D01*
G01X102228D02*
X99804D01*
G01X103228Y239680D02*
X102728D01*
G01X99304D02*
X98804D01*
G01X125170Y239780D02*
X105940D01*
G01Y240934D02*
X118720D01*
G01X98203Y240988D02*
X99817D01*
G01X106083D02*
X107697D01*
G01X102143D02*
X103757D01*
G01X110023D02*
X111637D01*
G01X113963D02*
X115577D01*
G01X101600Y241130D02*
X104300D01*
G01X97660D02*
X100360D01*
G01X105540D02*
X105940D01*
G01D02*
X108240D01*
G01X109480D02*
X112180D01*
G01X113420D02*
X116120D01*
G01X98203Y241338D02*
X99817D01*
G01X106083D02*
X107697D01*
G01X102143D02*
X103757D01*
G01X110023D02*
X111637D01*
G01X113963D02*
X115577D01*
G01X118720Y241680D02*
X105940D01*
G01X98203Y241841D02*
X99817D01*
G01X102143D02*
X103757D01*
G01X118720Y241880D02*
X105940D01*
G01X97681Y241888D02*
X100339D01*
G01X105561D02*
X108219D01*
G01X101622D02*
X104279D01*
G01X109502D02*
X112159D01*
G01X113442D02*
X116099D01*
G01X116395Y242056D02*
X116020D01*
G01X113520D02*
X113146D01*
G01X112455D02*
X112080D01*
G01X108515D02*
X108140D01*
G01X109580D02*
X109206D01*
G01X105641D02*
X105540D01*
G01X104300D02*
X104200D01*
G01X101700D02*
X101600D01*
G01X97761D02*
X97660D01*
G01X100360D02*
X100260D01*
G01X116099Y242438D02*
X113442D01*
G01X112159D02*
X109502D01*
G01X108219D02*
X105561D01*
G01X104279D02*
X101622D01*
G01X100339D02*
X97681D01*
G01X116038Y242468D02*
X115663D01*
G01X113877D02*
X113502D01*
G01X112098D02*
X111724D01*
G01X108158D02*
X107783D01*
G01X109937D02*
X109562D01*
G01X105997D02*
X105622D01*
G01X102057D02*
X101682D01*
G01X104218D02*
X103843D01*
G01X98117D02*
X97742D01*
G01X100278D02*
X99904D01*
G01X98203Y242531D02*
X99817D01*
G01X106083D02*
X107697D01*
G01X102143D02*
X103757D01*
G01X110023D02*
X111637D01*
G01X113963D02*
X115577D01*
G01X113820Y242580D02*
X111780D01*
G01X109880D02*
X107840D01*
G01X105940D02*
X103900D01*
G01X102000D02*
X99960D01*
G01X115720D02*
X118720D01*
G01X97660Y241889D02*
X97681Y241888D01*
G01X101600Y241889D02*
X101622Y241888D01*
G01X105540Y241889D02*
X105561Y241888D01*
G01X99904Y242468D02*
X99878Y242452D01*
X99848Y242442D01*
X99817Y242438D01*
G01X103843Y242468D02*
X103817Y242452D01*
X103788Y242442D01*
X103757Y242438D01*
G01X107783Y242468D02*
X107757Y242452D01*
X107728Y242442D01*
X107697Y242438D01*
G01X111724Y242468D02*
X111697Y242452D01*
X111668Y242442D01*
X111637Y242438D01*
G01X115663Y242468D02*
X115637Y242452D01*
X115608Y242442D01*
X115577Y242438D01*
G01X113952D02*
X113958Y242439D01*
X113962Y242440D01*
X113963Y242441D01*
G01X110012Y242438D02*
X110018Y242439D01*
X110022Y242440D01*
X110023Y242441D01*
G01X106072Y242438D02*
X106078Y242439D01*
X106082Y242440D01*
X106083Y242441D01*
G01X102132Y242438D02*
X102138Y242439D01*
X102142Y242440D01*
X102143Y242441D01*
G01X98192Y242438D02*
X98198Y242439D01*
X98202Y242440D01*
X98203Y242441D01*
G01X104279Y241888D02*
X104300Y241889D01*
G01X100339Y241888D02*
X100360Y241889D01*
G01X116099Y241888D02*
X116209Y241908D01*
X116311Y241965D01*
X116395Y242056D01*
G01X112159Y241888D02*
X112269Y241908D01*
X112371Y241965D01*
X112455Y242056D01*
G01X108219Y241888D02*
X108330Y241908D01*
X108431Y241965D01*
X108515Y242056D01*
G01X98804Y239680D02*
G03X98304Y239180I0J-500D01*
G01X99804D02*
G03X99304Y239680I-500J0D01*
G01X102728D02*
G03X102228Y239180I0J-500D01*
G01X103728D02*
G03X103228Y239680I-500J0D01*
G01X121981Y269531D02*
Y265511D01*
G01X122720Y254034D02*
Y250530D01*
G01X122770Y258530D02*
Y254630D01*
G01X125009Y270369D02*
X125441Y269531D01*
G01X123220Y250530D02*
Y253979D01*
G01D02*
Y254101D01*
G01Y250280D02*
Y250530D01*
G01X123530Y250280D02*
Y252779D01*
G01X123770Y250530D02*
Y253979D01*
G01Y250280D02*
Y250530D01*
G01X124360Y265511D02*
Y269531D01*
G01X125170Y257880D02*
Y253350D01*
G01X125441Y269531D02*
Y265511D01*
G01X123220Y253503D02*
X123361Y253336D01*
X123458Y253152D01*
X123514Y252964D01*
X123530Y252779D01*
G01X124360Y269531D02*
X124144Y269867D01*
G01X123220Y254101D02*
X124702Y253101D01*
G01X124144Y269867D02*
X123928Y270034D01*
G01X124576Y270704D02*
X125009Y270369D01*
G01X122198Y269867D02*
X121981Y269531D01*
G01X123928Y270034D02*
X123495Y270202D01*
G01X123220Y253979D02*
X123198Y253989D01*
X123133Y253999D01*
X123031Y254010D01*
X122902Y254020D01*
X122757Y254030D01*
G01X123928Y270872D02*
X124576Y270704D01*
G01X123770Y253979D02*
X123738Y253988D01*
X123642Y253996D01*
X123489Y254005D01*
X123289Y254013D01*
X123053Y254022D01*
X122797Y254030D01*
G01X121765Y270202D02*
X122414Y270704D01*
G01Y270034D02*
X122198Y269867D01*
G01X123770Y250280D02*
X123220D01*
G01X123770D02*
X124220D01*
G01X123770Y250530D02*
X122270D01*
G01X123770Y252779D02*
X123530D01*
G01X123220Y253778D02*
X123770D01*
G01Y253979D02*
X123220D01*
G01X122757Y254030D02*
X122797D01*
G01X122757D02*
X122797D01*
G01D02*
X122785D01*
X122760Y254031D01*
X122746Y254032D01*
X122734Y254033D01*
X122720Y254034D01*
G01X122757Y254030D02*
X122751D01*
X122739Y254031D01*
X122732Y254032D01*
X122726Y254033D01*
X122720Y254034D01*
G01X125441Y265511D02*
X124360D01*
G01X123495Y270202D02*
X122846D01*
G01X123063Y270872D02*
X123928D01*
G01X122846Y270202D02*
X122414Y270034D01*
G01Y270704D02*
X123063Y270872D01*
G01X122770Y254630D02*
G03X122720Y254034I0J-300D01*
G01X124702Y253101D02*
G03X125170Y253350I168J249D01*
G01X122270Y250530D02*
Y245530D01*
G01X123220Y245780D02*
Y250280D01*
G01Y245530D02*
Y245780D01*
G01X123368Y250280D02*
Y245780D01*
G01X123530Y243281D02*
Y245780D01*
G01X123589Y250280D02*
Y245780D01*
G01X123770D02*
Y250280D01*
G01Y245530D02*
Y245780D01*
G01X123844Y250280D02*
Y245780D01*
G01X124012Y250280D02*
Y245780D01*
G01X124220Y250280D02*
Y245780D01*
G01X123530Y243281D02*
X123770D01*
G01X122270Y245530D02*
X123770D01*
G01X123220Y245780D02*
X123770D01*
G01D02*
X124220D01*
G01X125170Y242710D02*
G03X124702Y242959I-300J1D01*
G01X97329Y267856D02*
Y268861D01*
G01X97357Y253095D02*
Y250131D01*
G01X97817Y250377D02*
Y259222D01*
G01X97828Y253622D02*
Y254172D01*
G01X97857Y253622D02*
Y254172D01*
G01X97960Y253480D02*
Y249230D01*
G01X98066Y254172D02*
Y253622D01*
G01X98210D02*
Y254172D01*
G01X98339Y253622D02*
Y254172D01*
G01X98360Y253480D02*
Y254930D01*
G01X99600D02*
Y253480D01*
G01X99622Y254172D02*
Y253622D01*
G01X99750Y254172D02*
Y253622D01*
G01X99895D02*
Y254172D01*
G01X100000Y253480D02*
Y249230D01*
G01X100103Y254172D02*
Y253622D01*
G01X100132Y254172D02*
Y253622D01*
G01X100143Y250366D02*
Y259222D01*
G01X100589Y250131D02*
Y253095D01*
G01X101297D02*
Y250131D01*
G01X101757Y250377D02*
Y259222D01*
G01X101768Y253622D02*
Y254172D01*
G01X101798Y253622D02*
Y254172D01*
G01X101900Y253480D02*
Y249230D01*
G01X102006Y254172D02*
Y253622D01*
G01X102150D02*
Y254172D01*
G01X102279Y253622D02*
Y254172D01*
G01X102300Y253480D02*
Y254930D01*
G01X102519Y272044D02*
Y268861D01*
G01Y265511D02*
Y267856D01*
G01X103540Y254930D02*
Y253480D01*
G01X103561Y254172D02*
Y253622D01*
G01X103690Y254172D02*
Y253622D01*
G01X103816Y273385D02*
Y268861D01*
G01Y267856D02*
Y265511D01*
G01X103835Y253622D02*
Y254172D01*
G01X103940Y253480D02*
Y249230D01*
G01X104043Y254172D02*
Y253622D01*
G01X104072Y254172D02*
Y253622D01*
G01X104083Y250366D02*
Y259222D01*
G01X104529Y250131D02*
Y253095D01*
G01X105237D02*
Y250131D01*
G01X105697Y250377D02*
Y259222D01*
G01X105708Y253622D02*
Y254172D01*
G01X105737Y253622D02*
Y254172D01*
G01X105840Y253480D02*
Y249230D01*
G01X105940Y257880D02*
Y254180D01*
G01X105946Y254172D02*
Y253622D01*
G01X105979Y268861D02*
Y267856D01*
G01X106090Y253622D02*
Y254172D01*
G01X106219Y253622D02*
Y254172D01*
G01X106240Y253480D02*
Y254930D01*
G01X107480D02*
Y253480D01*
G01X107502Y254172D02*
Y253622D01*
G01X107630Y254172D02*
Y253622D01*
G01X107709Y265511D02*
Y270872D01*
G01X107775Y253622D02*
Y254172D01*
G01X107880Y253480D02*
Y249230D01*
G01X107983Y254172D02*
Y253622D01*
G01X108012Y254172D02*
Y253622D01*
G01X108023Y250366D02*
Y259222D01*
G01X108469Y250131D02*
Y253095D01*
G01X108790Y269699D02*
Y265511D01*
G01Y270872D02*
Y270369D01*
G01X109178Y253095D02*
Y250131D01*
G01X109637Y250377D02*
Y259222D01*
G01X109648Y253622D02*
Y254172D01*
G01X109678Y253622D02*
Y254172D01*
G01X109780Y253480D02*
Y249230D01*
G01X109885Y254172D02*
Y253622D01*
G01X110030D02*
Y254172D01*
G01X110159Y253622D02*
Y254172D01*
G01X110180Y253480D02*
Y254930D01*
G01X111169Y265511D02*
Y269531D01*
G01X111420Y254930D02*
Y253480D01*
G01X111442Y254172D02*
Y253622D01*
G01X111570Y254172D02*
Y253622D01*
G01X111715D02*
Y254172D01*
G01X111820Y253480D02*
Y249230D01*
G01X111923Y254172D02*
Y253622D01*
G01X111952Y254172D02*
Y253622D01*
G01X111963Y250366D02*
Y259222D01*
G01X112250Y269531D02*
Y265511D01*
G01X112409Y250131D02*
Y253095D01*
G01X113117D02*
Y250131D01*
G01X113577Y250377D02*
Y259222D01*
G01X113588Y253622D02*
Y254172D01*
G01X113617Y253622D02*
Y254172D01*
G01X113720Y253480D02*
Y249230D01*
G01X113826Y254172D02*
Y253622D01*
G01X113970D02*
Y254172D01*
G01X114099Y253622D02*
Y254172D01*
G01X114120Y253480D02*
Y254930D01*
G01X114629Y265511D02*
Y269531D01*
G01X114920Y256280D02*
Y254380D01*
G01Y254180D02*
Y250080D01*
G01X115710Y269531D02*
Y265511D01*
G01X117440D02*
Y270872D01*
G01X118521Y269699D02*
Y265511D01*
G01Y270872D02*
Y270369D01*
G01X120900Y265511D02*
Y269531D01*
G01X99665Y253613D02*
X99635Y253656D01*
X99623Y253687D01*
X99622Y253697D01*
G01X103605Y253613D02*
X103575Y253656D01*
X103563Y253687D01*
X103561Y253697D01*
G01X107544Y253613D02*
X107515Y253656D01*
X107503Y253687D01*
X107502Y253697D01*
G01X111485Y253613D02*
X111455Y253656D01*
X111443Y253687D01*
X111442Y253697D01*
G01X111169Y269531D02*
X110952Y269867D01*
G01X114629Y269531D02*
X114413Y269867D01*
G01X115278Y270369D02*
X115710Y269531D01*
G01X100143Y254168D02*
Y254169D01*
X100142Y254170D01*
X100141Y254171D01*
X100138Y254172D01*
X100136D01*
X100132D01*
G01X104083Y254168D02*
Y254169D01*
X104082Y254170D01*
X104080Y254171D01*
X104078Y254172D01*
X104076D01*
X104072D01*
G01X108023Y254168D02*
Y254169D01*
X108022Y254170D01*
X108020Y254171D01*
X108019Y254172D01*
X108016D01*
X108012D01*
G01X111963Y254168D02*
Y254169D01*
X111962Y254170D01*
X111960Y254171D01*
X111958Y254172D01*
X111956D01*
X111952D01*
G01X98278Y253593D02*
X98296Y253480D01*
G01X102218Y253593D02*
X102236Y253480D01*
G01X106158Y253593D02*
X106217Y253223D01*
G01X106515Y254005D02*
X106573Y253635D01*
G01X110098Y253593D02*
X110156Y253223D01*
G01X110455Y254005D02*
X110513Y253635D01*
G01X114038Y253593D02*
X114096Y253223D01*
G01X114395Y254005D02*
X114453Y253635D01*
G01X99665Y253480D02*
X99682Y253593D01*
G01X103605Y253480D02*
X103622Y253593D01*
G01X107148Y253635D02*
X107206Y254005D01*
G01X107504Y253223D02*
X107562Y253593D01*
G01X111087Y253635D02*
X111146Y254005D01*
G01X111444Y253223D02*
X111502Y253593D01*
G01X98339Y253697D02*
X98337Y253687D01*
X98325Y253656D01*
X98296Y253613D01*
G01X102279Y253697D02*
X102277Y253687D01*
X102265Y253656D01*
X102236Y253613D01*
G01X106219Y253697D02*
X106217Y253687D01*
X106206Y253656D01*
X106176Y253613D01*
G01X110159Y253697D02*
X110157Y253687D01*
X110145Y253656D01*
X110116Y253613D01*
G01X114099Y253697D02*
X114097Y253687D01*
X114085Y253656D01*
X114056Y253613D01*
G01X97904Y253593D02*
X98035Y253480D01*
G01X98360Y253919D02*
X98260Y254005D01*
G01X101843Y253593D02*
X101975Y253480D01*
G01X102300Y253919D02*
X102200Y254005D01*
G01X105940Y253459D02*
X106217Y253223D01*
G01X105783Y253593D02*
X105915Y253480D01*
G01X106515Y254005D02*
X106431Y254096D01*
X106330Y254153D01*
X106219Y254172D01*
G01X110455Y254005D02*
X110371Y254096D01*
X110269Y254153D01*
X110159Y254172D01*
G01X114395Y254005D02*
X114311Y254096D01*
X114209Y254153D01*
X114099Y254172D01*
G01X100143Y253620D02*
X100142Y253621D01*
X100138Y253622D01*
X100132D01*
G01X104083Y253620D02*
X104082Y253621D01*
X104078Y253622D01*
X104072D01*
G01X108023Y253620D02*
X108022Y253621D01*
X108018Y253622D01*
X108012D01*
G01X111963Y253620D02*
X111962Y253621D01*
X111958Y253622D01*
X111952D01*
G01X99682Y253593D02*
X99600Y253687D01*
G01X99700Y254005D02*
X100057Y253593D01*
G01X103622D02*
X103540Y253687D01*
G01X103641Y254005D02*
X103997Y253593D01*
G01X107504Y253223D02*
X107148Y253635D01*
G01X107562Y253593D02*
X107206Y254005D01*
G01X107580D02*
X107937Y253593D01*
G01X111444Y253223D02*
X111087Y253635D01*
G01X111502Y253593D02*
X111146Y254005D01*
G01X111520D02*
X111877Y253593D01*
G01X120900Y269531D02*
X120684Y269867D01*
G01X100143Y250392D02*
X100210Y250345D01*
X100280Y250301D01*
X100352Y250261D01*
X100431Y250224D01*
X100507Y250193D01*
X100589Y250166D01*
G01X104083Y250392D02*
X104150Y250345D01*
X104220Y250301D01*
X104292Y250261D01*
X104370Y250224D01*
X104447Y250193D01*
X104529Y250166D01*
G01X108023Y250392D02*
X108090Y250345D01*
X108159Y250301D01*
X108232Y250261D01*
X108311Y250224D01*
X108387Y250193D01*
X108469Y250166D01*
G01X111963Y250392D02*
X112030Y250345D01*
X112100Y250301D01*
X112172Y250261D01*
X112251Y250224D01*
X112327Y250193D01*
X112409Y250166D01*
G01X110952Y269867D02*
X110736Y270034D01*
G01X111385Y270704D02*
X112034Y270202D01*
G01X114413Y269867D02*
X114196Y270034D01*
G01X114845Y270704D02*
X115278Y270369D01*
G01X120684Y269867D02*
X120467Y270034D01*
G01X121116Y270704D02*
X121765Y270202D01*
G01X106573Y253635D02*
X106140Y254005D01*
G01X109724Y253593D02*
X110156Y253223D01*
G01X110513Y253635D02*
X110080Y254005D01*
G01X113663Y253593D02*
X114096Y253223D01*
G01X114453Y253635D02*
X114020Y254005D01*
G01X112466Y269867D02*
X112250Y269531D01*
G01X100143Y253280D02*
X100210Y253242D01*
X100280Y253206D01*
X100352Y253173D01*
X100431Y253142D01*
X100507Y253117D01*
X100589Y253095D01*
G01X104083Y253280D02*
X104150Y253242D01*
X104220Y253206D01*
X104292Y253173D01*
X104370Y253142D01*
X104447Y253117D01*
X104529Y253095D01*
G01X108023Y253280D02*
X108090Y253242D01*
X108159Y253206D01*
X108232Y253173D01*
X108311Y253142D01*
X108387Y253117D01*
X108469Y253095D01*
G01X111963Y253280D02*
X112030Y253242D01*
X112100Y253206D01*
X112172Y253173D01*
X112251Y253142D01*
X112327Y253117D01*
X112409Y253095D01*
G01X100589Y250616D02*
X100510Y250643D01*
X100434Y250673D01*
X100359Y250708D01*
X100282Y250750D01*
X100213Y250793D01*
X100143Y250843D01*
G01X104529Y250616D02*
X104450Y250643D01*
X104374Y250673D01*
X104299Y250708D01*
X104222Y250750D01*
X104153Y250793D01*
X104083Y250843D01*
G01X108469Y250616D02*
X108391Y250643D01*
X108314Y250673D01*
X108239Y250708D01*
X108162Y250750D01*
X108093Y250793D01*
X108023Y250843D01*
G01X112409Y250616D02*
X112330Y250643D01*
X112254Y250673D01*
X112179Y250708D01*
X112102Y250750D01*
X112033Y250793D01*
X111963Y250843D01*
G01X110736Y270034D02*
X110304Y270202D01*
G01X114196Y270034D02*
X113764Y270202D01*
G01X120467Y270034D02*
X120035Y270202D01*
G01X97904Y253593D02*
X98260Y254005D01*
G01X98360Y253687D02*
X98278Y253593D01*
G01X101843D02*
X102200Y254005D01*
G01X102300Y253687D02*
X102218Y253593D01*
G01X105783D02*
X106140Y254005D01*
G01X106515D02*
X106158Y253593D01*
G01X106217Y253223D02*
X106573Y253635D01*
G01X109724Y253593D02*
X110080Y254005D01*
G01X110455D02*
X110098Y253593D01*
G01X110156Y253223D02*
X110513Y253635D01*
G01X113663Y253593D02*
X114020Y254005D01*
G01X114395D02*
X114038Y253593D01*
G01X114096Y253223D02*
X114453Y253635D01*
G01X110736Y270872D02*
X111385Y270704D01*
G01X114196Y270872D02*
X114845Y270704D01*
G01X120467Y270872D02*
X121116Y270704D01*
G01X100589Y250340D02*
X100510Y250362D01*
X100434Y250387D01*
X100359Y250416D01*
X100282Y250450D01*
X100213Y250485D01*
X100143Y250526D01*
G01X104529Y250340D02*
X104450Y250362D01*
X104374Y250387D01*
X104299Y250416D01*
X104222Y250450D01*
X104153Y250485D01*
X104083Y250526D01*
G01X108469Y250340D02*
X108391Y250362D01*
X108314Y250387D01*
X108239Y250416D01*
X108162Y250450D01*
X108093Y250485D01*
X108023Y250526D01*
G01X112409Y250340D02*
X112330Y250362D01*
X112254Y250387D01*
X112179Y250416D01*
X112102Y250450D01*
X112033Y250485D01*
X111963Y250526D01*
G01X97329Y268861D02*
X102519Y273385D01*
G01X98843Y268861D02*
X102519Y272044D01*
G01X99700Y254005D02*
X99600Y253919D01*
G01X100057Y253593D02*
X99926Y253480D01*
G01X103641Y254005D02*
X103540Y253919D01*
G01X103997Y253593D02*
X103865Y253480D01*
G01X107580Y254005D02*
X107148Y253635D01*
G01X107937Y253593D02*
X107504Y253223D01*
G01X111520Y254005D02*
X111087Y253635D01*
G01X111877Y253593D02*
X111444Y253223D01*
G01X108790Y270369D02*
X109222Y270704D01*
G01Y270034D02*
X108790Y269699D01*
G01X112034Y270202D02*
X112683Y270704D01*
G01Y270034D02*
X112466Y269867D01*
G01X118521Y270369D02*
X118954Y270704D01*
G01Y270034D02*
X118521Y269699D01*
G01X97817Y253622D02*
X97848Y253619D01*
X97878Y253609D01*
X97904Y253593D01*
G01X101757Y253622D02*
X101788Y253619D01*
X101817Y253609D01*
X101843Y253593D01*
G01X105697Y253622D02*
X105728Y253619D01*
X105757Y253609D01*
X105783Y253593D01*
G01X109637Y253622D02*
X109668Y253619D01*
X109697Y253609D01*
X109724Y253593D01*
G01X113577Y253622D02*
X113608Y253619D01*
X113637Y253609D01*
X113663Y253593D01*
G01X97817Y254172D02*
X97977Y254153D01*
X98127Y254096D01*
X98260Y254005D01*
G01X101757Y254172D02*
X101917Y254153D01*
X102067Y254096D01*
X102200Y254005D01*
G01X105697Y254172D02*
X105857Y254153D01*
X106007Y254096D01*
X106140Y254005D01*
G01X109637Y254172D02*
X109797Y254153D01*
X109947Y254096D01*
X110080Y254005D01*
G01X113577Y254172D02*
X113737Y254153D01*
X113887Y254096D01*
X114020Y254005D01*
G01X99622Y253622D02*
X99640Y253619D01*
X99659Y253609D01*
X99682Y253593D01*
G01X103561Y253622D02*
X103580Y253619D01*
X103599Y253609D01*
X103622Y253593D01*
G01X107502Y253622D02*
X107520Y253619D01*
X107539Y253609D01*
X107562Y253593D01*
G01X111442Y253622D02*
X111460Y253619D01*
X111480Y253609D01*
X111502Y253593D01*
G01X97817Y250854D02*
X97751Y250806D01*
X97678Y250758D01*
X97602Y250716D01*
X97523Y250678D01*
X97442Y250645D01*
X97357Y250616D01*
G01X101757Y250854D02*
X101691Y250806D01*
X101618Y250758D01*
X101542Y250716D01*
X101463Y250678D01*
X101382Y250645D01*
X101297Y250616D01*
G01X105697Y250854D02*
X105631Y250806D01*
X105558Y250758D01*
X105482Y250716D01*
X105403Y250678D01*
X105322Y250645D01*
X105237Y250616D01*
G01X109637Y250854D02*
X109571Y250806D01*
X109498Y250758D01*
X109422Y250716D01*
X109343Y250678D01*
X109262Y250645D01*
X109178Y250616D01*
G01X113577Y250854D02*
X113511Y250806D01*
X113438Y250758D01*
X113362Y250716D01*
X113283Y250678D01*
X113202Y250645D01*
X113117Y250616D01*
G01X98278Y253593D02*
X98301Y253609D01*
X98321Y253619D01*
X98339Y253622D01*
G01X102218Y253593D02*
X102241Y253609D01*
X102261Y253619D01*
X102279Y253622D01*
G01X106158Y253593D02*
X106181Y253609D01*
X106201Y253619D01*
X106219Y253622D01*
G01X110098Y253593D02*
X110121Y253609D01*
X110141Y253619D01*
X110159Y253622D01*
G01X114038Y253593D02*
X114061Y253609D01*
X114081Y253619D01*
X114099Y253622D01*
G01X99700Y254005D02*
X99833Y254096D01*
X99984Y254153D01*
X100143Y254172D01*
G01X103641Y254005D02*
X103773Y254096D01*
X103924Y254153D01*
X104083Y254172D01*
G01X107580Y254005D02*
X107713Y254096D01*
X107864Y254153D01*
X108023Y254172D01*
G01X111520Y254005D02*
X111653Y254096D01*
X111804Y254153D01*
X111963Y254172D01*
G01X113720Y249230D02*
X111820D01*
G01X109780D02*
X107880D01*
G01X105840D02*
X103940D01*
G01X101900D02*
X100000D01*
G01X118720Y250080D02*
X114920D01*
G01X113117Y250130D02*
X112409D01*
G01X109178D02*
X108469D01*
G01X105237D02*
X104529D01*
G01X101297D02*
X100589D01*
G01Y250166D02*
X101297D01*
G01X104529D02*
X105237D01*
G01X108469D02*
X109178D01*
G01X112409D02*
X113117D01*
G01Y250340D02*
X112409D01*
G01X109178D02*
X108469D01*
G01X105237D02*
X104529D01*
G01X101297D02*
X100589D01*
G01X100143Y250616D02*
X100589D01*
G01X101297D02*
X101757D01*
G01X97357D02*
X97817D01*
G01X104083D02*
X104529D01*
G01X105237D02*
X105697D01*
G01X108023D02*
X108469D01*
G01X109178D02*
X109637D01*
G01X111963D02*
X112409D01*
G01X113117D02*
X113577D01*
G01Y250680D02*
X111963D01*
G01X109637D02*
X108023D01*
G01X111820D02*
X109780D01*
G01X103940D02*
X101900D01*
G01X105697D02*
X104083D01*
G01X100000D02*
X97960D01*
G01X101757D02*
X100143D01*
G01X105840D02*
X105940D01*
G01D02*
X107880D01*
G01X113720D02*
X117706D01*
G01X100143Y250696D02*
X101757D01*
G01X104083D02*
X105697D01*
G01X108023D02*
X109637D01*
G01X111963D02*
X113577D01*
G01Y250775D02*
X111963D01*
G01X109637D02*
X108023D01*
G01X105697D02*
X104083D01*
G01X101757D02*
X100143D01*
G01X113577Y251225D02*
X111963D01*
G01X109637D02*
X108023D01*
G01X105697D02*
X104083D01*
G01X101757D02*
X100143D01*
G01X117342Y251680D02*
X113720D01*
G01X111820D02*
X109780D01*
G01X105940D02*
X105840D01*
G01X103940D02*
X101900D01*
G01X107880D02*
X105940D01*
G01X100000D02*
X97960D01*
G01X113577Y251755D02*
X111963D01*
G01X109637D02*
X108023D01*
G01X105697D02*
X104083D01*
G01X101757D02*
X100143D01*
G01X100589Y253095D02*
X101297D01*
G01X104529D02*
X105237D01*
G01X108469D02*
X109178D01*
G01X112409D02*
X113117D01*
G01X114920Y253266D02*
X113720D01*
G01X111820D02*
X109780D01*
G01X105940D02*
X105840D01*
G01X103940D02*
X101900D01*
G01X107880D02*
X105940D01*
G01X100000D02*
X97960D01*
G01X103940Y253480D02*
X101900D01*
G01X97960D02*
X100000D01*
G01X105840D02*
X105940D01*
G01D02*
X107880D01*
G01X109780D02*
X111820D01*
G01X113720D02*
X114920D01*
G01X113577Y253529D02*
X111963D01*
G01X109637D02*
X108023D01*
G01X105697D02*
X104083D01*
G01X101757D02*
X100143D01*
G01X99682Y253593D02*
X100057D01*
G01X97904D02*
X98278D01*
G01X105783D02*
X106158D01*
G01X103622D02*
X103997D01*
G01X101843D02*
X102218D01*
G01X109724D02*
X110098D01*
G01X107562D02*
X107937D01*
G01X113663D02*
X114038D01*
G01X111502D02*
X111877D01*
G01X103561Y253622D02*
X106219D01*
G01X99622D02*
X102279D01*
G01X107502D02*
X110159D01*
G01X111442D02*
X114099D01*
G01X99600Y254005D02*
X99700D01*
G01X98260D02*
X98360D01*
G01X106140D02*
X106515D01*
G01X103540D02*
X103641D01*
G01X102200D02*
X102300D01*
G01X110080D02*
X110455D01*
G01X107206D02*
X107580D01*
G01X114020D02*
X114395D01*
G01X111146D02*
X111520D01*
G01X103561Y254172D02*
X106219D01*
G01X99622D02*
X102279D01*
G01X107502D02*
X110159D01*
G01X111442D02*
X114099D01*
G01X105940Y254180D02*
X114920D01*
G01X105697Y254220D02*
X104083D01*
G01X101757D02*
X100143D01*
G01X105940Y254380D02*
X114920D01*
G01X113577Y254722D02*
X111963D01*
G01X109637D02*
X108023D01*
G01X105697D02*
X104083D01*
G01X101757D02*
X100143D01*
G01X114120Y254930D02*
X111420D01*
G01X110180D02*
X107480D01*
G01X105940D02*
X103540D01*
G01X106240D02*
X105940D01*
G01X102300D02*
X99600D01*
G01X113577Y255072D02*
X111963D01*
G01X109637D02*
X108023D01*
G01X105697D02*
X104083D01*
G01X101757D02*
X100143D01*
G01X114920Y255127D02*
X105940D01*
G01X125170Y256280D02*
X105940D01*
G01X125170Y257880D02*
X105940D01*
G01X122770Y258530D02*
X119270D01*
G01X113577Y259222D02*
X111963D01*
G01X109637D02*
X108023D01*
G01X105697D02*
X104083D01*
G01X101757D02*
X100143D01*
G01X98360Y254171D02*
X98339Y254172D01*
G01X102300Y254171D02*
X102279Y254172D01*
G01X100057Y253593D02*
X100083Y253609D01*
X100112Y253619D01*
X100143Y253622D01*
G01X103997Y253593D02*
X104023Y253609D01*
X104052Y253619D01*
X104083Y253622D01*
G01X107937Y253593D02*
X107963Y253609D01*
X107992Y253619D01*
X108023Y253622D01*
G01X111877Y253593D02*
X111903Y253609D01*
X111932Y253619D01*
X111963Y253622D01*
G01X97817Y250535D02*
X97751Y250495D01*
X97678Y250456D01*
X97602Y250422D01*
X97523Y250391D01*
X97442Y250364D01*
X97357Y250340D01*
G01X101757Y250535D02*
X101691Y250495D01*
X101618Y250456D01*
X101542Y250422D01*
X101463Y250391D01*
X101382Y250364D01*
X101297Y250340D01*
G01X105697Y250535D02*
X105631Y250495D01*
X105558Y250456D01*
X105482Y250422D01*
X105403Y250391D01*
X105322Y250364D01*
X105237Y250340D01*
G01X109637Y250535D02*
X109571Y250495D01*
X109498Y250456D01*
X109422Y250422D01*
X109343Y250391D01*
X109262Y250364D01*
X109178Y250340D01*
G01X113577Y250535D02*
X113511Y250495D01*
X113438Y250456D01*
X113362Y250422D01*
X113283Y250391D01*
X113202Y250364D01*
X113117Y250340D01*
G01X113588Y253622D02*
X113582D01*
X113578Y253621D01*
X113577Y253620D01*
G01X109648Y253622D02*
X109642D01*
X109639Y253621D01*
X109637Y253620D01*
G01X105708Y253622D02*
X105702D01*
X105698Y253621D01*
X105697Y253620D01*
G01X101768Y253622D02*
X101762D01*
X101759Y253621D01*
X101757Y253620D01*
G01X97828Y253622D02*
X97822D01*
X97819Y253621D01*
X97817Y253620D01*
G01X103561Y254172D02*
X103540Y254171D01*
G01X99622Y254172D02*
X99600Y254171D01*
G01X113588Y254172D02*
X113585D01*
X113582D01*
X113579Y254171D01*
X113578Y254169D01*
X113577Y254168D01*
G01X109648Y254172D02*
X109645D01*
X109643D01*
X109640Y254171D01*
X109639D01*
X109638Y254169D01*
X109637Y254168D01*
G01X105708Y254172D02*
X105705D01*
X105702D01*
X105700Y254171D01*
X105698D01*
Y254169D01*
X105697Y254168D01*
G01X101768Y254172D02*
X101765D01*
X101762D01*
X101760Y254171D01*
X101759D01*
X101757Y254169D01*
Y254168D01*
G01X97828Y254172D02*
X97825D01*
X97822D01*
X97820Y254171D01*
X97819D01*
X97818Y254169D01*
X97817Y254168D01*
G01X121981Y265511D02*
X120900D01*
G01X118521D02*
X117440D01*
G01X112250D02*
X111169D01*
G01X115710D02*
X114629D01*
G01X108790D02*
X107709D01*
G01X103816D02*
X102519D01*
G01X105979Y267856D02*
X103816D01*
G01X102519D02*
X97329D01*
G01X102519Y268861D02*
X98843D01*
G01X103816D02*
X105979D01*
G01X120035Y270202D02*
X119602D01*
G01X113764D02*
X113115D01*
G01X110304D02*
X109871D01*
G01Y270872D02*
X110736D01*
G01X107709D02*
X108790D01*
G01X113331D02*
X114196D01*
G01X119602D02*
X120467D01*
G01X117440D02*
X118521D01*
G01X102519Y273385D02*
X103816D01*
G01X113115Y270202D02*
X112683Y270034D01*
G01X111442Y254172D02*
X111331Y254153D01*
X111230Y254096D01*
X111146Y254005D01*
G01X107502Y254172D02*
X107391Y254153D01*
X107289Y254096D01*
X107206Y254005D01*
G01X97357Y250166D02*
X97436Y250192D01*
X97517Y250224D01*
X97596Y250262D01*
X97672Y250304D01*
X97746Y250351D01*
X97817Y250403D01*
G01X101297Y250166D02*
X101376Y250192D01*
X101457Y250224D01*
X101536Y250262D01*
X101612Y250304D01*
X101685Y250351D01*
X101757Y250403D01*
G01X105237Y250166D02*
X105316Y250192D01*
X105397Y250224D01*
X105476Y250262D01*
X105552Y250304D01*
X105626Y250351D01*
X105697Y250403D01*
G01X109178Y250166D02*
X109256Y250192D01*
X109337Y250224D01*
X109416Y250262D01*
X109492Y250304D01*
X109566Y250351D01*
X109637Y250403D01*
G01X113117Y250166D02*
X113196Y250192D01*
X113277Y250224D01*
X113356Y250262D01*
X113432Y250304D01*
X113506Y250351D01*
X113577Y250403D01*
G01X113117Y253095D02*
X113196Y253116D01*
X113277Y253143D01*
X113356Y253174D01*
X113432Y253208D01*
X113506Y253247D01*
X113577Y253289D01*
G01X109178Y253095D02*
X109256Y253116D01*
X109337Y253143D01*
X109416Y253174D01*
X109492Y253208D01*
X109566Y253247D01*
X109637Y253289D01*
G01X105237Y253095D02*
X105316Y253116D01*
X105397Y253143D01*
X105476Y253174D01*
X105552Y253208D01*
X105626Y253247D01*
X105697Y253289D01*
G01X101297Y253095D02*
X101376Y253116D01*
X101457Y253143D01*
X101536Y253174D01*
X101612Y253208D01*
X101685Y253247D01*
X101757Y253289D01*
G01X97357Y253095D02*
X97436Y253116D01*
X97517Y253143D01*
X97596Y253174D01*
X97672Y253208D01*
X97746Y253247D01*
X97817Y253289D01*
G01X119602Y270202D02*
X118954Y270034D01*
G01Y270704D02*
X119602Y270872D01*
G01X112683Y270704D02*
X113331Y270872D01*
G01X109871Y270202D02*
X109222Y270034D01*
G01Y270704D02*
X109871Y270872D01*
G01X101297Y250130D02*
G03X101757Y250377I-421J1335D01*
G01X97357Y250130D02*
G03X97817Y250377I-421J1335D01*
G01X104083Y250366D02*
G03X104529Y250130I867J1099D01*
G01X105237D02*
G03X105697Y250377I-421J1335D01*
G01X100143Y250366D02*
G03X100589Y250130I867J1099D01*
G01X108023Y250366D02*
G03X108469Y250130I867J1099D01*
G01X109178D02*
G03X109637Y250377I-422J1335D01*
G01X111963Y250366D02*
G03X112409Y250130I867J1099D01*
G01X113117D02*
G03X113577Y250377I-421J1335D01*
G01X118070Y252360D02*
G03I-1250J0D01*
G01X98663Y242966D02*
Y245929D01*
G01X99372D02*
Y242966D01*
G01X102603D02*
Y245929D01*
G01X103311D02*
Y242966D01*
G01X106543D02*
Y245929D01*
G01X107252D02*
Y242966D01*
G01X110483D02*
Y245929D01*
G01X111192D02*
Y242966D01*
G01X114423D02*
Y245929D01*
G01X115131D02*
Y242966D01*
G01X117342Y251680D02*
X119367Y246115D01*
G01X119999Y244380D02*
X119589Y245506D01*
G01X99817Y242780D02*
X99750Y242819D01*
X99681Y242855D01*
X99609Y242888D01*
X99530Y242918D01*
X99453Y242943D01*
X99372Y242966D01*
G01X103757Y242780D02*
X103691Y242819D01*
X103621Y242855D01*
X103549Y242888D01*
X103470Y242918D01*
X103393Y242943D01*
X103311Y242966D01*
G01X99817Y245669D02*
X99750Y245716D01*
X99681Y245760D01*
X99609Y245800D01*
X99530Y245837D01*
X99453Y245868D01*
X99372Y245895D01*
G01X103757Y245669D02*
X103691Y245716D01*
X103621Y245760D01*
X103549Y245800D01*
X103470Y245837D01*
X103393Y245868D01*
X103311Y245895D01*
G01X107697Y245669D02*
X107630Y245716D01*
X107561Y245760D01*
X107489Y245800D01*
X107410Y245837D01*
X107333Y245868D01*
X107252Y245895D01*
G01X111637Y245669D02*
X111570Y245716D01*
X111501Y245760D01*
X111429Y245800D01*
X111350Y245837D01*
X111273Y245868D01*
X111192Y245895D01*
G01X115577Y245669D02*
X115511Y245716D01*
X115441Y245760D01*
X115369Y245800D01*
X115290Y245837D01*
X115213Y245868D01*
X115131Y245895D01*
G01X107697Y242780D02*
X107630Y242819D01*
X107561Y242855D01*
X107489Y242888D01*
X107410Y242918D01*
X107333Y242943D01*
X107252Y242966D01*
G01X111637Y242780D02*
X111570Y242819D01*
X111501Y242855D01*
X111429Y242888D01*
X111350Y242918D01*
X111273Y242943D01*
X111192Y242966D01*
G01X115577Y242780D02*
X115511Y242819D01*
X115441Y242855D01*
X115369Y242888D01*
X115290Y242918D01*
X115213Y242943D01*
X115131Y242966D01*
G01X99372Y245444D02*
X99450Y245418D01*
X99527Y245388D01*
X99602Y245353D01*
X99678Y245311D01*
X99748Y245267D01*
X99817Y245218D01*
G01X103311Y245444D02*
X103390Y245418D01*
X103467Y245388D01*
X103541Y245353D01*
X103618Y245311D01*
X103688Y245267D01*
X103757Y245218D01*
G01X107252Y245444D02*
X107330Y245418D01*
X107407Y245388D01*
X107481Y245353D01*
X107558Y245311D01*
X107628Y245267D01*
X107697Y245218D01*
G01X111192Y245444D02*
X111270Y245418D01*
X111347Y245388D01*
X111421Y245353D01*
X111498Y245311D01*
X111568Y245267D01*
X111637Y245218D01*
G01X115131Y245444D02*
X115210Y245418D01*
X115287Y245388D01*
X115361Y245353D01*
X115438Y245311D01*
X115508Y245267D01*
X115577Y245218D01*
G01X99372Y245721D02*
X99450Y245699D01*
X99527Y245674D01*
X99602Y245645D01*
X99678Y245611D01*
X99748Y245575D01*
X99817Y245535D01*
G01X103311Y245721D02*
X103390Y245699D01*
X103467Y245674D01*
X103541Y245645D01*
X103618Y245611D01*
X103688Y245575D01*
X103757Y245535D01*
G01X107252Y245721D02*
X107330Y245699D01*
X107407Y245674D01*
X107481Y245645D01*
X107558Y245611D01*
X107628Y245575D01*
X107697Y245535D01*
G01X111192Y245721D02*
X111270Y245699D01*
X111347Y245674D01*
X111421Y245645D01*
X111498Y245611D01*
X111568Y245575D01*
X111637Y245535D01*
G01X115131Y245721D02*
X115210Y245699D01*
X115287Y245674D01*
X115361Y245645D01*
X115438Y245611D01*
X115508Y245575D01*
X115577Y245535D01*
G01X98203Y245207D02*
X98269Y245255D01*
X98343Y245302D01*
X98419Y245345D01*
X98497Y245383D01*
X98578Y245416D01*
X98663Y245444D01*
G01X102143Y245207D02*
X102209Y245255D01*
X102282Y245302D01*
X102359Y245345D01*
X102437Y245383D01*
X102518Y245416D01*
X102603Y245444D01*
G01X106083Y245207D02*
X106149Y245255D01*
X106222Y245302D01*
X106298Y245345D01*
X106377Y245383D01*
X106458Y245416D01*
X106543Y245444D01*
G01X110023Y245207D02*
X110089Y245255D01*
X110163Y245302D01*
X110239Y245345D01*
X110317Y245383D01*
X110398Y245416D01*
X110483Y245444D01*
G01X113963Y245207D02*
X114029Y245255D01*
X114102Y245302D01*
X114178Y245345D01*
X114257Y245383D01*
X114338Y245416D01*
X114423Y245444D01*
G01X99960Y242795D02*
X102000D01*
G01X103900D02*
X105940D01*
G01X107840D02*
X109880D01*
G01X111780D02*
X113820D01*
G01X115720D02*
X118720D01*
G01X115131Y242966D02*
X114423D01*
G01X107252D02*
X106543D01*
G01X111192D02*
X110483D01*
G01X103311D02*
X102603D01*
G01X99372D02*
X98663D01*
G01X98203Y244305D02*
X99817D01*
G01X106083D02*
X107697D01*
G01X102143D02*
X103757D01*
G01X110023D02*
X111637D01*
G01X113963D02*
X115577D01*
G01X99960Y244380D02*
X102000D01*
G01X103900D02*
X105940D01*
G01X107840D02*
X109880D01*
G01X111780D02*
X113820D01*
G01X115720D02*
X119999D01*
G01X98203Y244836D02*
X99817D01*
G01X106083D02*
X107697D01*
G01X102143D02*
X103757D01*
G01X110023D02*
X111637D01*
G01X113963D02*
X115577D01*
G01X98203Y245286D02*
X99817D01*
G01X106083D02*
X107697D01*
G01X102143D02*
X103757D01*
G01X110023D02*
X111637D01*
G01X113963D02*
X115577D01*
G01Y245365D02*
X113963D01*
G01X111637D02*
X110023D01*
G01X107697D02*
X106083D01*
G01X103757D02*
X102143D01*
G01X99817D02*
X98203D01*
G01X118721Y245380D02*
X115720D01*
G01X113820D02*
X111780D01*
G01X109880D02*
X107840D01*
G01X105940D02*
X103900D01*
G01X102000D02*
X99960D01*
G01X98203D02*
X99817D01*
G01X106083D02*
X107697D01*
G01X102143D02*
X103757D01*
G01X110023D02*
X111637D01*
G01X113963D02*
X115577D01*
G01Y245444D02*
X115131D01*
G01X114423D02*
X113963D01*
G01X111637D02*
X111192D01*
G01X107697D02*
X107252D01*
G01X110483D02*
X110023D01*
G01X106543D02*
X106083D01*
G01X103757D02*
X103311D01*
G01X102603D02*
X102143D01*
G01X99817D02*
X99372D01*
G01X98663D02*
X98203D01*
G01X98663Y245721D02*
X99372D01*
G01X102603D02*
X103311D01*
G01X106543D02*
X107252D01*
G01X110483D02*
X111192D01*
G01X114423D02*
X115131D01*
G01Y245895D02*
X114423D01*
G01X107252D02*
X106543D01*
G01X111192D02*
X110483D01*
G01X103311D02*
X102603D01*
G01X99372D02*
X98663D01*
G01Y245930D02*
X99372D01*
G01X102603D02*
X103311D01*
G01X106543D02*
X107252D01*
G01X110483D02*
X111192D01*
G01X114423D02*
X115131D01*
G01X115720Y246830D02*
X113820D01*
G01X111780D02*
X109880D01*
G01X103900D02*
X102000D01*
G01X107840D02*
X105940D01*
G01X99960D02*
X98060D01*
G01X98203Y245526D02*
X98269Y245566D01*
X98343Y245604D01*
X98419Y245639D01*
X98497Y245670D01*
X98578Y245697D01*
X98663Y245721D01*
G01X102143Y245526D02*
X102209Y245566D01*
X102282Y245604D01*
X102359Y245639D01*
X102437Y245670D01*
X102518Y245697D01*
X102603Y245721D01*
G01X106083Y245526D02*
X106149Y245566D01*
X106222Y245604D01*
X106298Y245639D01*
X106377Y245670D01*
X106458Y245697D01*
X106543Y245721D01*
G01X110023Y245526D02*
X110089Y245566D01*
X110163Y245604D01*
X110239Y245639D01*
X110317Y245670D01*
X110398Y245697D01*
X110483Y245721D01*
G01X113963Y245526D02*
X114029Y245566D01*
X114102Y245604D01*
X114178Y245639D01*
X114257Y245670D01*
X114338Y245697D01*
X114423Y245721D01*
G01X98663Y245895D02*
X98585Y245869D01*
X98504Y245836D01*
X98424Y245799D01*
X98348Y245757D01*
X98275Y245710D01*
X98203Y245658D01*
G01X102603Y245895D02*
X102524Y245869D01*
X102443Y245836D01*
X102365Y245799D01*
X102288Y245757D01*
X102215Y245710D01*
X102143Y245658D01*
G01X106543Y245895D02*
X106465Y245869D01*
X106383Y245836D01*
X106304Y245799D01*
X106228Y245757D01*
X106155Y245710D01*
X106083Y245658D01*
G01X110483Y245895D02*
X110405Y245869D01*
X110323Y245836D01*
X110244Y245799D01*
X110168Y245757D01*
X110095Y245710D01*
X110023Y245658D01*
G01X114423Y245895D02*
X114344Y245869D01*
X114263Y245836D01*
X114185Y245799D01*
X114108Y245757D01*
X114035Y245710D01*
X113963Y245658D01*
G01X114423Y242966D02*
X114344Y242945D01*
X114263Y242918D01*
X114185Y242887D01*
X114108Y242853D01*
X114035Y242814D01*
X113963Y242771D01*
G01X110483Y242966D02*
X110405Y242945D01*
X110323Y242918D01*
X110244Y242887D01*
X110168Y242853D01*
X110095Y242814D01*
X110023Y242771D01*
G01X106543Y242966D02*
X106465Y242945D01*
X106383Y242918D01*
X106304Y242887D01*
X106228Y242853D01*
X106155Y242814D01*
X106083Y242771D01*
G01X102603Y242966D02*
X102524Y242945D01*
X102443Y242918D01*
X102365Y242887D01*
X102288Y242853D01*
X102215Y242814D01*
X102143Y242771D01*
G01X98663Y242966D02*
X98585Y242945D01*
X98504Y242918D01*
X98424Y242887D01*
X98348Y242853D01*
X98275Y242814D01*
X98203Y242771D01*
G01X99817Y245695D02*
G03X99372Y245930I-866J-1100D01*
G01X98663D02*
G03X98203Y245684I419J-1336D01*
G01X107697Y245695D02*
G03X107252Y245930I-866J-1100D01*
G01X106543D02*
G03X106083Y245684I419J-1336D01*
G01X103757Y245695D02*
G03X103311Y245930I-865J-1101D01*
G01X102603D02*
G03X102143Y245684I419J-1336D01*
G01X115577Y245695D02*
G03X115131Y245930I-865J-1101D01*
G01X114423D02*
G03X113963Y245684I419J-1336D01*
G01X111637Y245695D02*
G03X111192Y245930I-866J-1100D01*
G01X110483D02*
G03X110023Y245684I419J-1336D01*
G01X118720Y245380D02*
G03X119367Y246115I400J300D01*
G01X128015Y344990D02*
X127040Y343546D01*
X126066Y342824D01*
X125091Y343546D01*
X124117Y344990D01*
Y346433D01*
X125091Y347877D01*
X126066Y348599D01*
X127040Y347877D01*
X128015Y346433D01*
Y344990D01*
G01X110475Y342824D02*
Y351486D01*
G01X104142Y344268D02*
X103654Y343546D01*
X102680Y342824D01*
X101706Y343546D01*
X100731Y344990D01*
Y346433D01*
X101706Y347877D01*
X102680Y348599D01*
X103654Y347877D01*
X104142Y346433D01*
X100731D01*
G01X109014Y347877D02*
X111937D01*
G01X123022Y499230D02*
X138607Y507607D01*
G01X140247Y505094D02*
X128764Y499230D01*
G01D02*
X140247Y493367D01*
G01X138607Y490854D02*
X123022Y499230D01*
G01X111540Y502581D02*
Y518497D01*
G01Y479127D02*
Y497555D01*
G01X116461Y518497D02*
Y479127D01*
G01D02*
X111540D01*
G01Y518497D02*
X116461D01*
G01X105118Y871653D02*
Y845668D01*
G01Y871653D02*
Y845668D01*
G01X100000Y840550D02*
G03X105118Y845668I0J5118D01*
G01X100000Y840550D02*
G03X105118Y845668I0J5118D01*
G01X122736Y892519D02*
Y883464D01*
G01X123720D02*
Y892519D01*
G01X125886D02*
Y883464D01*
G01X126870D02*
Y892519D01*
G01X129035D02*
Y883464D01*
G01X130020D02*
Y892519D01*
G01X132185Y883464D02*
X130020D01*
G01X129035D02*
X126870D01*
G01X125886D02*
X123720D01*
G01X113912Y882577D02*
X113815Y882326D01*
G01X114298Y881279D02*
X114395Y881530D01*
G01X114974Y882577D02*
X114878Y882326D01*
G01X115361Y881279D02*
X115457Y881530D01*
G01X115940Y881279D02*
X116085Y881572D01*
G01Y881237D02*
X115940Y880944D01*
G01X113839Y882745D02*
X113767Y882619D01*
G01X114902Y882745D02*
X114830Y882619D01*
G01X114370Y881111D02*
X114443Y881237D01*
G01X115433Y881111D02*
X115506Y881237D01*
G01X113984Y882661D02*
X113912Y882577D01*
G01X115047Y882661D02*
X114974Y882577D01*
G01X114226Y881195D02*
X114298Y881279D01*
G01X115288Y881195D02*
X115361Y881279D01*
G01X113960Y882870D02*
X113839Y882745D01*
G01X115022Y882870D02*
X114902Y882745D01*
G01X114250Y880986D02*
X114370Y881111D01*
G01X115312Y880986D02*
X115433Y881111D01*
G01X113719Y882451D02*
X113694Y882326D01*
G01X114491Y881405D02*
X114515Y881530D01*
G01X114781Y882451D02*
X114757Y882326D01*
G01X115554Y881405D02*
X115578Y881530D01*
G01X117003Y882410D02*
X117099Y882912D01*
G01X116979Y882242D02*
X116761Y881111D01*
G01X117244Y882912D02*
X116858Y880944D01*
G01X113767Y882619D02*
X113719Y882451D01*
G01X114830Y882619D02*
X114781Y882451D01*
G01X114443Y881237D02*
X114491Y881405D01*
G01X115506Y881237D02*
X115554Y881405D01*
G01X112205Y892519D02*
Y875590D01*
G01Y892519D02*
Y875590D01*
G01X113670Y882116D02*
Y881740D01*
G01X113791Y882075D02*
Y881781D01*
G01X114272Y883464D02*
Y890845D01*
G01X114419Y881781D02*
Y882075D01*
G01X114540Y881740D02*
Y882116D01*
G01X114733D02*
Y881740D01*
G01X114854Y882075D02*
Y881781D01*
G01X115481D02*
Y882075D01*
G01X115602Y881740D02*
Y882116D01*
G01X115795Y880944D02*
Y882912D01*
G01X115940D02*
Y881279D01*
G01X116085Y881572D02*
Y881237D01*
G01X116437Y890845D02*
Y883464D01*
G01X117421D02*
Y892519D01*
G01X119587D02*
Y883464D01*
G01X120571D02*
Y892519D01*
G01X113815Y882326D02*
X113791Y882075D01*
G01X114395Y881530D02*
X114419Y881781D01*
G01X114878Y882326D02*
X114854Y882075D01*
G01X115457Y881530D02*
X115481Y881781D01*
G01X113694Y882326D02*
X113670Y882116D01*
G01X114515Y881530D02*
X114540Y881740D01*
G01X114757Y882326D02*
X114733Y882116D01*
G01X115578Y881530D02*
X115602Y881740D01*
G01X114105Y882703D02*
X113984Y882661D01*
G01X115167Y882703D02*
X115047Y882661D01*
G01X114105Y881153D02*
X114226Y881195D01*
G01X115167Y881153D02*
X115288Y881195D01*
G01X114105Y882912D02*
X113960Y882870D01*
G01X115167Y882912D02*
X115022Y882870D01*
G01X114105Y880944D02*
X114250Y880986D01*
G01X115167Y880944D02*
X115312Y880986D01*
G01X113791Y881781D02*
X113815Y881530D01*
G01X114419Y882075D02*
X114395Y882326D01*
G01X114854Y881781D02*
X114878Y881530D01*
G01X115481Y882075D02*
X115457Y882326D01*
G01X113670Y881740D02*
X113694Y881530D01*
G01X114540Y882116D02*
X114515Y882326D01*
G01X114733Y881740D02*
X114757Y881530D01*
G01X115602Y882116D02*
X115578Y882326D01*
G01X116665Y880944D02*
X116278Y882912D01*
G01X113694Y881530D02*
X113719Y881405D01*
G01X114515Y882326D02*
X114491Y882451D01*
G01X114757Y881530D02*
X114781Y881405D01*
G01X115578Y882326D02*
X115554Y882451D01*
G01X116761Y881111D02*
X116544Y882242D01*
G01X116423Y882912D02*
X116520Y882410D01*
G01X113719Y881405D02*
X113767Y881237D01*
G01X114781Y881405D02*
X114830Y881237D01*
G01X114491Y882451D02*
X114443Y882619D01*
G01X115554Y882451D02*
X115506Y882619D01*
G01X113815Y881530D02*
X113912Y881279D01*
G01X114395Y882326D02*
X114298Y882577D01*
G01X114878Y881530D02*
X114974Y881279D01*
G01X115457Y882326D02*
X115361Y882577D01*
G01X113767Y881237D02*
X113839Y881111D01*
G01X114830Y881237D02*
X114902Y881111D01*
G01X114443Y882619D02*
X114370Y882745D01*
G01X115506Y882619D02*
X115433Y882745D01*
G01X113912Y881279D02*
X113984Y881195D01*
G01X114974Y881279D02*
X115047Y881195D01*
G01X114298Y882577D02*
X114226Y882661D01*
G01X115361Y882577D02*
X115288Y882661D01*
G01X113839Y881111D02*
X113960Y880986D01*
G01X114902Y881111D02*
X115022Y880986D01*
G01X114370Y882745D02*
X114250Y882870D01*
G01X115433Y882745D02*
X115312Y882870D01*
G01X113984Y881195D02*
X114105Y881153D01*
G01X115047Y881195D02*
X115167Y881153D01*
G01X114226Y882661D02*
X114105Y882703D01*
G01X115288Y882661D02*
X115167Y882703D01*
G01X113960Y880986D02*
X114105Y880944D01*
G01X115022Y880986D02*
X115167Y880944D01*
G01X114250Y882870D02*
X114105Y882912D01*
G01X115312Y882870D02*
X115167Y882912D01*
G01X110236Y873621D02*
X107087D01*
G01X110236D02*
X107087D01*
G01X116858Y880944D02*
X116665D01*
G01X115940D02*
X115795D01*
G01X116544Y882242D02*
X116979D01*
G01X116520Y882410D02*
X117003D01*
G01X117099Y882912D02*
X117244D01*
G01X116278D02*
X116423D01*
G01X115795D02*
X115940D01*
G01X122736Y883464D02*
X120571D01*
G01X119587D02*
X117421D01*
G01X116437D02*
X114272D01*
G01X110236Y873621D02*
G03X112205Y875590I0J1969D01*
G01X107087Y873621D02*
G03X105118Y871653I0J-1969D01*
G01X110236Y873621D02*
G03X112205Y875590I0J1969D01*
G01X107087Y873621D02*
G03X105118Y871653I0J-1969D01*
G01X123720Y892519D02*
X125886D01*
G01X126870D02*
X129035D01*
G01X130020D02*
X132185D01*
G01X116142Y897637D02*
X112205Y892519D01*
G01D02*
X116142Y897637D01*
G01X114272Y890845D02*
X116437D01*
G01X112205Y892519D02*
X292126D01*
G01X117421D02*
X119587D01*
G01X120571D02*
X122736D01*
G01X116142Y897637D02*
X288189D01*
G01X116142D02*
X288189D01*
G01X160886Y-797188D02*
Y-788527D01*
X163322D01*
X164296Y-789249D01*
X164784Y-789971D01*
Y-791414D01*
X164296Y-792136D01*
X163322Y-792858D01*
X160886D01*
G01X147244Y-797188D02*
X146270Y-796467D01*
X145783Y-795745D01*
X145296Y-794301D01*
Y-791414D01*
X145783Y-789971D01*
X146270Y-789249D01*
X147244Y-788527D01*
X148219Y-789249D01*
X148706Y-789971D01*
X149193Y-791414D01*
Y-794301D01*
X148706Y-795745D01*
X148219Y-796467D01*
X147244Y-797188D01*
G01X131654D02*
X131167D01*
Y-796467D01*
X131654Y-797188D01*
G01X137500Y-789971D02*
X137987Y-789249D01*
X138962Y-788527D01*
X139936D01*
X140911Y-789249D01*
X141398Y-789971D01*
Y-791414D01*
X140911Y-792136D01*
G01X155527Y-788527D02*
X154552Y-789971D01*
X154065Y-792136D01*
Y-793579D01*
X154552Y-795745D01*
X155527Y-797188D01*
G01X140911Y-792136D02*
X138962Y-793579D01*
X137987Y-795023D01*
X137500Y-797188D01*
X141398D01*
G01X152162Y-727083D02*
X516975D01*
G01X152162D02*
X516975D01*
G01X158303Y-686768D02*
X166964D01*
G01Y-677511D02*
X158303D01*
X164799Y-680922D01*
Y-676537D01*
G01X166964Y-655587D02*
X166243Y-656562D01*
X165521Y-657049D01*
X164077Y-657536D01*
X161190D01*
X159746Y-657049D01*
X159025Y-656562D01*
X158303Y-655587D01*
X159025Y-654613D01*
X159746Y-654125D01*
X161190Y-653638D01*
X164077D01*
X165521Y-654125D01*
X166243Y-654613D01*
X166964Y-655587D01*
G01X159746Y-665331D02*
X159025Y-664844D01*
X158303Y-663870D01*
Y-662895D01*
X159025Y-661921D01*
X159746Y-661434D01*
X161190D01*
X161912Y-661921D01*
X163356Y-663870D01*
G01D02*
X164799Y-664844D01*
X166964Y-665331D01*
Y-661434D01*
G01X146407Y-490690D02*
X184052Y-447279D01*
G01X131425Y-176912D02*
X134348D01*
G01X140682Y-171137D02*
Y-179799D01*
G01X146529Y-171137D02*
Y-179799D01*
X150426D01*
G01X191630Y187157D02*
X131311Y49471D01*
G01X157365Y106568D02*
X155490Y132819D01*
G01X156275Y132847D02*
X158096Y107356D01*
G01X162683D02*
X164504Y132847D01*
G01X165290Y132819D02*
X163415Y106568D01*
G01X162237Y105471D02*
X158543D01*
G01X159274Y106259D02*
X161506D01*
G01X157365Y106568D02*
G03X158543Y105471I1178J84D01*
G01X162237D02*
G03X163415Y106568I0J1181D01*
G01X161506Y106259D02*
G03X162683Y107356I-1J1181D01*
G01X158096D02*
G03X159274Y106259I1178J84D01*
G01X131559Y132847D02*
X133380Y107356D01*
G01X139788Y132847D02*
X137967Y107356D01*
G01X140574Y132819D02*
X138698Y106568D01*
G01X137520Y105471D02*
X133827D01*
G01X136789Y106259D02*
X134558D01*
G01X132649Y106568D02*
G03X133827Y105471I1178J84D01*
G01X137520D02*
G03X138698Y106568I0J1181D01*
G01X136789Y106259D02*
G03X137967Y107356I0J1181D01*
G01X133380D02*
G03X134558Y106259I1178J84D01*
G01X155686Y133030D02*
X156079D01*
G01X164701D02*
X165093D01*
G01X164701D02*
G03X164504Y132847I-1J-197D01*
G01X156275D02*
G03X156079Y133030I-196J-14D01*
G01X155686D02*
G03X155490Y132819I0J-197D01*
G01X140377Y133030D02*
X139985D01*
G01X131559Y132847D02*
G03X131363Y133030I-196J-14D01*
G01X140574Y132819D02*
G03X140377Y133030I-196J14D01*
G01X139985D02*
G03X139788Y132847I-1J-197D01*
G01X159309Y167322D02*
Y177374D01*
G01X161360D02*
Y167322D01*
G01X162867Y158786D02*
X164836Y158097D01*
G01X156112Y158786D02*
X162867D01*
G01Y159770D02*
X156112D01*
G01X161360Y167322D02*
X159309D01*
G01X162867Y159770D02*
X164836Y160459D01*
G01X163681Y153542D02*
G03I-1870J0D01*
G01X163386D02*
G03I-1575J0D01*
G01X156112Y159770D02*
G03Y158786I0J-492D01*
G01X162867D02*
G03Y159770I0J492D01*
G01X155866Y144819D02*
X155998Y144686D01*
G01X157244Y143647D02*
X157310Y143580D01*
G01X158031Y144819D02*
X158163Y144686D01*
G01X158589Y143614D02*
X158688Y143479D01*
G01X158557Y144183D02*
X158655Y144049D01*
G01X159574Y144652D02*
X159475Y144786D01*
G01X155965Y144082D02*
X156030Y143982D01*
G01X155866Y144552D02*
X155801Y144652D01*
G01X157146Y143513D02*
X157080Y143614D01*
G01X158130Y144082D02*
X158196Y143982D01*
G01X158031Y144552D02*
X157966Y144652D01*
G01X158786Y143614D02*
X158720Y143714D01*
G01X158688Y144284D02*
X158754Y144183D01*
G01X159443Y144552D02*
X159377Y144652D01*
G01X155899Y143848D02*
X155833Y143982D01*
G01X157211Y143714D02*
X157244Y143647D01*
G01X158065Y143848D02*
X157999Y143982D01*
G01X158491Y144351D02*
X158557Y144183D01*
G01X159639Y144484D02*
X159574Y144652D01*
G01X157080Y143614D02*
X157047Y143714D01*
G01X158557D02*
X158589Y143614D01*
G01X158655Y144384D02*
X158688Y144284D01*
G01X159475Y144451D02*
X159443Y144552D01*
G01X156030Y143982D02*
X156063Y143848D01*
G01X155998Y144686D02*
X156030Y144552D01*
G01X158196Y143982D02*
X158228Y143848D01*
G01X158163Y144686D02*
X158196Y144552D01*
G01X155407Y144082D02*
Y144216D01*
G01X155866Y144484D02*
Y144552D01*
G01X155899Y143714D02*
Y143848D01*
G01X156030Y144552D02*
Y144484D01*
G01X156063Y143848D02*
Y143714D01*
G01X156326Y143915D02*
Y144082D01*
G01X156785D02*
Y143915D01*
G01X157572Y144082D02*
Y144216D01*
G01X158031Y144484D02*
Y144552D01*
G01X158065Y143714D02*
Y143848D01*
G01X158196Y144552D02*
Y144484D01*
G01X158228Y143848D02*
Y143714D01*
G01X158491Y144484D02*
Y144351D01*
G01X158655Y144451D02*
Y144384D01*
G01X159475D02*
Y144451D01*
G01X159508Y144082D02*
Y144016D01*
G01X159672D02*
Y144250D01*
G01X159935Y144418D02*
Y144686D01*
G01X160131Y143345D02*
Y144652D01*
G01X160328Y144920D02*
Y143345D01*
G01X160591Y144418D02*
Y144686D01*
G01X160787Y143345D02*
Y144652D01*
G01X160984Y144920D02*
Y143345D01*
G01X158688Y143479D02*
X158852Y143379D01*
G01X158655Y144049D02*
X158819Y143949D01*
G01X159475Y144786D02*
X159311Y144887D01*
G01X155833Y143982D02*
X155735Y144049D01*
G01X157244Y143446D02*
X157146Y143513D01*
G01X155801Y144652D02*
X155702Y144719D01*
G01X157999Y143982D02*
X157900Y144049D01*
G01X158885Y143546D02*
X158786Y143614D01*
G01X157966Y144652D02*
X157868Y144719D01*
G01X158754Y144183D02*
X158852Y144116D01*
G01X159377Y144652D02*
X159278Y144719D01*
G01X159672Y144250D02*
X159639Y144484D01*
G01Y143781D02*
X159672Y144016D01*
G01X159508D02*
X159475Y143814D01*
G01X156030Y144484D02*
X155998Y144351D01*
G01X155801Y144149D02*
X155965Y144082D01*
G01X157966Y144149D02*
X158130Y144082D01*
G01X157376Y143379D02*
X157244Y143446D01*
G01X157310Y143580D02*
X157376Y143546D01*
G01X155735Y144887D02*
X155866Y144819D01*
G01X157900Y144887D02*
X158031Y144819D01*
G01X157080Y144552D02*
X157113Y144686D01*
G01X158196Y144484D02*
X158163Y144351D01*
G01X156063Y143714D02*
X156030Y143614D01*
G01X158228Y143714D02*
X158196Y143614D01*
G01X158688Y144552D02*
X158655Y144451D01*
G01X159443Y144284D02*
X159475Y144384D01*
G01Y143814D02*
X159443Y143714D01*
G01X155341Y143345D02*
X155210Y143379D01*
G01X157507Y143345D02*
X157376Y143379D01*
G01X158983Y143513D02*
X158885Y143546D01*
G01X158852Y144116D02*
X158950Y144082D01*
G01X159278Y144719D02*
X159180Y144753D01*
G01X158557Y144652D02*
X158491Y144484D01*
G01X159574Y143614D02*
X159639Y143781D01*
G01X155801Y144351D02*
X155866Y144484D01*
G01Y143647D02*
X155899Y143714D01*
G01X157966Y144351D02*
X158031Y144484D01*
G01Y143647D02*
X158065Y143714D01*
G01X155506Y144920D02*
X155735Y144887D01*
G01X157671Y144920D02*
X157900Y144887D01*
G01X155735Y144049D02*
X155538Y144082D01*
G01X157900Y144049D02*
X157704Y144082D01*
G01X155210Y143546D02*
X155374Y143513D01*
G01X157376Y143546D02*
X157539Y143513D01*
G01X158852Y143379D02*
X159016Y143345D01*
G01X158819Y143949D02*
X158983Y143915D01*
G01X155702Y144719D02*
X155538Y144753D01*
G01X157868Y144719D02*
X157704Y144753D01*
G01X159311Y144887D02*
X159147Y144920D01*
G01X155998Y144351D02*
X155932Y144250D01*
G01X156030Y143614D02*
X155965Y143513D01*
G01X157310Y144652D02*
X157244Y144552D01*
G01X158163Y144351D02*
X158097Y144250D01*
G01X158754Y144652D02*
X158688Y144552D01*
G01X158196Y143614D02*
X158130Y143513D01*
G01X159377Y144183D02*
X159443Y144284D01*
G01Y143714D02*
X159377Y143614D01*
G01X160328Y143345D02*
X160131D01*
G01X160984D02*
X160787D01*
G01X155604D02*
X155341D01*
G01X157769D02*
X157507D01*
G01X159016D02*
X159147D01*
G01X159180Y143513D02*
X158983D01*
G01X155374D02*
X155571D01*
G01X157539D02*
X157736D01*
G01X158720Y143714D02*
X158557D01*
G01X157047D02*
X157211D01*
G01X156785Y143915D02*
X156326D01*
G01X158983D02*
X159147D01*
G01X155538Y144082D02*
X155407D01*
G01X157704D02*
X157572D01*
G01X156326D02*
X156785D01*
G01X158950D02*
X159180D01*
G01X155407Y144216D02*
X155538D01*
G01X157572D02*
X157704D01*
G01X158655Y144786D02*
X158557Y144652D01*
G01X159475Y143479D02*
X159574Y143614D01*
G01X159935Y144686D02*
X160131Y144920D01*
G01Y144652D02*
X159935Y144418D01*
G01X160591Y144686D02*
X160787Y144920D01*
G01Y144652D02*
X160591Y144418D01*
G01X157244Y144552D02*
X157080D01*
G01X159180Y144753D02*
X158950D01*
G01X155538D02*
X155407D01*
G01X157704D02*
X157572D01*
G01X159147Y144920D02*
X158983D01*
G01X155440D02*
X155506D01*
G01X157605D02*
X157671D01*
G01X160131D02*
X160328D01*
G01X160787D02*
X160984D01*
G01X155735Y144284D02*
X155801Y144351D01*
G01Y143580D02*
X155866Y143647D01*
G01X157113Y144686D02*
X157244Y144819D01*
G01X157900Y144284D02*
X157966Y144351D01*
G01Y143580D02*
X158031Y143647D01*
G01X159147Y143345D02*
X159311Y143379D01*
G01X157736Y143513D02*
X157900Y143546D01*
G01X159147Y143915D02*
X159311Y143949D01*
G01X155571Y143513D02*
X155735Y143546D01*
G01X158983Y144920D02*
X158819Y144887D01*
G01X157572Y144753D02*
X157408Y144719D01*
G01X155407Y144753D02*
X155243Y144719D01*
G01X157376Y144887D02*
X157605Y144920D01*
G01X155210Y144887D02*
X155440Y144920D01*
G01X157900Y143379D02*
X157769Y143345D01*
G01X155735Y143379D02*
X155604Y143345D01*
G01X155932Y144250D02*
X155801Y144149D01*
G01X158097Y144250D02*
X157966Y144149D01*
G01X157408Y144719D02*
X157310Y144652D01*
G01X155965Y143513D02*
X155866Y143446D01*
G01X158852Y144719D02*
X158754Y144652D01*
G01X158130Y143513D02*
X158031Y143446D01*
G01X159278Y144116D02*
X159377Y144183D01*
G01X159311Y143949D02*
X159508Y144082D01*
G01X159377Y143614D02*
X159278Y143546D01*
G01X158819Y144887D02*
X158655Y144786D01*
G01X159311Y143379D02*
X159475Y143479D01*
G01X157244Y144819D02*
X157376Y144887D01*
G01X155735Y143546D02*
X155801Y143580D01*
G01X155866Y143446D02*
X155735Y143379D01*
G01X157900Y143546D02*
X157966Y143580D01*
G01X158031Y143446D02*
X157900Y143379D01*
G01X155538Y144216D02*
X155735Y144284D01*
G01X158950Y144753D02*
X158852Y144719D01*
G01X157704Y144216D02*
X157900Y144284D01*
G01X159180Y144082D02*
X159278Y144116D01*
G01Y143546D02*
X159180Y143513D01*
G01X144510Y154155D02*
X144634Y154028D01*
G01X144478Y153901D02*
X144416Y153996D01*
G01X144634Y154028D02*
X144665Y153901D01*
G01X133976Y153773D02*
Y154028D01*
G01X134163Y152755D02*
Y153996D01*
G01X134293Y167322D02*
Y177374D01*
G01X134350Y154251D02*
Y152755D01*
G01X136344Y177374D02*
Y167322D01*
G01X140855D02*
Y177374D01*
G01X142905D02*
Y167322D01*
G01X143543Y152755D02*
Y152914D01*
G01X144478Y153837D02*
Y153901D01*
G01X144665Y152914D02*
Y152755D01*
G01Y153901D02*
Y153837D01*
G01X146186Y167322D02*
Y180724D01*
G01X148237Y177792D02*
Y167322D01*
G01X152748D02*
Y177374D01*
G01X154798D02*
Y167322D01*
G01X144416Y153996D02*
X144323Y154060D01*
G01X143575Y153901D02*
X143606Y154028D01*
G01X144665Y153837D02*
X144634Y153710D01*
G01X144385Y154219D02*
X144510Y154155D01*
G01X133196Y159770D02*
X131228Y160459D01*
G01X139951Y158786D02*
X141920Y158097D01*
G01X156112Y159770D02*
X154144Y160459D01*
G01X144416Y153710D02*
X144478Y153837D01*
G01X144198Y154251D02*
X144385Y154219D01*
G01X144323Y154060D02*
X144167Y154092D01*
G01X143793Y153996D02*
X143730Y153901D01*
G01X144634Y153710D02*
X144572Y153614D01*
G01X133976Y154028D02*
X134163Y154251D01*
G01Y153996D02*
X133976Y153773D01*
G01X144665Y152755D02*
X143543D01*
G01X134350D02*
X134163D01*
G01X143793Y152914D02*
X144665D01*
G01X143730Y153901D02*
X143575D01*
G01X144167Y154092D02*
X144042D01*
G01X134163Y154251D02*
X134350D01*
G01X144073D02*
X144198D01*
G01X141920Y158097D02*
X131228D01*
G01X154144D02*
X164836D01*
G01X139951Y158786D02*
X133196D01*
G01Y159770D02*
X139951D01*
G01X164836Y160459D02*
X154144D01*
G01X131228D02*
X141920D01*
G01X154798Y167322D02*
X152748D01*
G01X148237D02*
X146186D01*
G01X142905D02*
X140855D01*
G01X136344D02*
X134293D01*
G01X143606Y154028D02*
X143730Y154155D01*
G01X143543Y152914D02*
X144416Y153710D01*
G01X143855Y154219D02*
X144073Y154251D01*
G01X144572Y153614D02*
X143793Y152914D01*
G01X144042Y154092D02*
X143886Y154060D01*
G01D02*
X143793Y153996D01*
G01X143730Y154155D02*
X143855Y154219D01*
G01X133196Y158786D02*
X131228Y158097D01*
G01X139951Y159770D02*
X141920Y160459D01*
G01X156112Y158786D02*
X154144Y158097D01*
G01X136122Y153542D02*
G03I-1870J0D01*
G01X145965D02*
G03I-1870J0D01*
G01X153839D02*
G03I-1870J0D01*
G01X153543D02*
G03I-1574J0D01*
G01X145669D02*
G03I-1574J0D01*
G01X135827D02*
G03I-1575J0D01*
G01X154144Y160459D02*
G03Y158097I0J-1181D01*
G01X141920D02*
G03Y160459I0J1181D01*
G01X139951Y158786D02*
G03Y159770I0J492D01*
G01X133196D02*
G03Y158786I0J-492D01*
G01X141594Y143446D02*
X141463Y143580D01*
G01X142448Y144819D02*
X142579Y144686D01*
G01X149961Y144016D02*
X149895Y144082D01*
G01X150092Y144116D02*
X149994Y144216D01*
G01X152848Y144016D02*
X152782Y144082D01*
G01X152979Y144116D02*
X152881Y144216D01*
G01X155079Y143647D02*
X155144Y143580D01*
G01X149075Y143614D02*
X149173Y143479D01*
G01X150059Y144652D02*
X149961Y144786D01*
G01X151962Y143614D02*
X152061Y143479D01*
G01X152946Y144652D02*
X152848Y144786D01*
G01X146385Y144149D02*
X145827Y144920D01*
G01X146943Y143345D02*
X146483Y143982D01*
G01X146024Y144920D02*
X146483Y144284D01*
G01X146581Y144149D02*
X147139Y143345D01*
G01X141660Y143647D02*
X141594Y143747D01*
G01X142382Y144619D02*
X142448Y144518D01*
G01X149206Y143714D02*
X149272Y143614D01*
G01X149862Y144652D02*
X149928Y144552D01*
G01X152093Y143714D02*
X152159Y143614D01*
G01X152750Y144652D02*
X152815Y144552D01*
G01X154980Y143513D02*
X154915Y143614D01*
G01X141463Y143580D02*
X141398Y143714D01*
G01X142579Y144686D02*
X142644Y144552D01*
G01X155046Y143714D02*
X155079Y143647D01*
G01X149009Y143781D02*
X149075Y143614D01*
G01X150157Y143949D02*
X150092Y144116D01*
G01X151896Y143781D02*
X151962Y143614D01*
G01X153045Y143949D02*
X152979Y144116D01*
G01X140184Y143345D02*
X139724Y144585D01*
G01X139823Y144920D02*
X140315Y143513D01*
G01X149173Y143814D02*
X149206Y143714D01*
G01X149994Y143915D02*
X149961Y144016D01*
G01X150092Y144552D02*
X150059Y144652D01*
G01X152061Y143814D02*
X152093Y143714D01*
G01X152881Y143915D02*
X152848Y144016D01*
G01X152979Y144552D02*
X152946Y144652D01*
G01X154915Y143614D02*
X154882Y143714D01*
G01X141594Y143747D02*
X141562Y143881D01*
G01X142448Y144518D02*
X142480Y144384D01*
G01X141398Y143714D02*
X141365Y143881D01*
G01X142644Y144552D02*
X142677Y144384D01*
G01X148976Y144016D02*
X149009Y143781D01*
G01X151864Y144016D02*
X151896Y143781D01*
G01X139528Y143345D02*
Y144920D01*
G01X139724Y144585D02*
Y143345D01*
G01X140906D02*
Y144585D01*
G01X141102Y144920D02*
Y143345D01*
G01X141365Y143881D02*
Y144384D01*
G01X141562Y143881D02*
Y144384D01*
G01X142480D02*
Y143881D01*
G01X142677Y144384D02*
Y143881D01*
G01X142940Y143345D02*
Y144920D01*
G01X143137D02*
Y143546D01*
G01X144121D02*
Y143345D01*
G01X144383D02*
Y144920D01*
G01X144580Y144082D02*
Y143546D01*
G01Y144719D02*
Y144284D01*
G01X145433D02*
Y144082D01*
G01X145565Y144920D02*
Y144719D01*
G01Y143546D02*
Y143345D01*
G01X148976Y144250D02*
Y144016D01*
G01X149141Y144183D02*
Y144250D01*
G01X149173Y143915D02*
Y143814D01*
G01X149994D02*
Y143915D01*
G01X150157Y143781D02*
Y143949D01*
G01X150420Y144753D02*
Y144920D01*
G01X151601D02*
Y144753D01*
G01X151864Y144250D02*
Y144016D01*
G01X152028Y144183D02*
Y144250D01*
G01X152061Y143915D02*
Y143814D01*
G01X152881D02*
Y143915D01*
G01X153045Y143781D02*
Y143949D01*
G01X153307Y143814D02*
Y144016D01*
G01X154094Y144652D02*
Y144016D01*
G01Y143345D02*
Y143814D01*
G01X154291D02*
Y143345D01*
G01Y144920D02*
Y144016D01*
G01X154620D02*
Y143814D01*
G01X149173Y143479D02*
X149337Y143379D01*
G01X149994Y144216D02*
X149830Y144317D01*
G01X152061Y143479D02*
X152224Y143379D01*
G01X149961Y144786D02*
X149797Y144887D01*
G01X152881Y144216D02*
X152717Y144317D01*
G01X152848Y144786D02*
X152684Y144887D01*
G01X141759Y143580D02*
X141660Y143647D01*
G01X142283Y144686D02*
X142382Y144619D01*
G01X149272Y143614D02*
X149370Y143546D01*
G01X149895Y144082D02*
X149797Y144149D01*
G01X149764Y144719D02*
X149862Y144652D01*
G01X152159Y143614D02*
X152257Y143546D01*
G01X152782Y144082D02*
X152684Y144149D01*
G01X152651Y144719D02*
X152750Y144652D01*
G01X155079Y143446D02*
X154980Y143513D01*
G01X149009Y144484D02*
X148976Y144250D01*
G01X151896Y144484D02*
X151864Y144250D01*
G01X149141D02*
X149173Y144451D01*
G01X152028Y144250D02*
X152061Y144451D01*
G01X141365Y144384D02*
X141398Y144552D01*
G01X142677Y143881D02*
X142644Y143714D01*
G01X141562Y144384D02*
X141594Y144518D01*
G01X142480Y143881D02*
X142448Y143747D01*
G01X154915Y144552D02*
X154948Y144686D01*
G01X141726Y143379D02*
X141594Y143446D01*
G01X142317Y144887D02*
X142448Y144819D01*
G01X155210Y143379D02*
X155079Y143446D01*
G01X155144Y143580D02*
X155210Y143546D01*
G01X149173Y144451D02*
X149206Y144552D01*
G01Y144016D02*
X149173Y143915D01*
G01X149961Y143714D02*
X149994Y143814D01*
G01X152061Y144451D02*
X152093Y144552D01*
G01Y144016D02*
X152061Y143915D01*
G01X152848Y143714D02*
X152881Y143814D01*
G01X140315Y143513D02*
X140807Y144920D01*
G01X140906Y144585D02*
X140446Y143345D01*
G01X149075Y144652D02*
X149009Y144484D01*
G01X150092Y143614D02*
X150157Y143781D01*
G01X151962Y144652D02*
X151896Y144484D01*
G01X152979Y143614D02*
X153045Y143781D01*
G01X141890Y143546D02*
X141759Y143580D01*
G01X142152Y144719D02*
X142283Y144686D01*
G01X149370Y143546D02*
X149469Y143513D01*
G01X149797Y144149D02*
X149698Y144183D01*
G01X152257Y143546D02*
X152356Y143513D01*
G01X149665Y144753D02*
X149764Y144719D01*
G01X152684Y144149D02*
X152585Y144183D01*
G01X152553Y144753D02*
X152651Y144719D01*
G01X150748Y143345D02*
X151404Y144753D01*
G01X151601D02*
X150945Y143345D01*
G01X141398Y144552D02*
X141463Y144686D01*
G01X142644Y143714D02*
X142579Y143580D01*
G01X141890Y143345D02*
X141726Y143379D01*
G01X149337D02*
X149502Y143345D01*
G01X142152Y144920D02*
X142317Y144887D01*
G01X152224Y143379D02*
X152389Y143345D01*
G01X149830Y144317D02*
X149665Y144351D01*
G01X149797Y144887D02*
X149633Y144920D01*
G01X152717Y144317D02*
X152553Y144351D01*
G01X152684Y144887D02*
X152520Y144920D01*
G01X141594Y144518D02*
X141660Y144619D01*
G01X142448Y143747D02*
X142382Y143647D01*
G01X149206Y144552D02*
X149272Y144652D01*
G01X149895Y143614D02*
X149961Y143714D01*
G01X152093Y144552D02*
X152159Y144652D01*
G01X152782Y143614D02*
X152848Y143714D01*
G01X155144Y144652D02*
X155079Y144552D01*
G01X145827Y143345D02*
X146385Y144149D01*
G01X154291Y143345D02*
X154094D01*
G01X150945D02*
X150748D01*
G01X145565D02*
X144383D01*
G01X147139D02*
X146943D01*
G01X146024D02*
X145827D01*
G01X141102D02*
X140906D01*
G01X139724D02*
X139528D01*
G01X140446D02*
X140184D01*
G01X142152D02*
X141890D01*
G01X144121D02*
X142940D01*
G01X149502D02*
X149665D01*
G01X152389D02*
X152553D01*
G01X149469Y143513D02*
X149698D01*
G01X152356D02*
X152585D01*
G01X142152Y143546D02*
X141890D01*
G01X143137D02*
X144121D01*
G01X144580D02*
X145565D01*
G01X154882Y143714D02*
X155046D01*
G01X154094Y143814D02*
X153307D01*
G01X154620D02*
X154291D01*
G01X154094Y144016D02*
X153537D01*
G01X154291D02*
X154620D01*
G01X145433Y144082D02*
X144580D01*
G01X149698Y144183D02*
X149469D01*
G01X152585D02*
X152356D01*
G01X144580Y144284D02*
X145433D01*
G01X149665Y144351D02*
X149502D01*
G01X152553D02*
X152389D01*
G01X146483Y144284D02*
X146943Y144920D01*
G01X146483Y143982D02*
X146024Y143345D01*
G01X147139Y144920D02*
X146581Y144149D01*
G01X149173Y144786D02*
X149075Y144652D01*
G01X149994Y143479D02*
X150092Y143614D01*
G01X152061Y144786D02*
X151962Y144652D01*
G01X152881Y143479D02*
X152979Y143614D01*
G01X155079Y144552D02*
X154915D01*
G01X149928D02*
X150092D01*
G01X152815D02*
X152979D01*
G01X145565Y144719D02*
X144580D01*
G01X141890D02*
X142152D01*
G01X151404Y144753D02*
X150420D01*
G01X149469D02*
X149665D01*
G01X152356D02*
X152553D01*
G01X149633Y144920D02*
X149502D01*
G01X152520D02*
X152389D01*
G01X140807D02*
X141102D01*
G01X139528D02*
X139823D01*
G01X141890D02*
X142152D01*
G01X142940D02*
X143137D01*
G01X144383D02*
X145565D01*
G01X146943D02*
X147139D01*
G01X145827D02*
X146024D01*
G01X150420D02*
X151601D01*
G01X154094D02*
X154291D01*
G01X153307Y144016D02*
X154094Y144920D01*
G01X153537Y144016D02*
X154094Y144652D01*
G01X141463Y144686D02*
X141594Y144819D01*
G01X142579Y143580D02*
X142448Y143446D01*
G01X149272Y144082D02*
X149206Y144016D01*
G01X152159Y144082D02*
X152093Y144016D01*
G01X154948Y144686D02*
X155079Y144819D01*
G01X152553Y143345D02*
X152717Y143379D01*
G01X149665Y143345D02*
X149830Y143379D01*
G01X152389Y144351D02*
X152224Y144317D01*
G01X152389Y144920D02*
X152224Y144887D01*
G01X149502Y144351D02*
X149337Y144317D01*
G01X142317Y143379D02*
X142152Y143345D01*
G01X149502Y144920D02*
X149337Y144887D01*
G01X142283Y143580D02*
X142152Y143546D01*
G01X141759Y144686D02*
X141890Y144719D01*
G01X141726Y144887D02*
X141890Y144920D01*
G01X141660Y144619D02*
X141759Y144686D01*
G01X142382Y143647D02*
X142283Y143580D01*
G01X149272Y144652D02*
X149370Y144719D01*
G01X149337Y144317D02*
X149141Y144183D01*
G01X149370Y144149D02*
X149272Y144082D01*
G01X149797Y143546D02*
X149895Y143614D01*
G01X152159Y144652D02*
X152257Y144719D01*
G01X152224Y144317D02*
X152028Y144183D01*
G01X152257Y144149D02*
X152159Y144082D01*
G01X152684Y143546D02*
X152782Y143614D01*
G01X155243Y144719D02*
X155144Y144652D01*
G01X149337Y144887D02*
X149173Y144786D01*
G01X152224Y144887D02*
X152061Y144786D01*
G01X149830Y143379D02*
X149994Y143479D01*
G01X152717Y143379D02*
X152881Y143479D01*
G01X141594Y144819D02*
X141726Y144887D01*
G01X142448Y143446D02*
X142317Y143379D01*
G01X155079Y144819D02*
X155210Y144887D01*
G01X149370Y144719D02*
X149469Y144753D01*
G01Y144183D02*
X149370Y144149D01*
G01X152257Y144719D02*
X152356Y144753D01*
G01X149698Y143513D02*
X149797Y143546D01*
G01X152356Y144183D02*
X152257Y144149D01*
G01X152585Y143513D02*
X152684Y143546D01*
G01X158489Y180724D02*
X159720Y180305D01*
G01X156849Y180724D02*
X158489D01*
G01X155619Y180305D02*
X156849Y180724D01*
G01X159309Y177374D02*
X158899Y178211D01*
G01X160540Y179468D02*
X161360Y177374D01*
G01X158899Y178211D02*
X158489Y178630D01*
G01X159720Y180305D02*
X160540Y179468D01*
G01X158489Y178630D02*
X157669Y179049D01*
G01D02*
X156439D01*
G01X155619Y178630D02*
X155208Y178211D01*
G01X156439Y179049D02*
X155619Y178630D01*
G01X133473Y180724D02*
X134703Y180305D01*
G01X140035Y180724D02*
X141265Y180305D01*
G01X151928Y180724D02*
X153158Y180305D01*
G01X131832Y180724D02*
X133473D01*
G01X138394D02*
X140035D01*
G01X146186D02*
X148237D01*
G01X150287D02*
X151928D01*
G01X137164Y180305D02*
X138394Y180724D01*
G01X149057Y180305D02*
X150287Y180724D01*
G01X133883Y178211D02*
X133473Y178630D01*
G01X134703Y180305D02*
X135933Y179049D01*
G01X134293Y177374D02*
X133883Y178211D01*
G01X140855Y177374D02*
X140444Y178211D01*
G01X152748Y177374D02*
X152338Y178211D01*
G01X142085Y179468D02*
X142905Y177374D01*
G01X148237Y180724D02*
Y179468D01*
G01X140444Y178211D02*
X140035Y178630D01*
G01X141265Y180305D02*
X142085Y179468D01*
G01X152338Y178211D02*
X151928Y178630D01*
G01X153158Y180305D02*
X154388Y179049D01*
G01X133473Y178630D02*
X132653Y179049D01*
G01X140035Y178630D02*
X139214Y179049D01*
G01X151928Y178630D02*
X151107Y179049D01*
G01X136754Y178211D02*
X136344Y177374D01*
G01X155208Y178211D02*
X154798Y177374D01*
G01X135933Y179049D02*
X137164Y180305D01*
G01Y178630D02*
X136754Y178211D01*
G01X151107Y179049D02*
X150287D01*
G01X139214D02*
X137984D01*
G01X132653D02*
X131832D01*
G01X148237Y179468D02*
X149057Y180305D01*
G01Y178630D02*
X148237Y177792D01*
G01X154388Y179049D02*
X155619Y180305D01*
G01X137984Y179049D02*
X137164Y178630D01*
G01X150287Y179049D02*
X149057Y178630D01*
G01X157247Y348599D02*
Y342824D01*
G01X163581D02*
Y348599D01*
G01X131912D02*
Y339937D01*
G01X147990Y342824D02*
Y348599D01*
G01X131912Y346433D02*
X132887Y347877D01*
X133861Y348599D01*
X134835Y347877D01*
X135810Y346433D01*
Y344990D01*
X134835Y343546D01*
X133861Y342824D01*
X132887D01*
X131912Y344990D01*
G01X143118Y344268D02*
X142631Y343546D01*
X141656Y342824D01*
X140682Y343546D01*
X139707Y344990D01*
Y346433D01*
X140682Y347877D01*
X141656Y348599D01*
X142631Y347877D01*
X143118Y346433D01*
X139707D01*
G01X147990Y347155D02*
X148965Y348599D01*
X149939D01*
X150913Y347155D01*
Y342824D01*
G01X157247Y351486D02*
Y350764D01*
G01X163581Y347155D02*
X164555Y348599D01*
X165530D01*
X166504Y347155D01*
Y342824D01*
G01X147629Y509282D02*
X148449Y512633D01*
G01X140247Y493367D02*
X138607Y490854D01*
G01X153370Y511795D02*
X151730Y509282D01*
G01X138607Y507607D02*
X140247Y505094D01*
G01X155831Y513471D02*
X153370Y511795D01*
G01X151730Y509282D02*
X147629D01*
G01X146809Y479127D02*
Y483315D01*
G01D02*
X169774Y504256D01*
G01X173876Y501743D02*
X153370Y483315D01*
G01X176336Y479127D02*
X146809D01*
G01X153370Y483315D02*
X176336D01*
G01X164033Y518497D02*
X168954Y517659D01*
G01X160752Y518497D02*
X164033D01*
G01X167314Y513471D02*
X163213Y514308D01*
G01D02*
X159932D01*
G01D02*
X155831Y513471D01*
G01X155011Y517659D02*
X160752Y518497D01*
G01X148449Y512633D02*
X151730Y515984D01*
G01D02*
X155011Y517659D01*
G01X155217Y883464D02*
Y892519D01*
G01X157382D02*
Y883464D01*
G01X158366D02*
Y892519D01*
G01X160531D02*
Y883464D01*
G01X161516D02*
Y892519D01*
G01X163681D02*
Y883464D01*
G01X164665D02*
Y892519D01*
G01X166831Y883464D02*
X164665D01*
G01X163681D02*
X161516D01*
G01X160531D02*
X158366D01*
G01X157382D02*
X155217D01*
G01X132185Y892519D02*
Y883464D01*
G01X133169D02*
Y892519D01*
G01X135335D02*
Y883464D01*
G01X136319D02*
Y892519D01*
G01X138484D02*
Y883464D01*
G01X139469D02*
Y892519D01*
G01X141634D02*
Y883464D01*
G01X142618D02*
Y892519D01*
G01X144783D02*
Y883464D01*
G01X145768D02*
Y892519D01*
G01X147933D02*
Y883464D01*
G01X148917D02*
Y892519D01*
G01X151083D02*
Y883464D01*
G01X152067D02*
Y892519D01*
G01X154232D02*
Y883464D01*
G01D02*
X152067D01*
G01X151083D02*
X148917D01*
G01X147933D02*
X145768D01*
G01X144783D02*
X142618D01*
G01X141634D02*
X139469D01*
G01X138484D02*
X136319D01*
G01X135335D02*
X133169D01*
G01X155217Y892519D02*
X157382D01*
G01X161516D02*
X163681D01*
G01X158366D02*
X160531D01*
G01X164665D02*
X166831D01*
G01X133169D02*
X135335D01*
G01X136319D02*
X138484D01*
G01X142618D02*
X144783D01*
G01X139469D02*
X141634D01*
G01X145768D02*
X147933D01*
G01X152067D02*
X154232D01*
G01X148917D02*
X151083D01*
G01X180583Y-1120610D02*
Y-1139623D01*
G01X185733Y-788527D02*
X186708Y-789971D01*
X187195Y-792136D01*
Y-793579D01*
X186708Y-795745D01*
X185733Y-797188D01*
G01X176477Y-792858D02*
X180374D01*
G01X168194Y-788527D02*
X173066D01*
G01X170630D02*
Y-797188D01*
G01X176477Y-788527D02*
Y-797188D01*
G01X180374Y-788527D02*
Y-797188D01*
G01X169130Y-727083D02*
Y-671178D01*
G01Y-615272D02*
Y-671178D01*
G01X166964D02*
Y-671665D01*
X166243D01*
X166964Y-671178D01*
G01X296361Y-615272D02*
X165193D01*
G01X184052Y-447279D02*
X230823Y-414761D01*
G01X258608Y-31794D02*
X187572Y-175468D01*
G01D02*
X175761D01*
G01X170402Y-176912D02*
X173325D01*
G01X169427Y-179799D02*
X171863Y-171137D01*
X174299Y-179799D01*
G01X193701Y-107274D02*
X202362D01*
G01X193701Y-113121D02*
Y-116044D01*
X197310Y-116531D01*
X196588Y-115557D01*
Y-114582D01*
X197310Y-113608D01*
X198031Y-113121D01*
X199475Y-112634D01*
X200919Y-113121D01*
X201641Y-113608D01*
X202362Y-114582D01*
Y-115557D01*
X201641Y-116531D01*
X200919Y-117018D01*
G01X193701Y-81940D02*
Y-84863D01*
X197310Y-85350D01*
X196588Y-84376D01*
Y-83401D01*
X197310Y-82427D01*
X198031Y-81940D01*
X199475Y-81453D01*
X200919Y-81940D01*
X201641Y-82427D01*
X202362Y-83401D01*
Y-84376D01*
X201641Y-85350D01*
X200919Y-85837D01*
G01X196588Y-89735D02*
X198031Y-90222D01*
X198754Y-91684D01*
X198031Y-93145D01*
X196588Y-93632D01*
X195144Y-93145D01*
X194423Y-92658D01*
X193701Y-91684D01*
X194423Y-90709D01*
X195144Y-90222D01*
X196588Y-89735D01*
X199475D01*
X200919Y-90222D01*
X201641Y-90709D01*
X202362Y-91684D01*
X201641Y-92658D01*
X200919Y-93145D01*
G01X204528Y94527D02*
G03X196654Y102401I-7874J0D01*
G01X204528Y94527D02*
G03X196654Y102401I-7874J0D01*
G01X169094Y105708D02*
Y155314D01*
G01X170276Y104920D02*
Y102401D01*
G01X171063Y104763D02*
Y155314D01*
G01X172638Y104763D02*
Y162479D01*
G01X176378Y102401D02*
Y103975D01*
G01X173425Y102401D02*
X176378D01*
G01Y103975D02*
X173425D01*
G01X168307Y104920D02*
X169094Y105708D01*
G01X171063Y104763D02*
G03X173425Y102401I2362J0D01*
G01X172638Y104763D02*
G03X173425Y103975I787J-1D01*
G01X171850Y142873D02*
X172638Y140850D01*
G01X168858Y138345D02*
Y147401D01*
G01X178937D02*
Y138345D01*
G01X172638Y129077D02*
X171063D01*
G01Y129789D02*
X172638D01*
G01Y129865D02*
X171063D01*
G01Y130576D02*
X172638D01*
G01X178937Y138345D02*
X168858D01*
G01X165290Y132819D02*
G03X165093Y133030I-196J14D01*
G01X178425Y142873D02*
G03I-4527J0D01*
G01X171063Y110248D02*
X172638D01*
G01Y110411D02*
X171063D01*
G01X172638Y110426D02*
X171063D01*
G01X172638Y110464D02*
X171063D01*
G01X168858Y147401D02*
X178937D01*
G01X164836Y158097D02*
G03Y160459I0J1181D01*
G01X171850Y145155D02*
Y142873D01*
G01Y145155D02*
X172638Y146755D01*
G01X196724Y189455D02*
X197216Y188785D01*
G01X196559Y192303D02*
X197052Y191633D01*
G01X194591Y193811D02*
X194919Y193309D01*
G01X197708Y189455D02*
X197380Y189958D01*
G01X197216Y192806D02*
X197544Y192303D01*
G01X196231Y193141D02*
X196559Y192303D01*
G01Y189958D02*
X196724Y189455D01*
G01X197052Y193309D02*
X197216Y192806D01*
G01X189178Y188115D02*
Y191801D01*
G01Y192806D02*
Y195989D01*
G01X190162D02*
Y188115D01*
G01X196231Y193811D02*
Y193141D01*
G01X196654Y201574D02*
Y221259D01*
G01X197052Y193644D02*
Y193309D01*
G01X197216Y188785D02*
X198036Y188283D01*
G01X197052Y191633D02*
X197872Y191131D01*
G01X198200Y189120D02*
X197708Y189455D01*
G01X197544Y192303D02*
X198036Y191968D01*
G01X197216Y194146D02*
X197052Y193644D01*
G01X192622Y192136D02*
X194919Y190963D01*
G01X194591Y190460D02*
X191474Y192136D01*
G01X196559Y194649D02*
X196231Y193811D01*
G01X198692Y188953D02*
X198200Y189120D01*
G01X198036Y191968D02*
X198528Y191801D01*
G01X194919Y190963D02*
X194591Y190460D01*
G01X197544Y194649D02*
X197216Y194146D01*
G01X198036Y188283D02*
X198856Y188115D01*
G01X197872Y191131D02*
X198692Y190963D01*
G01X197052Y195319D02*
X196559Y194649D01*
G01X190162Y188115D02*
X189178D01*
G01X197380Y189958D02*
X196559D01*
G01X189178Y195989D02*
X190162D01*
G01X199114Y201574D02*
X196654D01*
G01X198692Y195989D02*
X197872Y195822D01*
G01X198036Y194984D02*
X197544Y194649D01*
G01X197872Y195822D02*
X197052Y195319D01*
G01X191474Y192136D02*
X194591Y193811D01*
G01X194919Y193309D02*
X192622Y192136D01*
G01X198528Y195151D02*
X198036Y194984D01*
G01X175197Y187007D02*
Y196849D01*
G01X183600Y188115D02*
Y195989D01*
G01X184585D02*
Y192806D01*
G01Y191801D02*
Y188115D01*
G01X222441Y187007D02*
X175197D01*
G01X184585Y188115D02*
X183600D01*
G01X189178Y191801D02*
X184585D01*
G01Y192806D02*
X189178D01*
G01X183600Y195989D02*
X184585D01*
G01X196654Y221259D02*
X199114D01*
G01X175244Y278739D02*
Y219684D01*
G01X194762Y342824D02*
Y348599D01*
G01Y347155D02*
X195736Y348599D01*
X196711D01*
X197685Y347155D01*
Y342824D01*
G01X174786Y348599D02*
Y342103D01*
X174299Y340659D01*
X173812Y339937D01*
X171863D01*
X171376Y340659D01*
G01X174786Y344990D02*
X173812Y343546D01*
X172837Y342824D01*
X171863Y343546D01*
X170889Y344990D01*
Y346433D01*
X171863Y347877D01*
X172837Y348599D01*
X173812Y347877D01*
X174786Y346433D01*
G01X190377Y344990D02*
X189402Y343546D01*
X188428Y342824D01*
X187454Y343546D01*
X186479Y344990D01*
Y346433D01*
X187454Y347877D01*
X188428Y348599D01*
X189402Y347877D01*
X190377Y346433D01*
Y344990D01*
G01X193561Y505932D02*
Y512633D01*
G01X198482Y511795D02*
X193561Y505932D01*
G01X198482Y479127D02*
Y511795D01*
G01X203403Y479127D02*
X198482D01*
G01X171415Y507607D02*
Y509282D01*
G01X176336D02*
Y507607D01*
G01D02*
X175516Y504256D01*
G01X169774D02*
X171415Y507607D01*
G01X175516Y504256D02*
X173876Y501743D01*
G01X175516Y512633D02*
X176336Y509282D01*
G01X171415D02*
X169774Y511795D01*
G01D02*
X167314Y513471D01*
G01X176336Y483315D02*
Y479127D01*
G01X182898D02*
Y483315D01*
G01X186999D02*
Y479127D01*
G01D02*
X182898D01*
G01Y483315D02*
X186999D01*
G01X198482Y518497D02*
X203403D01*
G01X193561Y512633D02*
X198482Y518497D01*
G01X172235Y515984D02*
X175516Y512633D01*
G01X168954Y517659D02*
X172235Y515984D01*
G01X189862Y883464D02*
Y892519D01*
G01X192028D02*
Y883464D01*
G01X193012D02*
Y892519D01*
G01X195177D02*
Y883464D01*
G01X196161D02*
Y892519D01*
G01X198327D02*
Y883464D01*
G01D02*
X196161D01*
G01X195177D02*
X193012D01*
G01X192028D02*
X189862D01*
G01X166831Y892519D02*
Y883464D01*
G01X167815D02*
Y892519D01*
G01X169980D02*
Y883464D01*
G01X170965D02*
Y892519D01*
G01X173130D02*
Y883464D01*
G01X174114D02*
Y892519D01*
G01X176280D02*
Y883464D01*
G01X177264D02*
Y892519D01*
G01X179429D02*
Y883464D01*
G01X180413D02*
Y892519D01*
G01X182579D02*
Y883464D01*
G01X183563D02*
Y892519D01*
G01X185728D02*
Y883464D01*
G01X186713D02*
Y892519D01*
G01X188878D02*
Y883464D01*
G01D02*
X186713D01*
G01X185728D02*
X183563D01*
G01X182579D02*
X180413D01*
G01X179429D02*
X177264D01*
G01X176280D02*
X174114D01*
G01X173130D02*
X170965D01*
G01X169980D02*
X167815D01*
G01X189862Y892519D02*
X192028D01*
G01X193012D02*
X195177D01*
G01X196161D02*
X198327D01*
G01X170965D02*
X173130D01*
G01X167815D02*
X169980D01*
G01X174114D02*
X176280D01*
G01X180413D02*
X182579D01*
G01X177264D02*
X179429D01*
G01X183563D02*
X185728D01*
G01X186713D02*
X188878D01*
G01X201171Y950705D02*
X199222Y949262D01*
X198248Y947818D01*
X197761Y945653D01*
X201658D01*
G01X191914D02*
X191427D01*
Y946375D01*
X191914Y945653D01*
G01X292126Y943488D02*
X180221D01*
G01D02*
X296457D01*
G01X182170Y952871D02*
X182657Y953593D01*
X183632Y954314D01*
X184606D01*
X185581Y953593D01*
X186068Y952871D01*
Y951427D01*
X185581Y950705D01*
G01D02*
X183632Y949262D01*
X182657Y947818D01*
X182170Y945653D01*
X186068D01*
G01X197761Y952871D02*
X198248Y953593D01*
X199222Y954314D01*
X200197D01*
X201171Y953593D01*
X201658Y952871D01*
Y951427D01*
X201171Y950705D01*
G01X180583Y2171102D02*
Y2152090D01*
G01X233000Y-862173D02*
X234949Y-863616D01*
X235923Y-864338D01*
X236411Y-865060D01*
Y-866503D01*
X235923Y-867225D01*
X234949Y-867947D01*
X233974D01*
X233000Y-867225D01*
X232513Y-866503D01*
X232026Y-865782D01*
G01X294360Y-626384D02*
X201930Y-799354D01*
G01D02*
X198780D01*
G01X230823Y-414761D02*
X284394Y-395072D01*
G01X202362Y-99479D02*
Y-99966D01*
X201641D01*
X202362Y-99479D01*
G01X204528Y3936D02*
Y-75660D01*
G01X471014Y-1D02*
X212402D01*
G01D02*
X478898D01*
G01X204528Y7873D02*
G03X212402Y-1I7874J0D01*
G01X204528Y7873D02*
G03X212402Y-1I7874J0D01*
G01X411544Y63198D02*
G03I-105969J0D01*
G01X230537Y23424D02*
Y32086D01*
X227127Y25590D01*
X231512D01*
G01X221280Y23424D02*
X220793D01*
Y24146D01*
X221280Y23424D01*
G01X215434Y32086D02*
X212511D01*
X212024Y28477D01*
X212998Y29198D01*
X213972D01*
X214947Y28477D01*
X215434Y27755D01*
X215921Y26311D01*
X215434Y24868D01*
X214947Y24146D01*
X213972Y23424D01*
X212998D01*
X212024Y24146D01*
X211536Y24868D01*
G01X204528Y94527D02*
Y7873D01*
G01Y94527D02*
Y7873D01*
G01X227127Y65288D02*
X227614Y66009D01*
X228589Y66731D01*
X229563D01*
X230537Y66009D01*
X231024Y65288D01*
Y63844D01*
X230537Y63122D01*
X228589Y61679D01*
G01D02*
X227614Y60235D01*
X227127Y58070D01*
X231024D01*
G01X205690Y66731D02*
Y58070D01*
G01X214947D02*
Y66731D01*
X211536Y60235D01*
X215921D01*
G01X221280Y58070D02*
X220793D01*
Y58792D01*
X221280Y58070D01*
G01X229076Y92716D02*
X228101Y93437D01*
X227614Y94159D01*
X227127Y95603D01*
Y98490D01*
X227614Y99933D01*
X228101Y100655D01*
X229076Y101377D01*
X230050Y100655D01*
X230537Y99933D01*
X231024Y98490D01*
Y95603D01*
X230537Y94159D01*
X230050Y93437D01*
X229076Y92716D01*
G01X214947Y97046D02*
X215921Y95603D01*
Y94881D01*
X215434Y94159D01*
X214947Y93437D01*
X213972Y92716D01*
X212998D01*
X212024Y93437D01*
X211536Y94159D01*
G01X221280Y92716D02*
X220793D01*
Y93437D01*
X221280Y92716D01*
G01X212998Y97768D02*
X213972D01*
G01X203741Y99933D02*
X204228Y100655D01*
X205203Y101377D01*
X206177D01*
X207152Y100655D01*
X207639Y99933D01*
Y98490D01*
X207152Y97768D01*
G01X212024Y100655D02*
X212998Y101377D01*
X213972D01*
X214947Y100655D01*
X215434Y99933D01*
Y99212D01*
X214947Y98490D01*
X213972Y97768D01*
X214947Y97046D01*
G01X207152Y97768D02*
X205203Y96324D01*
X204228Y94881D01*
X203741Y92716D01*
X207639D01*
G01X230693Y201574D02*
Y217908D01*
G01X224951Y208694D02*
X224131Y207437D01*
G01X233153Y201574D02*
X230693D01*
G01X201645Y194649D02*
X201153Y195319D01*
G01X200989Y194146D02*
X200661Y194649D01*
G01X206074Y192136D02*
X205910Y192471D01*
G01X208699Y192136D02*
X208535Y192471D01*
G01X213456Y192136D02*
X213292Y192471D01*
G01X216081Y192136D02*
X215917Y192471D01*
G01X201973Y193811D02*
X201645Y194649D01*
G01X209191Y192973D02*
X209519Y192136D01*
G01X216573Y192973D02*
X216901Y192136D01*
G01X201153Y193644D02*
X200989Y194146D01*
G01X202137Y192638D02*
X201973Y193811D01*
G01X199114Y210788D02*
Y201574D01*
G01X201153Y193309D02*
Y193644D01*
G01X201317Y191801D02*
Y191466D01*
G01X202137D02*
Y192638D01*
G01X203449Y188115D02*
Y193476D01*
G01X204270Y192303D02*
Y188115D01*
G01Y193476D02*
Y192973D01*
G01X206074Y188115D02*
Y192136D01*
G01X206894D02*
Y188115D01*
G01X208699D02*
Y192136D01*
G01X209519D02*
Y188115D01*
G01X210597Y201574D02*
Y210788D01*
G01X210831Y188115D02*
Y193476D01*
G01X211652Y192303D02*
Y188115D01*
G01Y193476D02*
Y192973D01*
G01X213058Y221259D02*
Y201574D01*
G01X213456Y188115D02*
Y192136D01*
G01X214276D02*
Y188115D01*
G01X216081D02*
Y192136D01*
G01X216901D02*
Y188115D01*
G01X222441Y196849D02*
Y187007D01*
G01X200661Y194649D02*
X200169Y194984D01*
G01X205910Y192471D02*
X205746Y192638D01*
G01X206238Y193309D02*
X206730Y192806D01*
G01X208535Y192471D02*
X208370Y192638D01*
G01X208863Y193309D02*
X209191Y192973D01*
G01X213292Y192471D02*
X213128Y192638D01*
G01X213620Y193309D02*
X214112Y192806D01*
G01X215917Y192471D02*
X215752Y192638D01*
G01X216244Y193309D02*
X216573Y192973D01*
G01X201973Y190293D02*
X202137Y191466D01*
G01X201317D02*
X201153Y190460D01*
G01X205746Y192638D02*
X205418Y192806D01*
G01X208370Y192638D02*
X208043Y192806D01*
G01X213128Y192638D02*
X212800Y192806D01*
G01X215752Y192638D02*
X215424Y192806D01*
G01X219209Y211626D02*
X224951Y208694D01*
G01X224131Y207437D02*
X216339Y211626D01*
G01X201153Y195319D02*
X200333Y195822D01*
G01X200989Y192806D02*
X201153Y193309D01*
G01Y190460D02*
X200989Y189958D01*
G01X201645Y189455D02*
X201973Y190293D01*
G01X200169Y194984D02*
X199676Y195151D01*
G01X205746Y193476D02*
X206238Y193309D01*
G01X208370Y193476D02*
X208863Y193309D01*
G01X213128Y193476D02*
X213620Y193309D01*
G01X215752Y193476D02*
X216244Y193309D01*
G01X207058Y192471D02*
X206894Y192136D01*
G01X214440Y192471D02*
X214276Y192136D01*
G01X200661Y192303D02*
X200989Y192806D01*
G01Y189958D02*
X200661Y189455D01*
G01X200333Y195822D02*
X199512Y195989D01*
G01X201153Y188785D02*
X201645Y189455D01*
G01X216901Y188115D02*
X216081D01*
G01X214276D02*
X213456D01*
G01X211652D02*
X210831D01*
G01X206894D02*
X206074D01*
G01X209519D02*
X208699D01*
G01X204270D02*
X203449D01*
G01X198856D02*
X199512D01*
G01X199676Y188953D02*
X198692D01*
G01Y190963D02*
X199512D01*
G01X198528Y191801D02*
X199676D01*
G01X215424Y192806D02*
X214932D01*
G01X212800D02*
X212472D01*
G01X205418D02*
X205090D01*
G01X208043D02*
X207550D01*
G01X203449Y193476D02*
X204270D01*
G01X207715D02*
X208370D01*
G01X205090D02*
X205746D01*
G01X212472D02*
X213128D01*
G01X210831D02*
X211652D01*
G01X215096D02*
X215752D01*
G01X199676Y195151D02*
X198528D01*
G01X199512Y195989D02*
X198692D01*
G01X213058Y201574D02*
X210597D01*
G01X204270Y192973D02*
X204598Y193309D01*
G01Y192638D02*
X204270Y192303D01*
G01X206730Y192806D02*
X207222Y193309D01*
G01Y192638D02*
X207058Y192471D01*
G01X211652Y192973D02*
X211980Y193309D01*
G01Y192638D02*
X211652Y192303D01*
G01X214112Y192806D02*
X214604Y193309D01*
G01Y192638D02*
X214440Y192471D01*
G01X199512Y188115D02*
X200333Y188283D01*
G01X199512Y190963D02*
X200333Y191131D01*
G01X200169Y191968D02*
X200661Y192303D01*
G01X200333Y191131D02*
X201317Y191801D01*
G01X200661Y189455D02*
X200169Y189120D01*
G01X200333Y188283D02*
X201153Y188785D01*
G01X207550Y192806D02*
X207222Y192638D01*
G01X214932Y192806D02*
X214604Y192638D01*
G01X199676Y191801D02*
X200169Y191968D01*
G01X204598Y193309D02*
X205090Y193476D01*
G01Y192806D02*
X204598Y192638D01*
G01X207222Y193309D02*
X207715Y193476D01*
G01X211980Y193309D02*
X212472Y193476D01*
G01X200169Y189120D02*
X199676Y188953D01*
G01X212472Y192806D02*
X211980Y192638D01*
G01X214604Y193309D02*
X215096Y193476D01*
G01X228232Y214976D02*
Y218327D01*
G01X224131Y215814D02*
X224951Y214557D01*
G01X228232Y218327D02*
X230693Y221259D01*
G01Y217908D02*
X228232Y214976D01*
G01X230693Y221259D02*
X233153D01*
G01X210597D02*
X213058D01*
G01X199114D02*
Y213301D01*
G01X210597D02*
Y221259D01*
G01Y210788D02*
X199114D01*
G01Y213301D02*
X210597D01*
G01X216339Y211626D02*
X224131Y215814D01*
G01X224951Y214557D02*
X219209Y211626D01*
G01X220276Y303149D02*
Y314960D01*
G01X243758Y310138D02*
X227522Y347155D01*
G01X204019Y342824D02*
Y351486D01*
G01X209865Y348599D02*
X211814Y343546D01*
X211327Y341380D01*
X210352Y339937D01*
X209378D01*
G01X211814Y343546D02*
X213763Y348599D01*
G01X220276Y314960D02*
X358071D01*
G01X227522Y347155D02*
X215711D01*
G01X230470Y505932D02*
Y503419D01*
G01D02*
X232111Y505094D01*
G01Y501743D02*
X230470Y500068D01*
G01X232111Y505094D02*
X234571Y505932D01*
G01Y502581D02*
X232111Y501743D01*
G01X226369Y505932D02*
X230470D01*
G01X226369Y479127D02*
Y505932D01*
G01X230470Y500068D02*
Y479127D01*
G01D02*
X226369D01*
G01X209965Y505932D02*
Y512633D01*
G01X214886Y511795D02*
X209965Y505932D01*
G01X203403Y518497D02*
Y479127D01*
G01X214886D02*
Y511795D01*
G01X219807Y518497D02*
Y479127D01*
G01D02*
X214886D01*
G01Y518497D02*
X219807D01*
G01X209965Y512633D02*
X214886Y518497D01*
G01X232224Y860738D02*
X231978Y859985D01*
G01X232717Y861744D02*
X232224Y860738D01*
G01X231978Y859985D02*
X231732Y858728D01*
G01X223524Y892519D02*
Y883464D01*
G01X224508D02*
Y892519D01*
G01X225827Y855712D02*
Y856718D01*
G01Y858728D02*
Y859733D01*
G01X226673Y892519D02*
Y883464D01*
G01X227657D02*
Y892519D01*
G01X229764Y859733D02*
Y858728D01*
G01Y856718D02*
Y855712D01*
G01X229823Y892519D02*
Y883464D01*
G01X230807D02*
Y892519D01*
G01X231732Y858728D02*
Y856466D01*
G01D02*
X231978Y855210D01*
G01X229764Y855712D02*
X225827D01*
G01Y856718D02*
X229764D01*
G01Y858728D02*
X225827D01*
G01Y859733D02*
X229764D01*
G01X232972Y883464D02*
X230807D01*
G01X229823D02*
X227657D01*
G01X226673D02*
X224508D01*
G01X223858Y863503D02*
Y851692D01*
G01X231978Y855210D02*
X232224Y854456D01*
G01D02*
X232717Y853451D01*
G01X199311Y883464D02*
Y892519D01*
G01X201476D02*
Y883464D01*
G01X202461D02*
Y892519D01*
G01X204626D02*
Y883464D01*
G01X205610D02*
Y892519D01*
G01X207776D02*
Y883464D01*
G01X208760D02*
Y892519D01*
G01X210925D02*
Y883464D01*
G01X211909D02*
Y892519D01*
G01X214075D02*
Y883464D01*
G01X215059D02*
Y892519D01*
G01X215492Y863503D02*
Y858728D01*
G01X217224Y892519D02*
Y883464D01*
G01X218209D02*
Y892519D01*
G01X220374D02*
Y883464D01*
G01X221358D02*
Y892519D01*
G01X222382Y858728D02*
Y863503D01*
G01Y857220D02*
X215492D01*
G01Y858728D02*
X222382D01*
G01X214016Y863503D02*
X215492D01*
G01X222382D02*
X223858D01*
G01X223524Y883464D02*
X221358D01*
G01X220374D02*
X218209D01*
G01X217224D02*
X215059D01*
G01X214075D02*
X211909D01*
G01X210925D02*
X208760D01*
G01X207776D02*
X205610D01*
G01X204626D02*
X202461D01*
G01X201476D02*
X199311D01*
G01X214016Y851692D02*
Y863503D01*
G01X215492Y857220D02*
Y851692D01*
G01X222382D02*
Y857220D01*
G01X223858Y851692D02*
X222382D01*
G01X215492D02*
X214016D01*
G01X227657Y892519D02*
X229823D01*
G01X224508D02*
X226673D01*
G01X230807D02*
X232972D01*
G01X199311D02*
X201476D01*
G01X202461D02*
X204626D01*
G01X208760D02*
X210925D01*
G01X205610D02*
X207776D01*
G01X211909D02*
X214075D01*
G01X218209D02*
X220374D01*
G01X215059D02*
X217224D01*
G01X221358D02*
X223524D01*
G01X225405Y945653D02*
X224431Y946375D01*
X223943Y947097D01*
X223456Y948540D01*
Y951427D01*
X223943Y952871D01*
X224431Y953593D01*
X225405Y954314D01*
X226380Y953593D01*
X226867Y952871D01*
X227354Y951427D01*
Y948540D01*
X226867Y947097D01*
X226380Y946375D01*
X225405Y945653D01*
G01X215733Y954314D02*
Y945653D01*
G01X207505D02*
X206530Y946375D01*
X206043Y947097D01*
X205556Y948540D01*
Y951427D01*
X206043Y952871D01*
X206530Y953593D01*
X207505Y954314D01*
X208479Y953593D01*
X208967Y952871D01*
X209454Y951427D01*
Y948540D01*
X208967Y947097D01*
X208479Y946375D01*
X207505Y945653D01*
G01X211402D02*
X220064D01*
G01X211402Y949984D02*
X220064D01*
G01X263694Y-863616D02*
X266130D01*
G01X267591Y-854955D02*
X263694D01*
Y-846294D01*
X267591D01*
G01X263694Y-850624D02*
X266130D01*
G01X258822Y-847015D02*
X259796Y-848459D01*
X260283Y-850624D01*
X259796Y-852790D01*
G01X267591Y-867947D02*
X263694D01*
Y-859286D01*
X267591D01*
G01X248591Y-865060D02*
X251514D01*
G01X255899Y-846294D02*
X257848D01*
X258822Y-847015D01*
G01X236411Y-860729D02*
X235923Y-860007D01*
X234949Y-859286D01*
X233974D01*
X233000Y-860007D01*
X232513Y-860729D01*
Y-861451D01*
X233000Y-862173D01*
G01X239821Y-861451D02*
X240795Y-860007D01*
X241770Y-859286D01*
X242744D01*
X243719Y-860007D01*
X244206Y-860729D01*
G01X259796Y-852790D02*
X258822Y-854233D01*
X257848Y-854955D01*
X255899D01*
Y-846294D01*
G01Y-859286D02*
Y-867947D01*
X259796D01*
G01X247616D02*
X250052Y-859286D01*
X252488Y-867947D01*
G01X244206Y-866503D02*
X243719Y-867225D01*
X242744Y-867947D01*
X241770D01*
X240795Y-867225D01*
X240308Y-866503D01*
X239821Y-865782D01*
X239334Y-863616D01*
X239821Y-861451D01*
G01X449904Y-727083D02*
X260928D01*
G01D02*
Y-506611D01*
G01X245180Y-727083D02*
Y-490863D01*
G01Y-727083D02*
Y-490863D01*
G01X260928Y-502674D02*
Y-406112D01*
G01Y-506611D02*
X449904D01*
G01X395652Y-490863D02*
X245180D01*
G01X395652D02*
X245180D01*
G01X260928Y-410049D02*
X355416D01*
G01X265551Y-1D02*
Y118109D01*
G01X332480Y21259D02*
X245099D01*
G01X236871Y23424D02*
X235896Y24146D01*
X235409Y24868D01*
X234922Y26311D01*
Y29198D01*
X235409Y30642D01*
X235896Y31364D01*
X236871Y32086D01*
X237845Y31364D01*
X238333Y30642D01*
X238820Y29198D01*
Y26311D01*
X238333Y24868D01*
X237845Y24146D01*
X236871Y23424D01*
G01X289173Y55905D02*
X245099D01*
G01X236871Y58070D02*
X235896Y58792D01*
X235409Y59513D01*
X234922Y60957D01*
Y63844D01*
X235409Y65288D01*
X235896Y66009D01*
X236871Y66731D01*
X237845Y66009D01*
X238333Y65288D01*
X238820Y63844D01*
Y60957D01*
X238333Y59513D01*
X237845Y58792D01*
X236871Y58070D01*
G01X332480Y90550D02*
X245099D01*
G01X236871Y92716D02*
X235896Y93437D01*
X235409Y94159D01*
X234922Y95603D01*
Y98490D01*
X235409Y99933D01*
X235896Y100655D01*
X236871Y101377D01*
X237845Y100655D01*
X238333Y99933D01*
X238820Y98490D01*
Y95603D01*
X238333Y94159D01*
X237845Y93437D01*
X236871Y92716D01*
G01X340787Y118109D02*
X265551D01*
G01X257759Y201574D02*
Y211626D01*
G01X259810D02*
Y201574D01*
G01X263091D02*
Y214976D01*
G01X265141Y212044D02*
Y201574D01*
G01D02*
X263091D01*
G01X259810D02*
X257759D01*
G01X233153Y221259D02*
Y201574D01*
G01X238894D02*
Y217908D01*
G01X241355Y221259D02*
Y201574D01*
G01X244636D02*
Y214976D01*
G01X246687Y212044D02*
Y201574D01*
G01X251198D02*
Y211626D01*
G01X253248D02*
Y201574D01*
G01D02*
X251198D01*
G01X246687D02*
X244636D01*
G01X241355D02*
X238894D01*
G01X256939Y214976D02*
X258169Y214557D01*
G01X263091Y214976D02*
X265141D01*
G01X265961Y214557D02*
X267192Y214976D01*
G01X257349Y212463D02*
X256939Y212882D01*
G01X258169Y214557D02*
X258990Y213720D01*
G01X257759Y211626D02*
X257349Y212463D01*
G01X258990Y213720D02*
X259810Y211626D01*
G01X265141Y214976D02*
Y213720D01*
G01D02*
X265961Y214557D01*
G01Y212882D02*
X265141Y212044D01*
G01X267192Y213301D02*
X265961Y212882D01*
G01X236434Y214976D02*
Y218327D01*
G01X250378Y214976D02*
X251608Y214557D01*
G01X236434Y218327D02*
X238894Y221259D01*
G01Y217908D02*
X236434Y214976D01*
G01X244636D02*
X246687D01*
G01X248737D02*
X250378D01*
G01X255299D02*
X256939D01*
G01X238894Y221259D02*
X241355D01*
G01X247507Y214557D02*
X248737Y214976D01*
G01X254069Y214557D02*
X255299Y214976D01*
G01X250787Y212463D02*
X250378Y212882D01*
G01X251608Y214557D02*
X252838Y213301D01*
G01X251198Y211626D02*
X250787Y212463D01*
G01X246687Y214976D02*
Y213720D01*
G01X250378Y212882D02*
X249557Y213301D01*
G01X256939Y212882D02*
X256119Y213301D01*
G01X253658Y212463D02*
X253248Y211626D01*
G01X246687Y213720D02*
X247507Y214557D01*
G01Y212882D02*
X246687Y212044D01*
G01X252838Y213301D02*
X254069Y214557D01*
G01X256119Y213301D02*
X254889D01*
G01X249557D02*
X248737D01*
G01X254069Y212882D02*
X253658Y212463D01*
G01X254889Y213301D02*
X254069Y212882D01*
G01X248737Y213301D02*
X247507Y212882D01*
G01X261474Y308833D02*
Y308498D01*
G01X262294D02*
Y309671D01*
G01X263607Y305147D02*
Y310508D01*
G01X264427D02*
Y310006D01*
G01Y309336D02*
Y305147D01*
G01X262130Y307325D02*
X262294Y308498D01*
G01X261474D02*
X261310Y307493D01*
G01X256881Y306488D02*
X257373Y305818D01*
G01X256717Y309336D02*
X257209Y308666D01*
G01X257865Y306488D02*
X257537Y306990D01*
G01X257373Y309838D02*
X257701Y309336D01*
G01X256389Y310173D02*
X256717Y309336D01*
G01Y306990D02*
X256881Y306488D01*
G01X257209Y310341D02*
X257373Y309838D01*
G01X262294Y309671D02*
X262130Y310843D01*
G01X261146Y309838D02*
X261310Y310341D01*
G01Y307493D02*
X261146Y306990D01*
G01X261802Y306488D02*
X262130Y307325D01*
G01X258357Y306153D02*
X257865Y306488D01*
G01X257701Y309336D02*
X258193Y309001D01*
G01X266067Y309503D02*
X265904Y309671D01*
G01X260818Y309336D02*
X261146Y309838D01*
G01Y306990D02*
X260818Y306488D01*
G01X265904Y309671D02*
X265575Y309838D01*
G01X257373Y305818D02*
X258193Y305315D01*
G01X257209Y308666D02*
X258030Y308163D01*
G01X261310Y305818D02*
X261802Y306488D01*
G01X264427Y310006D02*
X264755Y310341D01*
G01Y309671D02*
X264427Y309336D01*
G01X258850Y305985D02*
X258357Y306153D01*
G01X258193Y309001D02*
X258685Y308833D01*
G01X258193Y305315D02*
X259014Y305147D01*
G01X258030Y308163D02*
X258850Y307995D01*
G01X260326Y309001D02*
X260818Y309336D01*
G01X260490Y308163D02*
X261474Y308833D01*
G01X260818Y306488D02*
X260326Y306153D01*
G01X260490Y305315D02*
X261310Y305818D01*
G01X264427Y305147D02*
X263607D01*
G01X259014D02*
X259670D01*
G01X259834Y305985D02*
X258850D01*
G01X257537Y306990D02*
X256717D01*
G01X258850Y307995D02*
X259670D01*
G01X258685Y308833D02*
X259834D01*
G01X265575Y309838D02*
X265247D01*
G01X259834Y308833D02*
X260326Y309001D01*
G01X265247Y309838D02*
X264755Y309671D01*
G01X260326Y306153D02*
X259834Y305985D01*
G01X259670Y305147D02*
X260490Y305315D01*
G01X259670Y307995D02*
X260490Y308163D01*
G01X243758Y305147D02*
Y313021D01*
G01X244742D02*
Y309838D01*
G01Y308833D02*
Y305147D01*
G01X249335D02*
Y308833D01*
G01Y309838D02*
Y313021D01*
G01X250319D02*
Y305147D01*
G01X255077Y307995D02*
X254748Y307493D01*
G01X252780Y309168D02*
X255077Y307995D01*
G01X254748Y307493D02*
X251632Y309168D01*
G01X250319Y305147D02*
X249335D01*
G01X244742D02*
X243758D01*
G01X249335Y308833D02*
X244742D01*
G01Y309838D02*
X249335D01*
G01X251632Y309168D02*
X254748Y310843D01*
G01X255077Y310341D02*
X252780Y309168D01*
G01X256389Y310843D02*
Y310173D01*
G01X257209Y310676D02*
Y310341D01*
G01X261310D02*
Y310676D01*
G01X261802Y311681D02*
X261310Y312351D01*
G01X261146Y311179D02*
X260818Y311681D01*
G01X262130Y310843D02*
X261802Y311681D01*
G01X261310Y310676D02*
X261146Y311179D01*
G01X257373D02*
X257209Y310676D01*
G01X256717Y311681D02*
X256389Y310843D01*
G01X260818Y311681D02*
X260326Y312016D01*
G01X257701Y311681D02*
X257373Y311179D01*
G01X257209Y312351D02*
X256717Y311681D01*
G01X261310Y312351D02*
X260490Y312854D01*
G01X260326Y312016D02*
X259834Y312184D01*
G01X265904Y310508D02*
X266396Y310341D01*
G01X260490Y312854D02*
X259670Y313021D01*
G01X258193Y312016D02*
X257701Y311681D01*
G01X258030Y312854D02*
X257209Y312351D01*
G01X265247Y310508D02*
X265904D01*
G01X263607D02*
X264427D01*
G01X259834Y312184D02*
X258685D01*
G01X259670Y313021D02*
X258850D01*
G01X258685Y312184D02*
X258193Y312016D01*
G01X264755Y310341D02*
X265247Y310508D01*
G01X258850Y313021D02*
X258030Y312854D01*
G01X254748Y310843D02*
X255077Y310341D01*
G01X243758Y313021D02*
X244742D01*
G01X249335D02*
X250319D01*
G01X263278Y505932D02*
X267380D01*
G01X256717Y499230D02*
Y479127D01*
G01X263278D02*
Y505932D01*
G01X267380Y479127D02*
X263278D01*
G01X244414Y500906D02*
X243593Y499230D01*
G01X242773Y502581D02*
X245234Y505094D01*
G01Y501743D02*
X244414Y500906D01*
G01X239493Y499230D02*
X238672Y500906D01*
G01X252616Y499230D02*
X251796Y500906D01*
G01X255076Y503419D02*
X256717Y499230D01*
G01X246874Y502581D02*
X245234Y501743D01*
G01X238672Y500906D02*
X237852Y501743D01*
G01X240313Y505094D02*
X242773Y502581D01*
G01X251796Y500906D02*
X250975Y501743D01*
G01X253436Y505094D02*
X255076Y503419D01*
G01X245234Y505094D02*
X247694Y505932D01*
G01X237852Y501743D02*
X236211Y502581D01*
G01X250975Y501743D02*
X249335Y502581D01*
G01X237852Y505932D02*
X240313Y505094D01*
G01X250975Y505932D02*
X253436Y505094D01*
G01X249335Y502581D02*
X246874D01*
G01X236211D02*
X234571D01*
G01Y505932D02*
X237852D01*
G01X247694D02*
X250975D01*
G01X239493Y479127D02*
Y499230D01*
G01X243593D02*
Y479127D01*
G01X252616D02*
Y499230D01*
G01X256717Y479127D02*
X252616D01*
G01X243593D02*
X239493D01*
G01X259045Y858225D02*
X258799Y857723D01*
G01X258553Y858728D02*
X259291Y859482D01*
G01Y858477D02*
X259045Y858225D01*
G01X259783Y858728D02*
X259291Y858477D01*
G01Y859482D02*
X260030Y859733D01*
G01X258169Y892519D02*
Y883464D01*
G01X259154D02*
Y892519D01*
G01X261319D02*
Y883464D01*
G01X262303D02*
Y892519D01*
G01X264469D02*
Y883464D01*
G01X265453D02*
Y892519D01*
G01X262244Y858979D02*
X262736Y857723D01*
G01X257569D02*
X257323Y858225D01*
G01X261506Y857723D02*
X261260Y858225D01*
G01X257323D02*
X257077Y858477D01*
G01X257815Y859482D02*
X258553Y858728D01*
G01X261260Y858225D02*
X261014Y858477D01*
G01X261752Y859482D02*
X262244Y858979D01*
G01X257077Y858477D02*
X256585Y858728D01*
G01X261014Y858477D02*
X260522Y858728D01*
G01X257077Y859733D02*
X257815Y859482D01*
G01X261014Y859733D02*
X261752Y859482D01*
G01X260522Y858728D02*
X259783D01*
G01X260030Y859733D02*
X261014D01*
G01X267618Y883464D02*
X265453D01*
G01X264469D02*
X262303D01*
G01X261319D02*
X259154D01*
G01X257569Y851692D02*
Y857723D01*
G01X258799D02*
Y851692D01*
G01X261506D02*
Y857723D01*
G01X262736D02*
Y851692D01*
G01D02*
X261506D01*
G01X258799D02*
X257569D01*
G01X233455Y862497D02*
X232717Y861744D01*
G01X247972Y858225D02*
X247726Y857723D01*
G01X234193Y861492D02*
X233209Y859985D01*
G01X243789Y858979D02*
X244281Y859482D01*
G01Y858477D02*
X243789Y857974D01*
G01X247480Y858728D02*
X248219Y859482D01*
G01Y858477D02*
X247972Y858225D01*
G01X254862Y858979D02*
X255354Y859482D01*
G01Y858477D02*
X254862Y857974D01*
G01X234931Y861995D02*
X234193Y861492D01*
G01X234685Y863251D02*
X233455Y862497D01*
G01X248711Y858728D02*
X248219Y858477D01*
G01X233209Y859985D02*
X232963Y858477D01*
G01X239114Y855210D02*
X239360Y856718D01*
G01X240344Y855210D02*
X240591Y856466D01*
G01X244281Y859482D02*
X245020Y859733D01*
G01Y858728D02*
X244281Y858477D01*
G01X248219Y859482D02*
X248957Y859733D01*
G01X255354Y859482D02*
X256093Y859733D01*
G01Y858728D02*
X255354Y858477D01*
G01X232963D02*
Y856718D01*
G01X232972Y892519D02*
Y883464D01*
G01X233957D02*
Y892519D01*
G01X236122D02*
Y883464D01*
G01X237106D02*
Y892519D01*
G01X239272D02*
Y883464D01*
G01X239360Y856718D02*
Y858477D01*
G01X240256Y883464D02*
Y892519D01*
G01X240591Y856466D02*
Y858728D01*
G01X242421Y892519D02*
Y883464D01*
G01X243406D02*
Y892519D01*
G01X243789Y859733D02*
Y858979D01*
G01X245571Y892519D02*
Y883464D01*
G01X246555D02*
Y892519D01*
G01X248720D02*
Y883464D01*
G01X249705D02*
Y892519D01*
G01X251870D02*
Y883464D01*
G01X252854D02*
Y892519D01*
G01X254862Y859733D02*
Y858979D01*
G01X255020Y892519D02*
Y883464D01*
G01X256004D02*
Y892519D01*
G01X240591Y858728D02*
X240344Y859985D01*
G01X232963Y856718D02*
X233209Y855210D01*
G01X239360Y858477D02*
X239114Y859985D01*
G01X240344D02*
X240098Y860738D01*
G01X251171Y858979D02*
X251663Y857723D01*
G01X240098Y860738D02*
X239606Y861744D01*
G01X246496Y857723D02*
X246250Y858225D01*
G01X250433Y857723D02*
X250187Y858225D01*
G01X239114Y859985D02*
X238130Y861492D01*
G01X239606Y861744D02*
X238868Y862497D01*
G01X246250Y858225D02*
X246004Y858477D01*
G01X246742Y859482D02*
X247480Y858728D01*
G01X250187Y858225D02*
X249941Y858477D01*
G01X250679Y859482D02*
X251171Y858979D01*
G01X238130Y861492D02*
X237392Y861995D01*
G01X246004Y858477D02*
X245512Y858728D01*
G01X249941Y858477D02*
X249449Y858728D01*
G01X238868Y862497D02*
X237638Y863251D01*
G01X246004Y859733D02*
X246742Y859482D01*
G01X249941Y859733D02*
X250679Y859482D01*
G01X237638Y863251D02*
X236161Y863503D01*
G01X237392Y861995D02*
X236161Y862246D01*
G01X256585Y858728D02*
X256093D01*
G01X249449D02*
X248711D01*
G01X245512D02*
X245020D01*
G01X242559Y859733D02*
X243789D01*
G01X245020D02*
X246004D01*
G01X248957D02*
X249941D01*
G01X253632D02*
X254862D01*
G01X256093D02*
X257077D01*
G01X258169Y883464D02*
X256004D01*
G01X255020D02*
X252854D01*
G01X251870D02*
X249705D01*
G01X248720D02*
X246555D01*
G01X245571D02*
X243406D01*
G01X242421D02*
X240256D01*
G01X239272D02*
X237106D01*
G01X236122D02*
X233957D01*
G01X236161Y862246D02*
X234931Y861995D01*
G01X236161Y863503D02*
X234685Y863251D01*
G01X239606Y853451D02*
X240098Y854456D01*
G01X238130Y853702D02*
X239114Y855210D01*
G01X238868Y852697D02*
X239606Y853451D01*
G01X237392Y853199D02*
X238130Y853702D01*
G01X237638Y851943D02*
X238868Y852697D01*
G01X240098Y854456D02*
X240344Y855210D01*
G01X242559Y851692D02*
Y859733D01*
G01X243789Y857974D02*
Y851692D01*
G01X246496D02*
Y857723D01*
G01X247726D02*
Y851692D01*
G01X250433D02*
Y857723D01*
G01X251663D02*
Y851692D01*
G01X253632D02*
Y859733D01*
G01X254862Y857974D02*
Y851692D01*
G01X233209Y855210D02*
X234193Y853702D01*
G01X232717Y853451D02*
X233455Y852697D01*
G01D02*
X234685Y851943D01*
G01X234193Y853702D02*
X234931Y853199D01*
G01X234685Y851943D02*
X236161Y851692D01*
G01X234931Y853199D02*
X236161Y852948D01*
G01X254862Y851692D02*
X253632D01*
G01X251663D02*
X250433D01*
G01X243789D02*
X242559D01*
G01X247726D02*
X246496D01*
G01X236161Y852948D02*
X237392Y853199D01*
G01X236161Y851692D02*
X237638Y851943D01*
G01X259154Y892519D02*
X261319D01*
G01X262303D02*
X264469D01*
G01X265453D02*
X267618D01*
G01X237106D02*
X239272D01*
G01X233957D02*
X236122D01*
G01X240256D02*
X242421D01*
G01X246555D02*
X248720D01*
G01X243406D02*
X245571D01*
G01X249705D02*
X251870D01*
G01X256004D02*
X258169D01*
G01X252854D02*
X255020D01*
G01X240996Y954314D02*
Y945653D01*
G01X248791D02*
X247817Y946375D01*
X247329Y947097D01*
X246842Y948540D01*
Y951427D01*
X247329Y952871D01*
X247817Y953593D01*
X248791Y954314D01*
X249765Y953593D01*
X250252Y952871D01*
X250740Y951427D01*
Y948540D01*
X250252Y947097D01*
X249765Y946375D01*
X248791Y945653D01*
G01X233200D02*
X232713D01*
Y946375D01*
X233200Y945653D01*
G01X294893Y-1135820D02*
Y-1124413D01*
X289903Y-1132968D01*
X296319D01*
G01X294875Y-846294D02*
Y-854955D01*
X298773D01*
G01X296824Y-867947D02*
X296337D01*
Y-867225D01*
X296824Y-867947D01*
G01X279772Y-852068D02*
X282695D01*
G01X271002Y-846294D02*
X275874D01*
G01X273438D02*
Y-854955D01*
G01X289029Y-846294D02*
Y-854955D01*
G01X278797D02*
X281233Y-846294D01*
X283669Y-854955D01*
G01X287080Y-860729D02*
X287567Y-860007D01*
X288541Y-859286D01*
X289516D01*
X290490Y-860007D01*
X290978Y-860729D01*
Y-862173D01*
X290490Y-862894D01*
G01D02*
X288541Y-864338D01*
X287567Y-865782D01*
X287080Y-867947D01*
X290978D01*
G01X312896Y-615272D02*
G03I-12598J0D01*
G01D02*
G03I-12598J0D01*
G01X284394Y-395072D02*
X341673Y-388652D01*
G01X290945Y-99479D02*
Y-99966D01*
X290223D01*
X290945Y-99479D01*
G01Y-115070D02*
X287336Y-114582D01*
X285171Y-114095D01*
X283727Y-113608D01*
X282283Y-113121D01*
Y-117018D01*
G01X290945Y-105812D02*
X282283D01*
X288780Y-109223D01*
Y-104838D01*
G01X293110Y51968D02*
Y-75660D01*
G01X282283Y-81940D02*
Y-84863D01*
X285893Y-85350D01*
X285171Y-84376D01*
Y-83401D01*
X285893Y-82427D01*
X286614Y-81940D01*
X288058Y-81453D01*
X289502Y-81940D01*
X290223Y-82427D01*
X290945Y-83401D01*
Y-84376D01*
X290223Y-85350D01*
X289502Y-85837D01*
G01X290945Y-90222D02*
X282283D01*
X288780Y-93632D01*
Y-89248D01*
G01X273426Y-1D02*
Y110235D01*
G01X367914Y-1D02*
X273426D01*
G01X299409Y55904D02*
G03I-6299J0D01*
G01D02*
G03I-6299J0D01*
G01X273426Y110235D02*
X367914D01*
G01X269652Y201574D02*
Y211626D01*
G01X271703D02*
Y201574D01*
G01X276214D02*
Y211626D01*
G01X278265D02*
Y201574D01*
G01D02*
X276214D01*
G01X271703D02*
X269652D01*
G01X268832Y214976D02*
X270063Y214557D01*
G01X275394Y214976D02*
X276624Y214557D01*
G01X267192Y214976D02*
X268832D01*
G01X273754D02*
X275394D01*
G01X272523Y214557D02*
X273754Y214976D01*
G01X269652Y211626D02*
X269242Y212463D01*
G01X276214Y211626D02*
X275804Y212463D01*
G01X277444Y213720D02*
X278265Y211626D01*
G01X269242Y212463D02*
X268832Y212882D01*
G01X270063Y214557D02*
X271293Y213301D01*
G01X275804Y212463D02*
X275394Y212882D01*
G01X276624Y214557D02*
X277444Y213720D01*
G01X268832Y212882D02*
X268012Y213301D01*
G01X275394Y212882D02*
X274574Y213301D01*
G01X272113Y212463D02*
X271703Y211626D01*
G01X274574Y213301D02*
X273343D01*
G01X268012D02*
X267192D01*
G01X271293D02*
X272523Y214557D01*
G01Y212882D02*
X272113Y212463D01*
G01X273343Y213301D02*
X272523Y212882D01*
G01X266231Y305147D02*
Y309168D01*
G01X267052D02*
Y305147D01*
G01X268856D02*
Y309168D01*
G01X269676D02*
Y305147D01*
G01X270989D02*
Y310508D01*
G01X271809D02*
Y310006D01*
G01Y309336D02*
Y305147D01*
G01X273613D02*
Y309168D01*
G01X274433D02*
Y305147D01*
G01X276238D02*
Y309168D01*
G01X277058D02*
Y305147D01*
G01X266231Y309168D02*
X266067Y309503D01*
G01X268856Y309168D02*
X268692Y309503D01*
G01X273613Y309168D02*
X273449Y309503D01*
G01X276238Y309168D02*
X276074Y309503D01*
G01X269348Y310006D02*
X269676Y309168D01*
G01X276730Y310006D02*
X277058Y309168D01*
G01X266396Y310341D02*
X266888Y309838D01*
G01X268692Y309503D02*
X268528Y309671D01*
G01X269020Y310341D02*
X269348Y310006D01*
G01X273449Y309503D02*
X273285Y309671D01*
G01X273778Y310341D02*
X274270Y309838D01*
G01X276074Y309503D02*
X275910Y309671D01*
G01X276402Y310341D02*
X276730Y310006D01*
G01X267216Y309503D02*
X267052Y309168D01*
G01X274598Y309503D02*
X274433Y309168D01*
G01X268528Y309671D02*
X268200Y309838D01*
G01X273285Y309671D02*
X272957Y309838D01*
G01X275910Y309671D02*
X275582Y309838D01*
G01X266888D02*
X267380Y310341D01*
G01Y309671D02*
X267216Y309503D01*
G01X271809Y310006D02*
X272137Y310341D01*
G01Y309671D02*
X271809Y309336D01*
G01X274270Y309838D02*
X274762Y310341D01*
G01Y309671D02*
X274598Y309503D01*
G01X277058Y305147D02*
X276238D01*
G01X274433D02*
X273613D01*
G01X271809D02*
X270989D01*
G01X267052D02*
X266231D01*
G01X269676D02*
X268856D01*
G01X275582Y309838D02*
X275090D01*
G01X272957D02*
X272629D01*
G01X268200D02*
X267708D01*
G01D02*
X267380Y309671D01*
G01X275090Y309838D02*
X274762Y309671D01*
G01X272629Y309838D02*
X272137Y309671D01*
G01X268528Y310508D02*
X269020Y310341D01*
G01X273285Y310508D02*
X273778Y310341D01*
G01X275910Y310508D02*
X276402Y310341D01*
G01X267872Y310508D02*
X268528D01*
G01X272629D02*
X273285D01*
G01X270989D02*
X271809D01*
G01X275254D02*
X275910D01*
G01X267380Y310341D02*
X267872Y310508D01*
G01X272137Y310341D02*
X272629Y310508D01*
G01X274762Y310341D02*
X275254Y310508D01*
G01X291986Y503419D02*
X293626Y499230D01*
G01X290345Y505094D02*
X291986Y503419D01*
G01X293626Y499230D02*
Y479127D01*
G01X267380Y505932D02*
Y503419D01*
G01X281323Y500906D02*
X280503Y499230D01*
G01X267380Y503419D02*
X269020Y505094D01*
G01Y501743D02*
X267380Y500068D01*
G01X279683Y502581D02*
X282143Y505094D01*
G01Y501743D02*
X281323Y500906D01*
G01X276402Y499230D02*
X275581Y500906D01*
G01X289525Y499230D02*
X288705Y500906D01*
G01X283784Y502581D02*
X282143Y501743D01*
G01X275581Y500906D02*
X274761Y501743D01*
G01X277222Y505094D02*
X279683Y502581D01*
G01X288705Y500906D02*
X287885Y501743D01*
G01X269020Y505094D02*
X271481Y505932D01*
G01Y502581D02*
X269020Y501743D01*
G01X282143Y505094D02*
X284604Y505932D01*
G01X274761Y501743D02*
X273121Y502581D01*
G01X287885Y501743D02*
X286244Y502581D01*
G01X274761Y505932D02*
X277222Y505094D01*
G01X287885Y505932D02*
X290345Y505094D01*
G01X286244Y502581D02*
X283784D01*
G01X273121D02*
X271481D01*
G01Y505932D02*
X274761D01*
G01X284604D02*
X287885D01*
G01X267380Y500068D02*
Y479127D01*
G01X276402D02*
Y499230D01*
G01X280503D02*
Y479127D01*
G01X289525D02*
Y499230D01*
G01X293626Y479127D02*
X289525D01*
G01X280503D02*
X276402D01*
G01X296457Y879920D02*
Y1032536D01*
G01Y879920D02*
Y1057392D01*
G01X295054Y864841D02*
X294606Y864172D01*
G01X294400D02*
X294951Y864981D01*
G01X296457Y866062D02*
X297754Y867802D01*
G01X292126Y892519D02*
Y875983D01*
G01Y892519D02*
Y875983D01*
G01X294951Y864981D02*
Y865826D01*
G01X295157D02*
Y864981D01*
G01X296457Y866062D02*
Y907558D01*
G01Y866062D02*
X295236Y867802D01*
G01X295157Y864981D02*
X295709Y864172D01*
G01X295502D02*
X295054Y864841D01*
G01X294606Y864172D02*
X294400D01*
G01X295709D02*
X295502D01*
G01X294951Y865826D02*
X295157D01*
G01X292126Y875983D02*
G03X300787I4330J0D01*
G01X292126D02*
G03X300787I4330J0D01*
G01X284687Y882700D02*
X284630Y882617D01*
G01X284936Y881946D02*
X284994Y882030D01*
G01X284956Y881737D02*
X285070Y881905D01*
G01X284994Y881318D02*
X284936Y881234D01*
G01X284668Y882910D02*
X284572Y882784D01*
G01X284956Y881025D02*
X285052Y881151D01*
G01X284744Y882742D02*
X284687Y882700D01*
G01X284879Y881905D02*
X284936Y881946D01*
G01Y881234D02*
X284879Y881193D01*
G01X284764Y882952D02*
X284668Y882910D01*
G01X284860Y881695D02*
X284956Y881737D01*
G01X284860Y880983D02*
X284956Y881025D01*
G01X284630Y882617D02*
X284591Y882491D01*
G01X285032Y881444D02*
X284994Y881318D01*
G01X284572Y882784D02*
X284515Y882617D01*
G01X285052Y881151D02*
X285109Y881318D01*
G01X286087Y882114D02*
X285627Y880983D01*
G01X285953Y882114D02*
X285627Y881318D01*
G01X284994Y882030D02*
X285032Y882114D01*
G01X284591Y882491D02*
X284572Y882365D01*
G01X285032Y882114D02*
X285052Y882240D01*
G01Y881569D02*
X285032Y881444D01*
G01X286816Y882449D02*
X286893Y882952D01*
G01X286797Y882282D02*
X286624Y881151D01*
G01X287008Y882952D02*
X286701Y880983D01*
G01X284515Y882617D02*
X284476Y882407D01*
G01X285109Y881318D02*
X285147Y881528D01*
G01X267618Y892519D02*
Y883464D01*
G01X268602D02*
Y892519D01*
G01X270768D02*
Y883464D01*
G01X271752D02*
Y892519D01*
G01X273917D02*
Y883464D01*
G01X274902D02*
Y892519D01*
G01X277067D02*
Y883464D01*
G01X278051D02*
Y892519D01*
G01X280217D02*
Y883464D01*
G01X281201D02*
Y892519D01*
G01X283366D02*
Y883464D01*
G01X284350D02*
Y890845D01*
G01X284476Y882407D02*
Y882198D01*
G01X284572Y882365D02*
Y882240D01*
G01X285052D02*
Y882365D01*
G01X285070Y881905D02*
Y881821D01*
G01X285167D02*
Y882114D01*
G01X285320D02*
Y882365D01*
G01X285512D02*
Y882952D01*
G01Y880983D02*
Y882114D01*
G01X285627Y882952D02*
Y882365D01*
G01Y881318D02*
Y882114D01*
G01X286087Y882365D02*
Y882114D01*
G01X286516Y890845D02*
Y883464D01*
G01X287500D02*
Y892519D01*
G01X289665D02*
Y883464D01*
G01X285147Y881528D02*
X285167Y881821D01*
G01X285070D02*
X285052Y881569D01*
G01X285167Y882114D02*
X285147Y882407D01*
G01X284476Y882198D02*
X284515Y881988D01*
G01X285147Y882407D02*
X285109Y882617D01*
G01X286548Y880983D02*
X286241Y882952D01*
G01X284515Y881444D02*
X284533Y881318D01*
G01X284572Y882240D02*
X284591Y882114D01*
G01X285052Y882365D02*
X285032Y882491D01*
G01X286624Y881151D02*
X286452Y882282D01*
G01X286356Y882952D02*
X286433Y882449D01*
G01X284533Y881318D02*
X284591Y881151D01*
G01X285109Y882617D02*
X285052Y882784D01*
G01X284649Y881318D02*
X284610Y881444D01*
G01X285032Y882491D02*
X284994Y882617D01*
G01X284515Y881988D02*
X284572Y881863D01*
G01X284591Y882114D02*
X284630Y882030D01*
G01X284591Y881151D02*
X284687Y881025D01*
G01X284572Y881863D02*
X284668Y881737D01*
G01X285052Y882784D02*
X284956Y882910D01*
G01X284706Y881234D02*
X284649Y881318D01*
G01X284630Y882030D02*
X284687Y881946D01*
G01X284994Y882617D02*
X284936Y882700D01*
G01X284764Y881193D02*
X284706Y881234D01*
G01X284687Y881946D02*
X284744Y881905D01*
G01X284936Y882700D02*
X284879Y882742D01*
G01X284687Y881025D02*
X284783Y880983D01*
G01X284668Y881737D02*
X284764Y881695D01*
G01X284956Y882910D02*
X284860Y882952D01*
G01X286701Y880983D02*
X286548D01*
G01X285627D02*
X285512D01*
G01X284783D02*
X284860D01*
G01X284879Y881193D02*
X284764D01*
G01X284610Y881444D02*
X284515D01*
G01X284764Y881695D02*
X284860D01*
G01X284744Y881905D02*
X284879D01*
G01X285512Y882114D02*
X285320D01*
G01X285627D02*
X285953D01*
G01X286452Y882282D02*
X286797D01*
G01X285627Y882365D02*
X286087D01*
G01X285320D02*
X285512D01*
G01X286433Y882449D02*
X286816D01*
G01X284879Y882742D02*
X284744D01*
G01X284860Y882952D02*
X284764D01*
G01X286893D02*
X287008D01*
G01X286241D02*
X286356D01*
G01X285512D02*
X285627D01*
G01X289665Y883464D02*
X287500D01*
G01X286516D02*
X284350D01*
G01X283366D02*
X281201D01*
G01X280217D02*
X278051D01*
G01X277067D02*
X274902D01*
G01X273917D02*
X271752D01*
G01X270768D02*
X268602D01*
G01X292126Y896456D02*
Y947425D01*
G01X294252Y898030D02*
X293318Y896683D01*
G01X293153Y896964D02*
X293922Y898030D01*
G01X293153Y896459D02*
X292384Y895393D01*
G01X292054D02*
X292988Y896683D01*
G01X293461Y892519D02*
X294528Y893267D01*
G01X293318Y896683D02*
X294252Y895393D01*
G01X293922D02*
X293153Y896459D01*
G01X292384Y898030D02*
X293153Y896964D01*
G01X292988Y896683D02*
X292054Y898030D01*
G01X293461Y892519D02*
X294528Y891724D01*
G01X299445Y892519D02*
X293461D01*
G01X294252Y895393D02*
X293922D01*
G01X292384D02*
X292054D01*
G01Y898030D02*
X292384D01*
G01X293922D02*
X294252D01*
G01X288189Y897637D02*
X292126Y892519D01*
G01X288189Y897637D02*
X292126Y892519D01*
G01X284350Y890845D02*
X286516D01*
G01X268602Y892519D02*
X270768D01*
G01X271752D02*
X273917D01*
G01X278051D02*
X280217D01*
G01X274902D02*
X277067D01*
G01X281201D02*
X283366D01*
G01X287500D02*
X289665D01*
G01X320472Y943488D02*
X296457D01*
G01Y1028599D02*
X505118D01*
G01X294291Y1081212D02*
Y1080724D01*
X293570D01*
X294291Y1081212D01*
G01X285630Y1075365D02*
Y1072442D01*
X289239Y1071955D01*
X288517Y1072929D01*
Y1073903D01*
X289239Y1074878D01*
X289961Y1075365D01*
X291404Y1075852D01*
X292848Y1075365D01*
X293570Y1074878D01*
X294291Y1073903D01*
Y1072929D01*
X293570Y1071955D01*
X292848Y1071467D01*
G01X288517Y1066595D02*
X285630Y1067569D01*
Y1063672D01*
G01X294291Y1065621D02*
X290683Y1066108D01*
X288517Y1066595D01*
G01X293570Y1090468D02*
X294291Y1089494D01*
Y1088519D01*
X293570Y1087545D01*
X292848Y1087058D01*
G01X291404Y1091443D02*
X292126D01*
X293570Y1090468D01*
G01X294291Y1096802D02*
X293570Y1095828D01*
X292848Y1095340D01*
X291404Y1094853D01*
X288517D01*
X287074Y1095340D01*
X286352Y1095828D01*
X285630Y1096802D01*
X286352Y1097777D01*
X287074Y1098264D01*
X288517Y1098751D01*
X291404D01*
X292848Y1098264D01*
X293570Y1097777D01*
X294291Y1096802D01*
G01X289239Y1088519D02*
Y1089494D01*
G01X286352Y1087545D02*
X285630Y1088519D01*
Y1089494D01*
X286352Y1090468D01*
X287074Y1090955D01*
X287795D01*
X288517Y1090468D01*
X289239Y1089494D01*
X289961Y1090468D01*
X291404Y1091443D01*
G01X294893Y2155892D02*
Y2167300D01*
X289903Y2158744D01*
X296319D01*
G01X318748Y-852068D02*
X321671D01*
G01X317774Y-854955D02*
X320210Y-846294D01*
X322646Y-854955D01*
G01X304619Y-867947D02*
X303645Y-867225D01*
X303157Y-866503D01*
X302670Y-865060D01*
Y-862173D01*
X303157Y-860729D01*
X303645Y-860007D01*
X304619Y-859286D01*
X305594Y-860007D01*
X306081Y-860729D01*
X306568Y-862173D01*
Y-865060D01*
X306081Y-866503D01*
X305594Y-867225D01*
X304619Y-867947D01*
G01X312415D02*
X311440Y-867225D01*
X310953Y-866503D01*
X310466Y-865060D01*
Y-862173D01*
X310953Y-860729D01*
X311440Y-860007D01*
X312415Y-859286D01*
X313389Y-860007D01*
X313876Y-860729D01*
X314363Y-862173D01*
Y-865060D01*
X313876Y-866503D01*
X313389Y-867225D01*
X312415Y-867947D01*
G01X320210D02*
X319235Y-867225D01*
X318748Y-866503D01*
X318261Y-865060D01*
Y-862173D01*
X318748Y-860729D01*
X319235Y-860007D01*
X320210Y-859286D01*
X321184Y-860007D01*
X321671Y-860729D01*
X322159Y-862173D01*
Y-865060D01*
X321671Y-866503D01*
X321184Y-867225D01*
X320210Y-867947D01*
G01X331000Y-776143D02*
X330513D01*
Y-775421D01*
X331000Y-776143D01*
G01X324666Y-771812D02*
X325641Y-773256D01*
Y-773978D01*
G01X422345Y-778308D02*
X319307D01*
G01D02*
X436125D01*
G01X322717Y-771091D02*
X323692D01*
G01X325641Y-773978D02*
X324666Y-775421D01*
X323692Y-776143D01*
X322717D01*
X321743Y-775421D01*
X321256Y-774699D01*
G01X321743Y-768203D02*
X322717Y-767482D01*
X323692D01*
X324666Y-768203D01*
X325153Y-768925D01*
Y-769647D01*
X324666Y-770369D01*
X323692Y-771091D01*
X324666Y-771812D01*
G01X300298Y-611335D02*
Y-434967D01*
G01Y-438904D02*
X375101D01*
G01X327034Y-132609D02*
X326313Y-132121D01*
X325591Y-131147D01*
Y-130173D01*
X326313Y-129198D01*
X327034Y-128711D01*
X328478D01*
X329200Y-129198D01*
G01D02*
X330643Y-131147D01*
X332087Y-132121D01*
X334252Y-132609D01*
Y-128711D01*
G01X332087Y-112634D02*
X333530Y-113608D01*
X334252Y-114582D01*
Y-115557D01*
G01X331365Y-117505D02*
X329921Y-116531D01*
X329200Y-115557D01*
Y-114582D01*
X329921Y-113608D01*
G01X325591Y-105325D02*
Y-108249D01*
X329200Y-108736D01*
X328478Y-107762D01*
Y-106787D01*
X329200Y-105812D01*
X329921Y-105325D01*
X331365Y-104838D01*
X332809Y-105325D01*
X333530Y-105812D01*
X334252Y-106787D01*
Y-107762D01*
X333530Y-108736D01*
X332809Y-109223D01*
G01X329200Y-115557D02*
X328478Y-116531D01*
X327756Y-117018D01*
X327034D01*
X326313Y-116531D01*
X325591Y-115557D01*
Y-114582D01*
X326313Y-113608D01*
X327034Y-113121D01*
X327756D01*
X328478Y-113608D01*
X329200Y-114582D01*
G01X329921Y-113608D02*
X331365Y-112634D01*
X332087D01*
G01X333530Y-116531D02*
X332087Y-117505D01*
X331365D01*
G01X334252Y-124327D02*
X328478Y-121403D01*
G01Y-124327D02*
X334252Y-121403D01*
G01X325591Y-81940D02*
Y-84863D01*
X329200Y-85350D01*
X328478Y-84376D01*
Y-83401D01*
X329200Y-82427D01*
X329921Y-81940D01*
X331365Y-81453D01*
X332809Y-81940D01*
X333530Y-82427D01*
X334252Y-83401D01*
Y-84376D01*
X333530Y-85350D01*
X332809Y-85837D01*
G01X334252Y-90222D02*
X325591D01*
X332087Y-93632D01*
Y-89248D01*
G01X342717Y21259D02*
G03I-6300J0D01*
G01D02*
G03I-6300J0D01*
G01Y90550D02*
G03I-6300J0D01*
G01D02*
G03I-6300J0D01*
G01X324311Y892519D02*
Y883464D01*
G01X325295D02*
Y892519D01*
G01X327461D02*
Y883464D01*
G01X328445D02*
Y892519D01*
G01X330610D02*
Y883464D01*
G01X331594D02*
Y892519D01*
G01X333760Y883464D02*
X331594D01*
G01X330610D02*
X328445D01*
G01X327461D02*
X325295D01*
G01X303872Y882075D02*
X303265Y880944D01*
G01X305085Y882075D02*
X304479Y880944D01*
G01X303695Y882075D02*
X303265Y881279D01*
G01X304909Y882075D02*
X304479Y881279D01*
G01X306046Y882410D02*
X306148Y882912D01*
G01X306021Y882242D02*
X305794Y881111D01*
G01X306299Y882912D02*
X305895Y880944D01*
G01X300787Y892519D02*
Y875983D01*
G01Y892519D02*
Y875983D01*
G01X302860Y882075D02*
Y882326D01*
G01X303113D02*
Y882912D01*
G01Y880944D02*
Y882075D01*
G01X303248Y883464D02*
Y892519D01*
G01X303265Y882912D02*
Y882326D01*
G01Y881279D02*
Y882075D01*
G01X303872Y882326D02*
Y882075D01*
G01X304074D02*
Y882326D01*
G01X304327D02*
Y882912D01*
G01Y880944D02*
Y882075D01*
G01X304479Y882912D02*
Y882326D01*
G01Y881279D02*
Y882075D01*
G01X305085Y882326D02*
Y882075D01*
G01X305413Y892519D02*
Y883464D01*
G01X306398D02*
Y892519D01*
G01X308563D02*
Y883464D01*
G01X309547D02*
Y892519D01*
G01X311713D02*
Y883464D01*
G01X312697D02*
Y892519D01*
G01X314862D02*
Y883464D01*
G01X315846D02*
Y892519D01*
G01X318012D02*
Y883464D01*
G01X318996D02*
Y892519D01*
G01X321161D02*
Y883464D01*
G01X322146D02*
Y892519D01*
G01X305693Y880944D02*
X305288Y882912D01*
G01X305794Y881111D02*
X305566Y882242D01*
G01X305440Y882912D02*
X305541Y882410D01*
G01X305895Y880944D02*
X305693D01*
G01X304479D02*
X304327D01*
G01X303265D02*
X303113D01*
G01X304327Y882075D02*
X304074D01*
G01X303113D02*
X302860D01*
G01X304479D02*
X304909D01*
G01X303265D02*
X303695D01*
G01X305566Y882242D02*
X306021D01*
G01X302860Y882326D02*
X303113D01*
G01X304479D02*
X305085D01*
G01X304074D02*
X304327D01*
G01X303265D02*
X303872D01*
G01X305541Y882410D02*
X306046D01*
G01X306148Y882912D02*
X306299D01*
G01X305288D02*
X305440D01*
G01X304327D02*
X304479D01*
G01X303113D02*
X303265D01*
G01X324311Y883464D02*
X322146D01*
G01X321161D02*
X318996D01*
G01X314862D02*
X312697D01*
G01X318012D02*
X315846D01*
G01X311713D02*
X309547D01*
G01X305413D02*
X303248D01*
G01X308563D02*
X306398D01*
G01X325295Y892519D02*
X327461D01*
G01X328445D02*
X330610D01*
G01X331594D02*
X333760D01*
G01X300787Y896456D02*
Y947425D01*
G01X304724Y897637D02*
X300787Y892519D01*
G01D02*
X304724Y897637D01*
G01X300787Y892519D02*
X442913D01*
G01X303248D02*
X305413D01*
G01X306398D02*
X308563D01*
G01X309547D02*
X311713D01*
G01X312697D02*
X314862D01*
G01X315846D02*
X318012D01*
G01X318996D02*
X321161D01*
G01X322146D02*
X324311D01*
G01X304724Y897637D02*
X438976D01*
G01X304724D02*
X438976D01*
G01X300787Y943488D02*
X320472D01*
G01X340744Y-767482D02*
X337820D01*
X337333Y-771091D01*
X338308Y-770369D01*
X339282D01*
X340257Y-771091D01*
X340744Y-771812D01*
X341231Y-773256D01*
X340744Y-774699D01*
X340257Y-775421D01*
X339282Y-776143D01*
X338308D01*
X337333Y-775421D01*
X336846Y-774699D01*
G01X346590Y-776143D02*
X345616Y-775421D01*
X345129Y-774699D01*
X344641Y-773256D01*
Y-770369D01*
X345129Y-768925D01*
X345616Y-768203D01*
X346590Y-767482D01*
X347565Y-768203D01*
X348052Y-768925D01*
X348539Y-770369D01*
Y-773256D01*
X348052Y-774699D01*
X347565Y-775421D01*
X346590Y-776143D01*
G01X449904Y-410049D02*
X355416D01*
G01D02*
X577233D01*
G01X341673Y-388652D02*
X400732Y-394534D01*
G01X365026Y-105812D02*
X365748Y-106787D01*
Y-107762D01*
X365026Y-108736D01*
X364305Y-109223D01*
G01X362861Y-104838D02*
X363583D01*
X365026Y-105812D01*
G01X360696Y-107762D02*
Y-106787D01*
G01X365748Y-99479D02*
Y-99966D01*
X365026D01*
X365748Y-99479D01*
G01X349081Y-117505D02*
X347638Y-116531D01*
X346916Y-115557D01*
Y-114582D01*
X347638Y-113608D01*
G01X349804Y-112634D02*
X351247Y-113608D01*
X351969Y-114582D01*
Y-115557D01*
G01X359974Y-113121D02*
X361418Y-113608D01*
X362139Y-115070D01*
X361418Y-116531D01*
X359974Y-117018D01*
X358530Y-116531D01*
X357809Y-116044D01*
X357087Y-115070D01*
X357809Y-114095D01*
X358530Y-113608D01*
X359974Y-113121D01*
X362861D01*
X364305Y-113608D01*
X365026Y-114095D01*
X365748Y-115070D01*
X365026Y-116044D01*
X364305Y-116531D01*
G01X346194Y-105325D02*
X347638Y-105812D01*
X348360Y-107274D01*
X347638Y-108736D01*
X346194Y-109223D01*
X344751Y-108736D01*
X344029Y-108249D01*
X343307Y-107274D01*
X344029Y-106300D01*
X344751Y-105812D01*
X346194Y-105325D01*
X349081D01*
X350525Y-105812D01*
X351247Y-106300D01*
X351969Y-107274D01*
X351247Y-108249D01*
X350525Y-108736D01*
G01X357809D02*
X357087Y-107762D01*
Y-106787D01*
X357809Y-105812D01*
X358530Y-105325D01*
X359252D01*
X359974Y-105812D01*
X360696Y-106787D01*
X361418Y-105812D01*
X362861Y-104838D01*
G01X334252Y-99479D02*
Y-99966D01*
X333530D01*
X334252Y-99479D01*
G01X351969D02*
Y-99966D01*
X351247D01*
X351969Y-99479D01*
G01X334252Y-115557D02*
X333530Y-116531D01*
G01X346916Y-115557D02*
X346194Y-116531D01*
X345473Y-117018D01*
X344751D01*
X344029Y-116531D01*
X343307Y-115557D01*
Y-114582D01*
X344029Y-113608D01*
X344751Y-113121D01*
X345473D01*
X346194Y-113608D01*
X346916Y-114582D01*
G01X351969Y-115557D02*
X351247Y-116531D01*
G01X347638Y-113608D02*
X349081Y-112634D01*
X349804D01*
G01X351247Y-116531D02*
X349804Y-117505D01*
X349081D01*
G01X336417Y17322D02*
Y-75660D01*
G01X354134Y36219D02*
Y-75660D01*
G01X343307Y-81940D02*
Y-84863D01*
X346916Y-85350D01*
X346194Y-84376D01*
Y-83401D01*
X346916Y-82427D01*
X347638Y-81940D01*
X349081Y-81453D01*
X350525Y-81940D01*
X351247Y-82427D01*
X351969Y-83401D01*
Y-84376D01*
X351247Y-85350D01*
X350525Y-85837D01*
G01X357087Y-81940D02*
Y-84863D01*
X360696Y-85350D01*
X359974Y-84376D01*
Y-83401D01*
X360696Y-82427D01*
X361418Y-81940D01*
X362861Y-81453D01*
X364305Y-81940D01*
X365026Y-82427D01*
X365748Y-83401D01*
Y-84376D01*
X365026Y-85350D01*
X364305Y-85837D01*
G01X346194Y-89735D02*
X347638Y-90222D01*
X348360Y-91684D01*
X347638Y-93145D01*
X346194Y-93632D01*
X344751Y-93145D01*
X344029Y-92658D01*
X343307Y-91684D01*
X344029Y-90709D01*
X344751Y-90222D01*
X346194Y-89735D01*
X349081D01*
X350525Y-90222D01*
X351247Y-90709D01*
X351969Y-91684D01*
X351247Y-92658D01*
X350525Y-93145D01*
G01X365748Y-90222D02*
X357087D01*
X363583Y-93632D01*
Y-89248D01*
G01X357804Y8324D02*
X418413Y-91813D01*
G01X365945Y38188D02*
G03X367914Y40156I0J1969D01*
G01X354134Y71653D02*
Y40156D01*
G01X356103Y38188D02*
X365945D01*
G01X354134Y40156D02*
G03X356103Y38188I1968J0D01*
G01X354134Y71653D02*
Y40156D01*
G01X356103Y38188D02*
X367914D01*
G01X354134Y40156D02*
G03X356103Y38188I1968J0D01*
G01X367914Y71653D02*
G03X365945Y73621I-1969J-1D01*
G01D02*
X356103D01*
G01D02*
G03X354134Y71653I0J-1969D01*
G01X367914Y73621D02*
X356103D01*
G01D02*
G03X354134Y71653I0J-1969D01*
G01X358071Y840550D02*
Y134802D01*
G01X340787D02*
Y118109D01*
G01X358071Y134802D02*
X340787D01*
G01X352607Y196849D02*
Y303149D01*
G01X340791D02*
X358071Y303142D01*
G01X340787Y303149D02*
X358071Y303142D01*
G01Y820865D02*
X453740D01*
G01X358957Y892519D02*
Y883464D01*
G01X359941D02*
Y892519D01*
G01X362106D02*
Y883464D01*
G01X363091D02*
Y892519D01*
G01X365256D02*
Y883464D01*
G01X366240D02*
Y892519D01*
G01X368406Y883464D02*
X366240D01*
G01X362106D02*
X359941D01*
G01X365256D02*
X363091D01*
G01X333760Y892519D02*
Y883464D01*
G01X334744D02*
Y892519D01*
G01X336909D02*
Y883464D01*
G01X337894D02*
Y892519D01*
G01X340059D02*
Y883464D01*
G01X341043D02*
Y892519D01*
G01X343209D02*
Y883464D01*
G01X344193D02*
Y892519D01*
G01X346358D02*
Y883464D01*
G01X347343D02*
Y892519D01*
G01X349508D02*
Y883464D01*
G01X350492D02*
Y892519D01*
G01X352657D02*
Y883464D01*
G01X353642D02*
Y892519D01*
G01X355807D02*
Y883464D01*
G01X356791D02*
Y892519D01*
G01X358957Y883464D02*
X356791D01*
G01X352657D02*
X350492D01*
G01X355807D02*
X353642D01*
G01X349508D02*
X347343D01*
G01X343209D02*
X341043D01*
G01X346358D02*
X344193D01*
G01X340059D02*
X337894D01*
G01X336909D02*
X334744D01*
G01X359941Y892519D02*
X362106D01*
G01X363091D02*
X365256D01*
G01X366240D02*
X368406D01*
G01X334744D02*
X336909D01*
G01X337894D02*
X340059D01*
G01X341043D02*
X343209D01*
G01X344193D02*
X346358D01*
G01X347343D02*
X349508D01*
G01X350492D02*
X352657D01*
G01X353642D02*
X355807D01*
G01X356791D02*
X358957D01*
G01X386912Y-680627D02*
Y-463700D01*
G01X390849Y-684564D02*
X499414D01*
G01X399511D02*
G03I-12599J0D01*
G01D02*
G03I-12599J0D01*
G01X390849Y-545981D02*
X629637D01*
G01X399511D02*
G03I-12599J0D01*
G01D02*
G03I-12599J0D01*
G01X395652Y-457477D02*
Y-490863D01*
G01Y-457477D02*
Y-490863D01*
G01X386912Y-467637D02*
X418408D01*
G01X430219Y-457477D02*
X395652D01*
G01X430219D02*
X395652D01*
G01X449904Y-438904D02*
X375101D01*
G01D02*
X576031D01*
G01X400732Y-394534D02*
X436574Y-403991D01*
G01X367914Y36219D02*
Y-75660D01*
G01Y38188D02*
Y-1D01*
G01X369882Y38188D02*
X390598D01*
G01X367914Y40156D02*
Y71653D01*
G01X400775Y46127D02*
X400287Y44684D01*
X398826Y43962D01*
X397364Y44684D01*
X396877Y46127D01*
X397364Y47571D01*
X397852Y48293D01*
X398826Y49015D01*
X399800Y48293D01*
X400287Y47571D01*
X400775Y46127D01*
Y43240D01*
X400287Y41797D01*
X399800Y41075D01*
X398826Y40353D01*
X397852Y41075D01*
X397364Y41797D01*
G01X369882Y73621D02*
X390598D01*
G01X367914Y110235D02*
Y73621D01*
G01X392697Y106298D02*
Y111827D01*
G01X394173Y118109D02*
Y106298D01*
G01D02*
X392697D01*
G01X398826Y84448D02*
Y75786D01*
G01X384331Y106298D02*
Y118109D01*
G01X385807Y111827D02*
Y106298D01*
G01D02*
X384331D01*
G01X392697Y113334D02*
Y118109D01*
G01X396142Y113334D02*
Y114340D01*
G01X400079D02*
Y113334D01*
G01D02*
X396142D01*
G01Y114340D02*
X400079D01*
G01X392697Y118109D02*
X394173D01*
G01X396142Y110319D02*
Y111324D01*
G01X400079D02*
Y110319D01*
G01D02*
X396142D01*
G01Y111324D02*
X400079D01*
G01X385807Y118109D02*
Y113334D01*
G01D02*
X392697D01*
G01X384331Y118109D02*
X385807D01*
G01X392697Y111827D02*
X385807D01*
G01X395007Y830745D02*
X394602Y830125D01*
G01X396628Y835504D02*
X397843Y836952D01*
G01Y835297D02*
X396628Y833849D01*
G01X395007Y833642D02*
X392170Y832193D01*
G01X396628Y833849D02*
Y835504D01*
G01X397843Y827228D02*
Y835297D01*
G01X399059Y836952D02*
Y827228D01*
G01X400680D02*
Y833849D01*
G01X394602Y834262D02*
X395007Y833642D01*
G01X392170Y832193D02*
X395007Y830745D01*
G01X399059Y827228D02*
X397843D01*
G01X401692D02*
X400680D01*
G01Y833849D02*
X401692D01*
G01X397843Y836952D02*
X399059D01*
G01X390752Y832193D02*
X394602Y834262D01*
G01X381028Y827228D02*
Y836952D01*
G01X382243D02*
Y833021D01*
G01Y831780D02*
Y827228D01*
G01X387916D02*
Y831780D01*
G01Y833021D02*
Y836952D01*
G01X389131D02*
Y827228D01*
G01X394602Y830125D02*
X390752Y832193D01*
G01X389131Y827228D02*
X387916D01*
G01X382243D02*
X381028D01*
G01X387916Y831780D02*
X382243D01*
G01Y833021D02*
X387916D01*
G01X381028Y836952D02*
X382243D01*
G01X387916D02*
X389131D01*
G01X391437Y883464D02*
Y892519D01*
G01X393602D02*
Y883464D01*
G01X394587D02*
Y892519D01*
G01X396752D02*
Y883464D01*
G01X397736D02*
Y892519D01*
G01X399902D02*
Y883464D01*
G01X400886D02*
Y892519D01*
G01X399902Y883464D02*
X397736D01*
G01X403051D02*
X400886D01*
G01X396752D02*
X394587D01*
G01X393602D02*
X391437D01*
G01X368406Y892519D02*
Y883464D01*
G01X369390D02*
Y892519D01*
G01X371555D02*
Y883464D01*
G01X372539D02*
Y892519D01*
G01X374705D02*
Y883464D01*
G01X375689D02*
Y892519D01*
G01X377854D02*
Y883464D01*
G01X378839D02*
Y892519D01*
G01X381004D02*
Y883464D01*
G01X381988D02*
Y892519D01*
G01X384154D02*
Y883464D01*
G01X385138D02*
Y892519D01*
G01X387303D02*
Y883464D01*
G01X388287D02*
Y892519D01*
G01X390453D02*
Y883464D01*
G01D02*
X388287D01*
G01X387303D02*
X385138D01*
G01X381004D02*
X378839D01*
G01X384154D02*
X381988D01*
G01X377854D02*
X375689D01*
G01X371555D02*
X369390D01*
G01X374705D02*
X372539D01*
G01X391437Y892519D02*
X393602D01*
G01X394587D02*
X396752D01*
G01X397736D02*
X399902D01*
G01X400886D02*
X403051D01*
G01X369390D02*
X371555D01*
G01X372539D02*
X374705D01*
G01X375689D02*
X377854D01*
G01X378839D02*
X381004D01*
G01X381988D02*
X384154D01*
G01X385138D02*
X387303D01*
G01X388287D02*
X390453D01*
G01X401124Y-1120610D02*
Y-1139623D01*
G01X422345Y-650705D02*
Y-782245D01*
G01X429010Y-643929D02*
X441261Y-631175D01*
G01X426282Y-650705D02*
X445967D01*
G01X426282D02*
X449904D01*
G01X422345Y-583776D02*
Y-646768D01*
G01D02*
G03X426282Y-650705I3937J0D01*
G01X422345Y-583776D02*
Y-646768D01*
G01D02*
G03X426282Y-650705I3937J0D01*
G01X445967Y-579839D02*
X426282D01*
G01X449904D02*
X426282D01*
G01X428776Y-586823D02*
X442688Y-603817D01*
G01X426282Y-579839D02*
G03X422345Y-583776I0J-3937D01*
G01X426282Y-579839D02*
G03X422345Y-583776I0J-3937D01*
G01X449904Y-467637D02*
X418408D01*
G01D02*
X589894D01*
G01X430219Y-402314D02*
Y-457477D01*
G01Y-402314D02*
Y-457477D01*
G01X432173Y-96144D02*
Y-87482D01*
X434609D01*
X435583Y-88204D01*
X436071Y-88925D01*
Y-90369D01*
X435583Y-91091D01*
X434609Y-91813D01*
X432173D01*
G01X418413D02*
X430224D01*
G01X415391Y46127D02*
X416365Y49015D01*
X412468D01*
G01X422212Y40353D02*
X421237Y41075D01*
X420750Y41797D01*
X420263Y43240D01*
Y46127D01*
X420750Y47571D01*
X421237Y48293D01*
X422212Y49015D01*
X423186Y48293D01*
X423673Y47571D01*
X424161Y46127D01*
Y43240D01*
X423673Y41797D01*
X423186Y41075D01*
X422212Y40353D01*
G01X406621D02*
X406134D01*
Y41075D01*
X406621Y40353D01*
G01X414417D02*
X414904Y43962D01*
X415391Y46127D01*
G01X433051Y106298D02*
X431821D01*
G01X429114D02*
X427884D01*
G01X425177Y112580D02*
Y106298D01*
G01X427884D02*
Y112329D01*
G01X429114D02*
Y106298D01*
G01X431821D02*
Y112329D01*
G01X433051D02*
Y106298D01*
G01X430007Y75786D02*
X429033Y76508D01*
X428545Y77230D01*
X428058Y78673D01*
Y81560D01*
X428545Y83004D01*
X429033Y83726D01*
X430007Y84448D01*
X430981Y83726D01*
X431469Y83004D01*
X431956Y81560D01*
Y78673D01*
X431469Y77230D01*
X430981Y76508D01*
X430007Y75786D01*
G01X403770Y107303D02*
X405000Y106549D01*
G01X406134Y80839D02*
X405159Y81560D01*
X404672Y82282D01*
Y83004D01*
X405159Y83726D01*
X406134Y84448D01*
X407108D01*
X408083Y83726D01*
X408570Y83004D01*
Y82282D01*
X408083Y81560D01*
X407108Y80839D01*
G01X403031Y108057D02*
X403770Y107303D01*
G01X405000Y106549D02*
X406476Y106298D01*
G01X405246Y107806D02*
X406476Y107555D01*
G01X412874Y106298D02*
Y114340D01*
G01X414104Y112580D02*
Y106298D01*
G01X421978D02*
X420748D01*
G01X425177D02*
X423947D01*
G01X418041D02*
X416811D01*
G01X414104D02*
X412874D01*
G01X416811D02*
Y112329D01*
G01X418041D02*
Y106298D01*
G01X420748D02*
Y112329D01*
G01X421978D02*
Y106298D01*
G01X423947D02*
Y114340D01*
G01X406476Y107555D02*
X407707Y107806D01*
G01X406476Y106298D02*
X407953Y106549D01*
G01X409183Y107303D02*
X409921Y108057D01*
G01X407953Y106549D02*
X409183Y107303D01*
G01X406134Y75786D02*
X405159Y76508D01*
G01D02*
X404185Y77952D01*
Y78673D01*
X404672Y79395D01*
X405159Y80117D01*
X406134Y80839D01*
X407108D01*
X408083Y80117D01*
G01D02*
X409057Y78673D01*
Y77952D01*
X408570Y77230D01*
X408083Y76508D01*
X407108Y75786D01*
X406134D01*
G01X414417D02*
X413929D01*
Y76508D01*
X414417Y75786D01*
G01X422212D02*
X422699Y79395D01*
X423186Y81560D01*
X423673Y83004D01*
X424161Y84448D01*
X420263D01*
G01X427392Y113083D02*
X426900Y113334D01*
G01X431329Y113083D02*
X430837Y113334D01*
G01X427638Y112832D02*
X427392Y113083D01*
G01X428130Y114088D02*
X428868Y113334D01*
G01X431575Y112832D02*
X431329Y113083D01*
G01X432067Y114088D02*
X432559Y113586D01*
G01X427392Y114340D02*
X428130Y114088D01*
G01X431329Y114340D02*
X432067Y114088D01*
G01X430837Y113334D02*
X430098D01*
G01X426900D02*
X426407D01*
G01Y114340D02*
X427392D01*
G01X430344D02*
X431329D01*
G01X425177D02*
Y113586D01*
G01D02*
X425669Y114088D01*
G01X428868Y113334D02*
X429606Y114088D01*
G01Y113083D02*
X429360Y112832D01*
G01X430098Y113334D02*
X429606Y113083D01*
G01X425669Y114088D02*
X426407Y114340D01*
G01Y113334D02*
X425669Y113083D01*
G01X429606Y114088D02*
X430344Y114340D01*
G01X427884Y112329D02*
X427638Y112832D01*
G01X431821Y112329D02*
X431575Y112832D01*
G01X432559Y113586D02*
X433051Y112329D01*
G01X429360Y112832D02*
X429114Y112329D01*
G01X425669Y113083D02*
X425177Y112580D01*
G01X416319Y113083D02*
X415827Y113334D01*
G01X420256Y113083D02*
X419764Y113334D01*
G01X409183Y117104D02*
X407953Y117858D01*
G01X408445Y116099D02*
X407707Y116601D01*
G01X409921Y116350D02*
X409183Y117104D01*
G01X416565Y112832D02*
X416319Y113083D01*
G01X417057Y114088D02*
X417795Y113334D01*
G01X420502Y112832D02*
X420256Y113083D01*
G01X420994Y114088D02*
X421486Y113586D01*
G01X409429Y114591D02*
X408445Y116099D01*
G01X407953Y117858D02*
X406476Y118109D01*
G01X407707Y116601D02*
X406476Y116853D01*
G01X416319Y114340D02*
X417057Y114088D01*
G01X420256Y114340D02*
X420994Y114088D01*
G01X410413Y115345D02*
X409921Y116350D01*
G01X410659Y114591D02*
X410413Y115345D01*
G01X410906Y113334D02*
X410659Y114591D01*
G01X414104Y114340D02*
Y113586D01*
G01X419764Y113334D02*
X419026D01*
G01X415827D02*
X415335D01*
G01X412874Y114340D02*
X414104D01*
G01X415335D02*
X416319D01*
G01X419272D02*
X420256D01*
G01X423947D02*
X425177D01*
G01X409675Y113083D02*
X409429Y114591D01*
G01X403524D02*
X403278Y113083D01*
G01X402293Y114591D02*
X402047Y113334D01*
G01X406476Y116853D02*
X405246Y116601D01*
G01X406476Y118109D02*
X405000Y117858D01*
G01X402539Y115345D02*
X402293Y114591D01*
G01X403031Y116350D02*
X402539Y115345D01*
G01X404508Y116099D02*
X403524Y114591D01*
G01X403770Y117104D02*
X403031Y116350D01*
G01X414104Y113586D02*
X414596Y114088D01*
G01X417795Y113334D02*
X418533Y114088D01*
G01Y113083D02*
X418287Y112832D01*
G01X405246Y116601D02*
X404508Y116099D01*
G01X405000Y117858D02*
X403770Y117104D01*
G01X419026Y113334D02*
X418533Y113083D01*
G01X414596Y114088D02*
X415335Y114340D01*
G01Y113334D02*
X414596Y113083D01*
G01X418533Y114088D02*
X419272Y114340D01*
G01X404508Y108308D02*
X405246Y107806D01*
G01X403524Y109816D02*
X404508Y108308D01*
G01X402539Y109062D02*
X403031Y108057D01*
G01X416811Y112329D02*
X416565Y112832D01*
G01X420748Y112329D02*
X420502Y112832D01*
G01X421486Y113586D02*
X421978Y112329D01*
G01X402293Y109816D02*
X402539Y109062D01*
G01X402047Y111073D02*
X402293Y109816D01*
G01X403278Y111324D02*
X403524Y109816D01*
G01X402047Y113334D02*
Y111073D01*
G01X403278Y113083D02*
Y111324D01*
G01X409675D02*
Y113083D01*
G01X410906Y111073D02*
Y113334D01*
G01X409429Y109816D02*
X409675Y111324D01*
G01X410659Y109816D02*
X410906Y111073D01*
G01X410413Y109062D02*
X410659Y109816D01*
G01X409921Y108057D02*
X410413Y109062D01*
G01X418287Y112832D02*
X418041Y112329D01*
G01X408445Y108308D02*
X409429Y109816D01*
G01X414596Y113083D02*
X414104Y112580D01*
G01X407707Y107806D02*
X408445Y108308D01*
G01X401692Y833228D02*
X402098Y833642D01*
G01Y832814D02*
X401692Y832400D01*
G01X404731Y833021D02*
X405339Y833642D01*
G01Y832814D02*
X405136Y832607D01*
G01X410809Y833228D02*
X411214Y833642D01*
G01Y832814D02*
X410809Y832400D01*
G01X413848Y833021D02*
X414456Y833642D01*
G01Y832814D02*
X414253Y832607D01*
G01X405744Y833021D02*
X405339Y832814D01*
G01X414861Y833021D02*
X414456Y832814D01*
G01X402098Y833642D02*
X402705Y833849D01*
G01Y833021D02*
X402098Y832814D01*
G01X405339Y833642D02*
X405947Y833849D01*
G01X411214Y833642D02*
X411822Y833849D01*
G01Y833021D02*
X411214Y832814D01*
G01X414456Y833642D02*
X415063Y833849D01*
G01X405136Y832607D02*
X404934Y832193D01*
G01X414253Y832607D02*
X414050Y832193D01*
G01X401692Y833849D02*
Y833228D01*
G01Y832400D02*
Y827228D01*
G01X403921D02*
Y832193D01*
G01X404934D02*
Y827228D01*
G01X407162D02*
Y832193D01*
G01X408175D02*
Y827228D01*
G01X409796D02*
Y833849D01*
G01X410809D02*
Y833228D01*
G01Y832400D02*
Y827228D01*
G01X413037D02*
Y832193D01*
G01X414050D02*
Y827228D01*
G01X416279D02*
Y832193D01*
G01X417292D02*
Y827228D01*
G01X407770Y833228D02*
X408175Y832193D01*
G01X416887Y833228D02*
X417292Y832193D01*
G01X403921D02*
X403718Y832607D01*
G01X407162Y832193D02*
X406960Y832607D01*
G01X413037Y832193D02*
X412835Y832607D01*
G01X416279Y832193D02*
X416076Y832607D01*
G01X403718D02*
X403516Y832814D01*
G01X404123Y833642D02*
X404731Y833021D01*
G01X406960Y832607D02*
X406757Y832814D01*
G01X407365Y833642D02*
X407770Y833228D01*
G01X412835Y832607D02*
X412632Y832814D01*
G01X413240Y833642D02*
X413848Y833021D01*
G01X416076Y832607D02*
X415874Y832814D01*
G01X416481Y833642D02*
X416887Y833228D01*
G01X403516Y832814D02*
X403111Y833021D01*
G01X406757Y832814D02*
X406352Y833021D01*
G01X412632Y832814D02*
X412227Y833021D01*
G01X415874Y832814D02*
X415469Y833021D01*
G01X403516Y833849D02*
X404123Y833642D01*
G01X406757Y833849D02*
X407365Y833642D01*
G01X412632Y833849D02*
X413240Y833642D01*
G01X415874Y833849D02*
X416481Y833642D01*
G01X417292Y827228D02*
X416279D01*
G01X414050D02*
X413037D01*
G01X408175D02*
X407162D01*
G01X410809D02*
X409796D01*
G01X404934D02*
X403921D01*
G01X415469Y833021D02*
X414861D01*
G01X412227D02*
X411822D01*
G01X406352D02*
X405744D01*
G01X403111D02*
X402705D01*
G01Y833849D02*
X403516D01*
G01X405947D02*
X406757D01*
G01X409796D02*
X410809D01*
G01X411822D02*
X412632D01*
G01X415063D02*
X415874D01*
G01X425098Y892519D02*
Y883464D01*
G01X426083D02*
Y892519D01*
G01X428248D02*
Y883464D01*
G01X429232D02*
Y892519D01*
G01X431398D02*
Y883464D01*
G01X432382D02*
Y892519D01*
G01X434547D02*
Y883464D01*
G01D02*
X432382D01*
G01X428248D02*
X426083D01*
G01X431398D02*
X429232D01*
G01X403051Y892519D02*
Y883464D01*
G01X404035D02*
Y892519D01*
G01X406201D02*
Y883464D01*
G01X407185D02*
Y892519D01*
G01X409350D02*
Y883464D01*
G01X410335D02*
Y892519D01*
G01X412500D02*
Y883464D01*
G01X413484D02*
Y892519D01*
G01X415650D02*
Y883464D01*
G01X416634D02*
Y892519D01*
G01X418799D02*
Y883464D01*
G01X419783D02*
Y892519D01*
G01X421949D02*
Y883464D01*
G01X422933D02*
Y892519D01*
G01X425098Y883464D02*
X422933D01*
G01X418799D02*
X416634D01*
G01X421949D02*
X419783D01*
G01X415650D02*
X413484D01*
G01X409350D02*
X407185D01*
G01X412500D02*
X410335D01*
G01X406201D02*
X404035D01*
G01X426083Y892519D02*
X428248D01*
G01X429232D02*
X431398D01*
G01X432382D02*
X434547D01*
G01X404035D02*
X406201D01*
G01X407185D02*
X409350D01*
G01X410335D02*
X412500D01*
G01X413484D02*
X415650D01*
G01X416634D02*
X418799D01*
G01X419783D02*
X421949D01*
G01X422933D02*
X425098D01*
G01X401124Y2171102D02*
Y2152090D01*
G01X449904Y-731020D02*
Y-782245D01*
G01Y-778308D02*
X469589D01*
G01D02*
X436125D01*
G01X449904Y-650705D02*
Y-727083D01*
G01Y-650705D02*
X578046D01*
G01X449904D02*
X578014D01*
G01X449904Y-646768D02*
Y-463700D01*
G01Y-646768D02*
Y-434967D01*
G01Y-646768D02*
Y-583776D01*
G01X445967Y-650705D02*
G03X449904Y-646768I0J3937D01*
G01X467180Y-603817D02*
X474398Y-590825D01*
G01X460291Y-631175D02*
X520343D01*
G01X442688Y-603817D02*
X457796D01*
G01D02*
X517849D01*
G01X441261Y-631175D02*
X460291D01*
G01X466458Y-597321D02*
X467180Y-595155D01*
X468623Y-593712D01*
X470789Y-592990D01*
X472954Y-593712D01*
X474398Y-595155D01*
X475119Y-597321D01*
X474398Y-599486D01*
X472954Y-600929D01*
X470789Y-601651D01*
X468623Y-600929D01*
X467180Y-599486D01*
X466458Y-597321D01*
G01X449904Y-579839D02*
X578014D01*
G01X449904Y-583776D02*
G03X445967Y-579839I-3937J0D01*
G01X449904Y-506611D02*
Y-579839D01*
G01X453841Y-506611D02*
X663648D01*
G01X449904Y-502674D02*
Y-406112D01*
G01X436574Y-403991D02*
X469287Y-418546D01*
G01X450687Y-88204D02*
X451661Y-89647D01*
X452148Y-91813D01*
X451661Y-93978D01*
X451174Y-94700D01*
X450687Y-95421D01*
X449713Y-96144D01*
X447764D01*
Y-87482D01*
G01X439481Y-96144D02*
X441917Y-87482D01*
X444353Y-96144D01*
G01X447764Y-87482D02*
X449713D01*
X450687Y-88204D01*
G01X440456Y-93256D02*
X443379D01*
G01X468399Y53578D02*
X495259Y-94116D01*
G01X453740Y62204D02*
X478898D01*
G01X453730Y62223D02*
X478888D01*
G01X453730Y303149D02*
Y62223D01*
G01X453740Y840550D02*
Y62204D01*
G01X459871Y82277D02*
X460609D01*
G01X465899D02*
X466637D01*
G01X463931Y80643D02*
X464177Y80266D01*
G01X459871Y79890D02*
Y82277D01*
G01X465161Y80392D02*
Y81397D01*
G01D02*
X465899Y82277D01*
G01Y81271D02*
X465161Y80392D01*
G01X461593Y79387D02*
X463931Y80643D01*
G01X464177Y80266D02*
X462454Y79387D01*
G01D02*
X464177Y78507D01*
G01X463931Y78130D02*
X461593Y79387D01*
G01X468237Y76371D02*
X467622D01*
G01X466637D02*
X465899D01*
G01X460609D02*
X459871D01*
G01X467622Y76999D02*
X468237D01*
G01X459871Y76371D02*
Y79136D01*
G01X460609Y82277D02*
Y76371D01*
G01X465899D02*
Y81271D01*
G01X466637Y82277D02*
Y76371D01*
G01X467622D02*
Y76999D01*
G01X468237D02*
Y76371D01*
G01X464177Y78507D02*
X463931Y78130D01*
G01X459871Y79136D02*
X456426D01*
G01Y79890D02*
X459871D01*
G01X455688Y82277D02*
X456426D01*
G01X453730Y101574D02*
X478888D01*
G01X456426Y82277D02*
Y79890D01*
G01Y76371D02*
X455688D01*
G01D02*
Y82277D01*
G01X456426Y79136D02*
Y76371D01*
G01X453730Y303149D02*
X1400000D01*
G01X450000Y845668D02*
Y871653D01*
G01Y845668D02*
Y871653D01*
G01X517323Y840550D02*
X455118D01*
G01X450000Y845668D02*
G03X455118Y840550I5118J0D01*
G01X450000Y845668D02*
G03X455118Y840550I5118J0D01*
G01X439045Y881279D02*
X439291Y881572D01*
G01Y881237D02*
X439045Y880944D01*
G01X440850Y882410D02*
X441014Y882912D01*
G01X440809Y882242D02*
X440440Y881111D01*
G01X441260Y882912D02*
X440604Y880944D01*
G01X435531Y883464D02*
Y892519D01*
G01X437697D02*
Y883464D01*
G01X438681D02*
Y892519D01*
G01X438799Y880944D02*
Y882912D01*
G01X439045D02*
Y881279D01*
G01X439291Y881572D02*
Y881237D01*
G01X440846Y892519D02*
Y883464D01*
G01X442913Y892519D02*
Y875590D01*
G01D02*
Y892519D01*
G01X440276Y880944D02*
X439620Y882912D01*
G01X440440Y881111D02*
X440071Y882242D01*
G01X439866Y882912D02*
X440030Y882410D01*
G01X448031Y873621D02*
X444882D01*
G01X448031D02*
X444882D01*
G01X440604Y880944D02*
X440276D01*
G01X439045D02*
X438799D01*
G01X440071Y882242D02*
X440809D01*
G01X440030Y882410D02*
X440850D01*
G01X441014Y882912D02*
X441260D01*
G01X439620D02*
X439866D01*
G01X438799D02*
X439045D01*
G01X440846Y883464D02*
X438681D01*
G01X437697D02*
X435531D01*
G01X450000Y871653D02*
G03X448031Y873621I-1968J0D01*
G01X442913Y875590D02*
G03X444882Y873621I1969J0D01*
G01X450000Y871653D02*
G03X448031Y873621I-1968J0D01*
G01X442913Y875590D02*
G03X444882Y873621I1969J0D01*
G01X438976Y897637D02*
X442913Y892519D01*
G01X438976Y897637D02*
X442913Y892519D01*
G01X435531D02*
X437697D01*
G01X438681D02*
X440846D01*
G01X495477Y-705823D02*
Y-821367D01*
G01X493312Y-809674D02*
Y-810161D01*
X492590D01*
X493312Y-809674D01*
G01Y-800417D02*
X484650D01*
X491146Y-803828D01*
Y-799443D01*
G01X484650Y-815521D02*
Y-818444D01*
X488259Y-818931D01*
X487537Y-817957D01*
Y-816982D01*
X488259Y-816008D01*
X488981Y-815521D01*
X490424Y-815033D01*
X491868Y-815521D01*
X492590Y-816008D01*
X493312Y-816982D01*
Y-817957D01*
X492590Y-818931D01*
X491868Y-819418D01*
G01X493312Y-794084D02*
X492590Y-795058D01*
X491868Y-795545D01*
X490424Y-796032D01*
X487537D01*
X486094Y-795545D01*
X485372Y-795058D01*
X484650Y-794084D01*
X485372Y-793109D01*
X486094Y-792622D01*
X487537Y-792135D01*
X490424D01*
X491868Y-792622D01*
X492590Y-793109D01*
X493312Y-794084D01*
G01X495477Y-727083D02*
Y-705823D01*
G01Y-684564D02*
Y-705823D01*
G01X499989Y-629010D02*
X499014Y-628288D01*
X498527Y-627566D01*
X498040Y-626122D01*
Y-623235D01*
X498527Y-621792D01*
X499014Y-621070D01*
X499989Y-620348D01*
X500963Y-621070D01*
X501450Y-621792D01*
X501937Y-623235D01*
Y-626122D01*
X501450Y-627566D01*
X500963Y-628288D01*
X499989Y-629010D01*
G01X497495Y-601651D02*
X496520Y-600929D01*
X496033Y-600208D01*
X495546Y-598764D01*
Y-595877D01*
X496033Y-594433D01*
X496520Y-593712D01*
X497495Y-592990D01*
X498469Y-593712D01*
X498956Y-594433D01*
X499444Y-595877D01*
Y-598764D01*
X498956Y-600208D01*
X498469Y-600929D01*
X497495Y-601651D01*
G01X492193Y-629010D02*
X491706D01*
Y-628288D01*
X492193Y-629010D01*
G01X489700Y-601651D02*
X489212D01*
Y-600929D01*
X489700Y-601651D01*
G01X481904Y-592990D02*
Y-601651D01*
G01X484398Y-620348D02*
Y-629010D01*
G01X468952Y-624679D02*
X469674Y-622514D01*
X471117Y-621070D01*
X473283Y-620348D01*
X475448Y-621070D01*
X476891Y-622514D01*
X477613Y-624679D01*
X476891Y-626844D01*
X475448Y-628288D01*
X473283Y-629010D01*
X471117Y-628288D01*
X469674Y-626844D01*
X468952Y-624679D01*
G01X469674Y-631175D02*
X476891Y-618183D01*
G01X502424Y-514485D02*
X499471D01*
G01X502424D02*
X499471D01*
G01D02*
Y-503428D01*
G01Y-514485D02*
Y-503428D01*
G01Y-500412D02*
Y-490863D01*
G01Y-500412D02*
Y-490863D01*
G01X485692Y-514485D02*
X482739D01*
G01X485692D02*
X482739D01*
G01X499471Y-503428D02*
X485692D01*
G01X499471D02*
X485692D01*
G01Y-500412D02*
X499471D01*
G01X485692D02*
X499471D01*
G01X482739Y-514485D02*
Y-490863D01*
G01Y-514485D02*
Y-490863D01*
G01X485692D02*
Y-500412D01*
G01Y-490863D02*
Y-500412D01*
G01Y-503428D02*
Y-514485D01*
G01Y-503428D02*
Y-514485D01*
G01X499471Y-490863D02*
X502424D01*
G01X499471D02*
X502424D01*
G01X482739D02*
X485692D01*
G01X482739D02*
X485692D01*
G01X495800Y-439034D02*
X520024Y-481115D01*
G01X469287Y-418546D02*
X495800Y-439034D01*
G01X495259Y-94116D02*
X507070D01*
G01X495866Y6298D02*
X499016D01*
G01X493110Y9448D02*
Y6298D01*
G01X495866Y9448D02*
Y6298D01*
G01X496687D02*
Y9448D01*
G01X496850D02*
Y6298D01*
G01X497638D02*
Y9448D01*
G01X499016Y6298D02*
Y9448D01*
G01X1302165Y-19686D02*
X486762D01*
G01X1302165D02*
X486762D01*
G01X493110Y6298D02*
X489961D01*
G01X491339D02*
X497638D01*
G01X478888Y101574D02*
Y-1D01*
G01Y-11812D02*
Y-7875D01*
G01Y-11812D02*
Y-7875D01*
G01X478898Y62204D02*
Y-1D01*
G01X489961Y6298D02*
Y9448D01*
G01X491339D02*
Y6298D01*
G01X492126Y9448D02*
Y6298D01*
G01X492290Y9448D02*
Y6298D01*
G01X478888Y-11812D02*
G03X486762Y-19686I7874J0D01*
G01X478888Y-11812D02*
G03X486762Y-19686I7874J0D01*
G01X478888Y-7875D02*
G03X471014Y-1I-7874J0D01*
G01X478888Y-7875D02*
G03X471014Y-1I-7874J0D01*
G01X492862Y31259D02*
X492844Y31261D01*
G01Y31324D02*
X492859Y31321D01*
G01X493295Y31259D02*
X493280Y31261D01*
G01X494154Y31259D02*
X494139Y31261D01*
G01X492847Y31274D02*
X492859Y31271D01*
G01X493019Y31259D02*
X493007Y31261D01*
G01X493179Y31259D02*
X493167Y31261D01*
G01X493285Y31274D02*
X493297Y31271D01*
G01X492884Y31362D02*
X492872Y31364D01*
G01X493536Y31259D02*
X493524Y31261D01*
G01X493704Y31259D02*
X493691Y31261D01*
G01X493812D02*
X493824Y31259D01*
G01X493927D02*
X493915Y31261D01*
G01X493809Y31304D02*
X493822Y31301D01*
G01X494144Y31274D02*
X494156Y31271D01*
G01X493726Y31377D02*
X493738Y31374D01*
G01X494306Y31261D02*
X494319Y31259D01*
G01X493846Y31374D02*
X493834Y31377D01*
G01X493950D02*
X493962Y31374D01*
G01X494343Y31332D02*
X494331Y31334D01*
G01X494820Y31259D02*
X494808Y31261D01*
G01X494341Y31374D02*
X494328Y31377D01*
G01X495067Y31261D02*
X495079Y31259D01*
G01X494843Y31377D02*
X494855Y31374D01*
G01X492874Y31377D02*
X492884Y31374D01*
G01X493917Y31276D02*
X493927Y31274D01*
G01X493735Y31359D02*
X493726Y31362D01*
G01X493694Y31276D02*
X493704Y31274D01*
G01X493959Y31359D02*
X493950Y31362D01*
G01X494811Y31276D02*
X494820Y31274D01*
G01X494852Y31359D02*
X494843Y31362D01*
G01X493009Y31276D02*
X493017Y31274D01*
G01Y31324D02*
X493009Y31327D01*
G01X493169Y31274D02*
X493177Y31271D01*
G01X493526Y31276D02*
X493533Y31274D01*
G01Y31324D02*
X493526Y31327D01*
G01X493822Y31271D02*
X493814Y31274D01*
G01X493812Y31316D02*
X493819Y31314D01*
G01X493844Y31362D02*
X493836Y31364D01*
G01X494309Y31274D02*
X494316Y31271D01*
G01X494341Y31319D02*
X494333Y31321D01*
G01X494331Y31364D02*
X494338Y31362D01*
G01X495069Y31274D02*
X495076Y31271D01*
G01X492840Y31316D02*
X492828Y31321D01*
G01X492844Y31261D02*
X492835Y31266D01*
G01X492889Y31359D02*
X492884Y31362D01*
G01Y31374D02*
X492894Y31369D01*
G01X493002Y31316D02*
X492997Y31319D01*
G01X493280Y31261D02*
X493270Y31266D01*
G01X493519Y31316D02*
X493514Y31319D01*
G01X493691Y31261D02*
X493681Y31266D01*
G01X493915Y31261D02*
X493905Y31266D01*
G01X493738Y31374D02*
X493748Y31369D01*
G01X494139Y31261D02*
X494129Y31266D01*
G01X493962Y31374D02*
X493972Y31369D01*
G01X494808Y31261D02*
X494798Y31266D01*
G01X494855Y31374D02*
X494865Y31369D01*
G01X493799Y31269D02*
X493812Y31261D01*
G01X493797Y31312D02*
X493809Y31304D01*
G01X493858Y31367D02*
X493846Y31374D01*
G01X494294Y31269D02*
X494306Y31261D01*
G01X494356Y31324D02*
X494343Y31332D01*
G01X494353Y31367D02*
X494341Y31374D01*
G01X492840Y31279D02*
X492847Y31274D01*
G01X492837Y31329D02*
X492844Y31324D01*
G01X492936Y31284D02*
X492928Y31289D01*
G01X492894Y31369D02*
X492901Y31364D01*
G01X492960Y31352D02*
X492968Y31347D01*
G01X493278Y31279D02*
X493285Y31274D01*
G01X493686Y31281D02*
X493694Y31276D01*
G01X493814Y31274D02*
X493807Y31279D01*
G01X493743Y31354D02*
X493735Y31359D01*
G01X493804Y31321D02*
X493812Y31316D01*
G01X493910Y31281D02*
X493917Y31276D01*
G01X493851Y31357D02*
X493844Y31362D01*
G01X494016Y31284D02*
X494009Y31289D01*
G01X493967Y31354D02*
X493959Y31359D01*
G01X494137Y31279D02*
X494144Y31274D01*
G01X494041Y31352D02*
X494048Y31347D01*
G01X494301Y31279D02*
X494309Y31274D01*
G01X494348Y31314D02*
X494341Y31319D01*
G01X494338Y31362D02*
X494346Y31357D01*
G01X494803Y31281D02*
X494811Y31276D01*
G01X494860Y31354D02*
X494852Y31359D01*
G01X493007Y31261D02*
X492997Y31269D01*
G01X493167Y31261D02*
X493157Y31269D01*
G01X493524Y31261D02*
X493514Y31269D01*
G01X495057D02*
X495067Y31261D01*
G01X493005Y31281D02*
X493009Y31276D01*
G01Y31327D02*
X493005Y31332D01*
G01X493521Y31281D02*
X493526Y31276D01*
G01Y31327D02*
X493521Y31332D01*
G01X492835Y31266D02*
X492825Y31276D01*
G01X492894Y31354D02*
X492889Y31359D01*
G01X493165Y31279D02*
X493169Y31274D01*
G01X493270Y31266D02*
X493261Y31276D01*
G01X493681Y31266D02*
X493671Y31276D01*
G01X493789Y31319D02*
X493797Y31312D01*
G01X493748Y31369D02*
X493757Y31359D01*
G01X493799Y31327D02*
X493804Y31321D01*
G01X493905Y31266D02*
X493895Y31276D01*
G01X493972Y31369D02*
X493981Y31359D01*
G01X494129Y31266D02*
X494119Y31276D01*
G01X494798Y31266D02*
X494789Y31276D01*
G01X494865Y31369D02*
X494875Y31359D01*
G01X495064Y31279D02*
X495069Y31274D01*
G01X492997Y31269D02*
X492990Y31279D01*
G01X494855Y31261D02*
X494843Y31259D01*
G01X494331D02*
X494343Y31261D01*
G01X494808Y31374D02*
X494820Y31377D01*
G01X494166Y31271D02*
X494178Y31274D01*
G01X494319Y31334D02*
X494306Y31332D01*
G01X493962Y31261D02*
X493950Y31259D01*
G01X493834D02*
X493846Y31261D01*
G01X494319Y31377D02*
X494306Y31374D01*
G01X493738Y31261D02*
X493726Y31259D01*
G01X493834Y31301D02*
X493846Y31304D01*
G01X493915Y31374D02*
X493927Y31377D01*
G01X493307Y31271D02*
X493320Y31274D01*
G01X493822Y31377D02*
X493809Y31374D01*
G01X493691D02*
X493704Y31377D01*
G01X493524Y31374D02*
X493536Y31377D01*
G01X493167Y31321D02*
X493179Y31324D01*
G01X492869Y31271D02*
X492881Y31274D01*
G01X493007Y31374D02*
X493019Y31377D01*
G01X492857Y31364D02*
X492844Y31362D01*
G01X494181Y31261D02*
X494163Y31259D01*
G01X493322Y31261D02*
X493305Y31259D01*
G01X492884Y31261D02*
X492867Y31259D01*
G01X495866Y29920D02*
X499016D01*
G01X497372Y31160D02*
X497274D01*
G01X497717D02*
X497643D01*
G01X495472Y31259D02*
X495384D01*
G01X495281D02*
X495266D01*
G01X495364D02*
X495350D01*
G01X495246D02*
X495157D01*
G01X495025D02*
X495010D01*
G01X494917D02*
X494902D01*
G01X494843D02*
X494820D01*
G01X494683D02*
X494668D01*
G01X494767D02*
X494752D01*
G01X494648D02*
X494555D01*
G01X494402D02*
X494387D01*
G01X494163D02*
X494154D01*
G01X494082D02*
X494068D01*
G01X493950D02*
X493927D01*
G01X493726D02*
X493704D01*
G01X493595D02*
X493536D01*
G01X493389D02*
X493366D01*
G01X493484D02*
X493462D01*
G01X493305D02*
X493295D01*
G01X493238D02*
X493179D01*
G01X493113D02*
X493098D01*
G01X493078D02*
X493019D01*
G01X492867D02*
X492862D01*
G01X492800D02*
X492707D01*
G01X494319D02*
X494331D01*
G01X493824D02*
X493834D01*
G01X495079D02*
X495138D01*
G01X493836Y31271D02*
X493822D01*
G01X494609D02*
X494648D01*
G01X494555D02*
X494594D01*
G01X494316D02*
X494333D01*
G01X494156D02*
X494166D01*
G01X493297D02*
X493307D01*
G01X493177D02*
X493224D01*
G01X492859D02*
X492869D01*
G01X492761D02*
X492800D01*
G01X492707D02*
X492746D01*
G01X495076D02*
X495123D01*
G01X493927Y31274D02*
X493950D01*
G01X493704D02*
X493726D01*
G01X493533D02*
X493580D01*
G01X493017D02*
X493064D01*
G01X495384D02*
X495458D01*
G01X495157D02*
X495231D01*
G01X494820D02*
X494843D01*
G01X493802Y31286D02*
X493789D01*
G01X494191D02*
X494203D01*
G01X493332D02*
X493344D01*
G01X492894D02*
X492906D01*
G01X494786Y31289D02*
X494801D01*
G01X493893D02*
X493907D01*
G01X493669D02*
X493684D01*
G01X493822Y31301D02*
X493834D01*
G01X495458Y31306D02*
X495394D01*
G01X495231D02*
X495167D01*
G01X494752D02*
X494683D01*
G01X495123Y31309D02*
X495076D01*
G01X493580D02*
X493533D01*
G01X493224D02*
X493177D01*
G01X493064D02*
X493017D01*
G01X494823Y31312D02*
X494786D01*
G01X493930D02*
X493893D01*
G01X492869D02*
X492859D01*
G01X493819Y31314D02*
X493836D01*
G01X494333Y31321D02*
X494316D01*
G01X494259D02*
X494225D01*
G01X493649D02*
X493615D01*
G01X494683D02*
X494752D01*
G01X492859D02*
X492869D01*
G01X495394D02*
X495458D01*
G01X495167D02*
X495231D01*
G01X495123Y31324D02*
X495081D01*
G01X493580D02*
X493533D01*
G01X493064D02*
X493017D01*
G01X493179D02*
X493224D01*
G01X494801Y31327D02*
X494823D01*
G01X493907D02*
X493930D01*
G01X494331Y31334D02*
X494319D01*
G01X494225D02*
X494259D01*
G01X493615D02*
X493649D01*
G01X493684Y31347D02*
X493669D01*
G01X492909Y31349D02*
X492896D01*
G01X494350D02*
X494363D01*
G01X495458Y31362D02*
X495384D01*
G01X495231D02*
X495157D01*
G01X495010D02*
X494936D01*
G01X494843D02*
X494820D01*
G01X493950D02*
X493927D01*
G01X493726D02*
X493704D01*
G01X493533D02*
X493580D01*
G01X493017D02*
X493064D01*
G01X494186Y31364D02*
X494117D01*
G01X493836D02*
X493819D01*
G01X493327D02*
X493258D01*
G01X492872D02*
X492857D01*
G01X494316D02*
X494331D01*
G01X495062Y31377D02*
X495044D01*
G01X495138D02*
X495123D01*
G01X494328D02*
X494319D01*
G01X493834D02*
X493822D01*
G01X494668D02*
X494683D01*
G01X494752D02*
X494767D01*
G01X494594D02*
X494609D01*
G01X494387D02*
X494402D01*
G01X494117D02*
X494206D01*
G01X494068D02*
X494082D01*
G01X493927D02*
X493950D01*
G01X493704D02*
X493726D01*
G01X493536D02*
X493595D01*
G01X493366D02*
X493381D01*
G01X493470D02*
X493484D01*
G01X493415D02*
X493435D01*
G01X493258D02*
X493346D01*
G01X493224D02*
X493238D01*
G01X493098D02*
X493113D01*
G01X493019D02*
X493078D01*
G01X492854D02*
X492874D01*
G01X492746D02*
X492761D01*
G01X495384D02*
X495472D01*
G01X495305D02*
X495325D01*
G01X495157D02*
X495246D01*
G01X494936D02*
X495025D01*
G01X494902D02*
X494917D01*
G01X494820D02*
X494843D01*
G01X497274Y31751D02*
X497372D01*
G01X497643D02*
X497717D01*
G01X499016Y33070D02*
X495866D01*
G01X492997Y31319D02*
X492990Y31329D01*
G01X493157Y31269D02*
X493150Y31279D01*
G01X493514Y31269D02*
X493507Y31279D01*
G01X493514Y31319D02*
X493507Y31329D01*
G01X493792Y31279D02*
X493799Y31269D01*
G01X493866Y31357D02*
X493858Y31367D01*
G01X494287Y31279D02*
X494294Y31269D01*
G01X494363Y31314D02*
X494356Y31324D01*
G01X494360Y31357D02*
X494353Y31367D01*
G01X495049Y31279D02*
X495057Y31269D01*
G01X492835Y31286D02*
X492840Y31279D01*
G01X492828Y31321D02*
X492822Y31329D01*
G01X492901Y31364D02*
X492906Y31357D01*
G01X493273Y31286D02*
X493278Y31279D01*
G01X493748Y31347D02*
X493743Y31354D01*
G01X493807Y31279D02*
X493802Y31286D01*
G01X493856Y31349D02*
X493851Y31357D01*
G01X493972Y31347D02*
X493967Y31354D01*
G01X494131Y31286D02*
X494137Y31279D01*
G01X494296Y31286D02*
X494301Y31279D01*
G01X494353Y31306D02*
X494348Y31314D01*
G01X494346Y31357D02*
X494350Y31349D01*
G01X494865Y31347D02*
X494860Y31354D01*
G01X497372Y31751D02*
X497557Y31462D01*
G01X497495Y31399D02*
X497274Y31751D01*
G01X492832Y31339D02*
X492837Y31329D01*
G01X492896Y31349D02*
X492894Y31354D01*
G01X493757Y31359D02*
X493763Y31349D01*
G01X493981Y31359D02*
X493986Y31349D01*
G01X494875Y31359D02*
X494880Y31349D01*
G01X494843Y31274D02*
X494852Y31276D01*
G01X494820Y31362D02*
X494811Y31359D01*
G01X493950Y31274D02*
X493959Y31276D01*
G01X493726Y31274D02*
X493735Y31276D01*
G01X493927Y31362D02*
X493917Y31359D01*
G01X493704Y31362D02*
X493694Y31359D01*
G01X492844Y31374D02*
X492854Y31377D01*
G01X493785Y31332D02*
X493789Y31319D01*
G01X493871Y31344D02*
X493866Y31357D01*
G01X494281Y31292D02*
X494287Y31279D01*
G01X494368Y31301D02*
X494363Y31314D01*
G01X495044Y31377D02*
X495067Y31319D01*
G01X495081Y31324D02*
X495062Y31377D01*
G01X493435D02*
X493470Y31284D01*
G01X493462Y31259D02*
X493425Y31364D01*
G01X495350Y31259D02*
X495315Y31362D01*
G01X495325Y31377D02*
X495364Y31259D01*
G01X492906Y31357D02*
X492909Y31349D01*
G01X492990Y31279D02*
X492987Y31286D01*
G01X493002Y31289D02*
X493005Y31281D01*
G01X492990Y31329D02*
X492987Y31337D01*
G01X493005Y31332D02*
X493002Y31339D01*
G01X493150Y31279D02*
X493147Y31286D01*
G01X493162D02*
X493165Y31279D01*
G01X493507D02*
X493504Y31286D01*
G01X493519Y31289D02*
X493521Y31281D01*
G01X493507Y31329D02*
X493504Y31337D01*
G01X493521Y31332D02*
X493519Y31339D01*
G01X493684Y31289D02*
X493686Y31281D01*
G01X493789Y31286D02*
X493792Y31279D01*
G01X493797Y31334D02*
X493799Y31327D01*
G01X493858Y31342D02*
X493856Y31349D01*
G01X493907Y31289D02*
X493910Y31281D01*
G01X494294Y31294D02*
X494296Y31286D01*
G01X494356Y31299D02*
X494353Y31306D01*
G01X494363Y31349D02*
X494360Y31357D01*
G01X494801Y31289D02*
X494803Y31281D01*
G01X495047Y31286D02*
X495049Y31279D01*
G01X495062Y31286D02*
X495064Y31279D01*
G01X492825Y31276D02*
X492822Y31286D01*
G01Y31329D02*
X492820Y31339D01*
G01X493261Y31276D02*
X493258Y31286D01*
G01X493750Y31337D02*
X493748Y31347D01*
G01X493974Y31337D02*
X493972Y31347D01*
G01X494119Y31276D02*
X494117Y31286D01*
G01X494867Y31337D02*
X494865Y31347D01*
G01X493671Y31276D02*
X493669Y31289D01*
G01X493763Y31349D02*
X493765Y31337D01*
G01X493895Y31276D02*
X493893Y31289D01*
G01X493986Y31349D02*
X493989Y31337D01*
G01X494789Y31276D02*
X494786Y31289D01*
G01X494880Y31349D02*
X494882Y31337D01*
G01X493873Y31327D02*
X493871Y31344D01*
G01X494279Y31309D02*
X494281Y31292D01*
G01X492707Y31259D02*
Y31271D01*
G01X492746D02*
Y31377D01*
G01X492761D02*
Y31271D01*
G01X492800D02*
Y31259D01*
G01X492820Y31339D02*
Y31349D01*
G01X492822Y31286D02*
Y31292D01*
G01X492832Y31349D02*
Y31339D01*
G01X492835Y31292D02*
Y31286D01*
G01X492869Y31321D02*
Y31312D01*
G01X492987Y31286D02*
Y31296D01*
G01Y31337D02*
Y31349D01*
G01X493002Y31294D02*
Y31289D01*
G01Y31339D02*
Y31347D01*
G01X493064Y31362D02*
Y31324D01*
G01Y31274D02*
Y31309D01*
G01X493078Y31377D02*
Y31259D01*
G01X493098D02*
Y31377D01*
G01X493110Y33070D02*
Y29920D01*
G01X493113Y31377D02*
Y31279D01*
G01X493128Y31296D02*
Y31276D01*
G01X493147Y31286D02*
Y31296D01*
G01X493162Y31294D02*
Y31286D01*
G01X493224Y31324D02*
Y31377D01*
G01Y31271D02*
Y31309D01*
G01X493238Y31377D02*
Y31259D01*
G01X493258Y31364D02*
Y31377D01*
G01Y31286D02*
Y31292D01*
G01X493273D02*
Y31286D01*
G01X493346Y31377D02*
Y31364D01*
G01X493366Y31259D02*
Y31377D01*
G01X493381D02*
Y31284D01*
G01X493470D02*
Y31377D01*
G01X493484D02*
Y31259D01*
G01X493504Y31286D02*
Y31296D01*
G01Y31337D02*
Y31349D01*
G01X493519Y31294D02*
Y31289D01*
G01Y31339D02*
Y31347D01*
G01X493580Y31362D02*
Y31324D01*
G01Y31274D02*
Y31309D01*
G01X493595Y31377D02*
Y31259D01*
G01X493615Y31321D02*
Y31334D01*
G01X493649D02*
Y31321D01*
G01X493750Y31299D02*
Y31337D01*
G01X493765D02*
Y31299D01*
G01X493785Y31344D02*
Y31332D01*
G01X493797Y31342D02*
Y31334D01*
G01X493858D02*
Y31342D01*
G01X493861Y31314D02*
Y31309D01*
G01X493873D02*
Y31327D01*
G01X493893Y31312D02*
Y31349D01*
G01X493907Y31347D02*
Y31327D01*
G01X493930D02*
Y31312D01*
G01X493974Y31299D02*
Y31337D01*
G01X493989D02*
Y31299D01*
G01X494068Y31259D02*
Y31377D01*
G01X494082D02*
Y31279D01*
G01X494097Y31296D02*
Y31276D01*
G01X494117Y31364D02*
Y31377D01*
G01Y31286D02*
Y31292D01*
G01X494131D02*
Y31286D01*
G01X494206Y31377D02*
Y31364D01*
G01X494225Y31321D02*
Y31334D01*
G01X494259D02*
Y31321D01*
G01X494279Y31327D02*
Y31309D01*
G01X494291Y31321D02*
Y31327D01*
G01X494294Y31299D02*
Y31294D01*
G01X494356D02*
Y31299D01*
G01X494368Y31292D02*
Y31301D01*
G01X494387Y31259D02*
Y31377D01*
G01X494402D02*
Y31279D01*
G01X494417Y31296D02*
Y31276D01*
G01X494555Y31259D02*
Y31271D01*
G01X494594D02*
Y31377D01*
G01X494609D02*
Y31271D01*
G01X494648D02*
Y31259D01*
G01X494668D02*
Y31377D01*
G01X494683D02*
Y31321D01*
G01Y31306D02*
Y31259D01*
G01X494752Y31321D02*
Y31377D01*
G01Y31259D02*
Y31306D01*
G01X494767Y31377D02*
Y31259D01*
G01X494786Y31312D02*
Y31349D01*
G01X494801Y31347D02*
Y31327D01*
G01X494823D02*
Y31312D01*
G01X494867Y31299D02*
Y31337D01*
G01X494882D02*
Y31299D01*
G01X494902Y31259D02*
Y31377D01*
G01X494917D02*
Y31259D01*
G01X494936Y31362D02*
Y31377D01*
G01X495010Y31259D02*
Y31362D01*
G01X495025Y31377D02*
Y31259D01*
G01X495047Y31296D02*
Y31286D01*
G01X495062Y31294D02*
Y31286D01*
G01X495123Y31377D02*
Y31324D01*
G01Y31271D02*
Y31309D01*
G01X495138Y31259D02*
Y31377D01*
G01X495157Y31259D02*
Y31274D01*
G01Y31362D02*
Y31377D01*
G01X495167Y31306D02*
Y31321D01*
G01X495231D02*
Y31362D01*
G01Y31274D02*
Y31306D01*
G01X495246Y31377D02*
Y31259D01*
G01X495384D02*
Y31274D01*
G01Y31362D02*
Y31377D01*
G01X495394Y31306D02*
Y31321D01*
G01X495458D02*
Y31362D01*
G01Y31274D02*
Y31306D01*
G01X495472Y31377D02*
Y31259D01*
G01X495866Y33070D02*
Y29920D01*
G01X496687D02*
Y33070D01*
G01X496850D02*
Y29920D01*
G01X497638D02*
Y33070D01*
G01X497643Y31550D02*
Y31751D01*
G01Y31160D02*
Y31449D01*
G01X497717Y31751D02*
Y31160D01*
G01X499016Y29920D02*
Y33070D01*
G01X493871Y31292D02*
X493873Y31309D01*
G01X494281Y31344D02*
X494279Y31327D01*
G01X493861Y31309D02*
X493858Y31294D01*
G01X494291Y31327D02*
X494294Y31342D01*
G01X493669Y31347D02*
X493671Y31359D01*
G01X493765Y31299D02*
X493763Y31286D01*
G01X493989Y31299D02*
X493986Y31286D01*
G01X494882Y31299D02*
X494880Y31286D01*
G01X492822Y31292D02*
X492825Y31301D01*
G01X492906Y31286D02*
X492904Y31276D01*
G01X493258Y31292D02*
X493261Y31301D01*
G01X493344Y31286D02*
X493342Y31276D01*
G01X493748Y31289D02*
X493750Y31299D01*
G01X493893Y31349D02*
X493895Y31359D01*
G01X493972Y31289D02*
X493974Y31299D01*
G01X494117Y31292D02*
X494119Y31301D01*
G01X494203Y31286D02*
X494200Y31276D01*
G01X494786Y31349D02*
X494789Y31359D01*
G01X494865Y31289D02*
X494867Y31299D01*
G01X492820Y31349D02*
X492822Y31357D01*
G01X492987Y31349D02*
X492990Y31357D01*
G01X493002Y31347D02*
X493005Y31354D01*
G01X492987Y31296D02*
X492990Y31304D01*
G01X493005Y31301D02*
X493002Y31294D01*
G01X493147Y31296D02*
X493150Y31304D01*
G01X493165Y31301D02*
X493162Y31294D01*
G01X493504Y31349D02*
X493507Y31357D01*
G01X493519Y31347D02*
X493521Y31354D01*
G01X493504Y31296D02*
X493507Y31304D01*
G01X493521Y31301D02*
X493519Y31294D01*
G01X493686Y31354D02*
X493684Y31347D01*
G01X493799Y31349D02*
X493797Y31342D01*
G01X493856Y31327D02*
X493858Y31334D01*
G01Y31294D02*
X493856Y31286D01*
G01X493910Y31354D02*
X493907Y31347D01*
G01X494294Y31342D02*
X494296Y31349D01*
G01Y31306D02*
X494294Y31299D01*
G01X494353Y31286D02*
X494356Y31294D01*
G01X494803Y31354D02*
X494801Y31347D01*
G01X495049Y31304D02*
X495047Y31296D01*
G01X495064Y31301D02*
X495062Y31294D01*
G01X495266Y31259D02*
X495305Y31377D01*
G01X495315Y31362D02*
X495281Y31259D01*
G01X493425Y31364D02*
X493389Y31259D01*
G01X493381Y31284D02*
X493415Y31377D01*
G01X493789Y31357D02*
X493785Y31344D01*
G01X493866Y31279D02*
X493871Y31292D01*
G01X494287Y31357D02*
X494281Y31344D01*
G01X494363Y31279D02*
X494368Y31292D01*
G01X492835Y31354D02*
X492832Y31349D01*
G01X492840Y31301D02*
X492835Y31292D01*
G01X493278Y31301D02*
X493273Y31292D01*
G01X493763Y31286D02*
X493757Y31276D01*
G01X493986Y31286D02*
X493981Y31276D01*
G01X494137Y31301D02*
X494131Y31292D01*
G01X494880Y31286D02*
X494875Y31276D01*
G01X492928Y31289D02*
X492960Y31352D01*
G01X492968Y31347D02*
X492936Y31284D01*
G01X494009Y31289D02*
X494041Y31352D01*
G01X494048Y31347D02*
X494016Y31284D01*
G01X492822Y31357D02*
X492828Y31364D01*
G01X492825Y31301D02*
X492830Y31309D01*
G01X492889Y31279D02*
X492894Y31286D01*
G01X493261Y31301D02*
X493265Y31309D01*
G01X493327Y31279D02*
X493332Y31286D01*
G01X493743Y31281D02*
X493748Y31289D01*
G01X493804Y31357D02*
X493799Y31349D01*
G01X493856Y31286D02*
X493851Y31279D01*
G01X493967Y31281D02*
X493972Y31289D01*
G01X494119Y31301D02*
X494124Y31309D01*
G01X494186Y31279D02*
X494191Y31286D01*
G01X494296Y31349D02*
X494301Y31357D01*
G01Y31314D02*
X494296Y31306D01*
G01X494348Y31279D02*
X494353Y31286D01*
G01X494860Y31281D02*
X494865Y31289D01*
G01X492990Y31357D02*
X492997Y31367D01*
G01X492990Y31304D02*
X492997Y31314D01*
G01X493150Y31304D02*
X493157Y31314D01*
G01X493507Y31357D02*
X493514Y31367D01*
G01X493507Y31304D02*
X493514Y31314D01*
G01X493797Y31367D02*
X493789Y31357D01*
G01X493858Y31269D02*
X493866Y31279D01*
G01X494294Y31367D02*
X494287Y31357D01*
G01X494356Y31269D02*
X494363Y31279D01*
G01X495057Y31314D02*
X495049Y31304D01*
G01X493113Y31279D02*
X493128Y31296D01*
G01Y31276D02*
X493113Y31259D01*
G01X494082Y31279D02*
X494097Y31296D01*
G01Y31276D02*
X494082Y31259D01*
G01X494402Y31279D02*
X494417Y31296D01*
G01Y31276D02*
X494402Y31259D01*
G01X497274Y31160D02*
X497495Y31399D01*
G01X497643Y31449D02*
X497372Y31160D01*
G01X492840Y31359D02*
X492835Y31354D01*
G01X492844Y31306D02*
X492840Y31301D01*
G01X492904Y31276D02*
X492894Y31266D01*
G01X493005Y31354D02*
X493009Y31359D01*
G01Y31306D02*
X493005Y31301D01*
G01X493169Y31306D02*
X493165Y31301D01*
G01X493342Y31276D02*
X493332Y31266D01*
G01X493521Y31354D02*
X493526Y31359D01*
G01Y31306D02*
X493521Y31301D01*
G01X493671Y31359D02*
X493681Y31369D01*
G01X493757Y31276D02*
X493748Y31266D01*
G01X493851Y31321D02*
X493856Y31327D01*
G01X493895Y31359D02*
X493905Y31369D01*
G01X493981Y31276D02*
X493972Y31266D01*
G01X494200Y31276D02*
X494191Y31266D01*
G01X494789Y31359D02*
X494798Y31369D01*
G01X494875Y31276D02*
X494865Y31266D01*
G01X495069Y31306D02*
X495064Y31301D01*
G01X497557Y31462D02*
X497643Y31550D01*
G01X493346Y31364D02*
X493278Y31301D01*
G01X494206Y31364D02*
X494137Y31301D01*
G01X493265Y31309D02*
X493327Y31364D01*
G01X494124Y31309D02*
X494186Y31364D01*
G01X492830Y31309D02*
X492840Y31316D01*
G01X492997Y31367D02*
X493007Y31374D01*
G01X493157Y31314D02*
X493167Y31321D01*
G01X493514Y31367D02*
X493524Y31374D01*
G01X492828Y31364D02*
X492835Y31369D01*
G01X492881Y31274D02*
X492889Y31279D01*
G01X493320Y31274D02*
X493327Y31279D01*
G01X493694Y31359D02*
X493686Y31354D01*
G01X493812Y31362D02*
X493804Y31357D01*
G01X493735Y31276D02*
X493743Y31281D01*
G01X493844Y31316D02*
X493851Y31321D01*
G01X493917Y31359D02*
X493910Y31354D01*
G01X493846Y31304D02*
X493861Y31314D01*
G01X493851Y31279D02*
X493844Y31274D01*
G01X493959Y31276D02*
X493967Y31281D01*
G01X494178Y31274D02*
X494186Y31279D01*
G01X494301Y31357D02*
X494309Y31362D01*
G01X494306Y31332D02*
X494291Y31321D01*
G01X494309Y31319D02*
X494301Y31314D01*
G01X494341Y31274D02*
X494348Y31279D01*
G01X494811Y31359D02*
X494803Y31354D01*
G01X494852Y31276D02*
X494860Y31281D01*
G01X493809Y31374D02*
X493797Y31367D01*
G01X493846Y31261D02*
X493858Y31269D01*
G01X494306Y31374D02*
X494294Y31367D01*
G01X494343Y31261D02*
X494356Y31269D01*
G01X492835Y31369D02*
X492844Y31374D01*
G01Y31362D02*
X492840Y31359D01*
G01X492894Y31266D02*
X492884Y31261D01*
G01X492997Y31314D02*
X493002Y31316D01*
G01X493332Y31266D02*
X493322Y31261D01*
G01X493514Y31314D02*
X493519Y31316D01*
G01X493681Y31369D02*
X493691Y31374D01*
G01X493905Y31369D02*
X493915Y31374D01*
G01X493748Y31266D02*
X493738Y31261D01*
G01X493972Y31266D02*
X493962Y31261D01*
G01X494191Y31266D02*
X494181Y31261D01*
G01X494798Y31369D02*
X494808Y31374D01*
G01X494865Y31266D02*
X494855Y31261D01*
G01X495067Y31319D02*
X495057Y31314D01*
G01X492859Y31312D02*
X492844Y31306D01*
G01X493009Y31359D02*
X493017Y31362D01*
G01Y31309D02*
X493009Y31306D01*
G01X493177Y31309D02*
X493169Y31306D01*
G01X493526Y31359D02*
X493533Y31362D01*
G01Y31309D02*
X493526Y31306D01*
G01X493819Y31364D02*
X493812Y31362D01*
G01X493836Y31314D02*
X493844Y31316D01*
G01Y31274D02*
X493836Y31271D01*
G01X494309Y31362D02*
X494316Y31364D01*
G01Y31321D02*
X494309Y31319D01*
G01X494333Y31271D02*
X494341Y31274D01*
G01X495076Y31309D02*
X495069Y31306D01*
G01X493009Y7654D02*
X493017Y7652D01*
G01Y7702D02*
X493009Y7705D01*
G01X493169Y7652D02*
X493177Y7649D01*
G01X493526Y7654D02*
X493533Y7652D01*
G01Y7702D02*
X493526Y7705D01*
G01X493822Y7649D02*
X493814Y7652D01*
G01X493812Y7694D02*
X493819Y7692D01*
G01X493844Y7740D02*
X493836Y7742D01*
G01X494309Y7652D02*
X494316Y7649D01*
G01X494341Y7697D02*
X494333Y7699D01*
G01X494331Y7742D02*
X494338Y7740D01*
G01X495069Y7652D02*
X495076Y7649D01*
G01X492840Y7694D02*
X492828Y7699D01*
G01X492844Y7639D02*
X492835Y7644D01*
G01X492889Y7737D02*
X492884Y7740D01*
G01Y7752D02*
X492894Y7747D01*
G01X493002Y7694D02*
X492997Y7697D01*
G01X493280Y7639D02*
X493270Y7644D01*
G01X493519Y7694D02*
X493514Y7697D01*
G01X493691Y7639D02*
X493681Y7644D01*
G01X493915Y7639D02*
X493905Y7644D01*
G01X493738Y7752D02*
X493748Y7747D01*
G01X494139Y7639D02*
X494129Y7644D01*
G01X493962Y7752D02*
X493972Y7747D01*
G01X494808Y7639D02*
X494798Y7644D01*
G01X494855Y7752D02*
X494865Y7747D01*
G01X493799Y7647D02*
X493812Y7639D01*
G01X493797Y7690D02*
X493809Y7682D01*
G01X493858Y7745D02*
X493846Y7752D01*
G01X494294Y7647D02*
X494306Y7639D01*
G01X494356Y7702D02*
X494343Y7710D01*
G01X494353Y7745D02*
X494341Y7752D01*
G01X492840Y7657D02*
X492847Y7652D01*
G01X492837Y7707D02*
X492844Y7702D01*
G01X492936Y7662D02*
X492928Y7667D01*
G01X492894Y7747D02*
X492901Y7742D01*
G01X492960Y7730D02*
X492968Y7725D01*
G01X493278Y7657D02*
X493285Y7652D01*
G01X493686Y7659D02*
X493694Y7654D01*
G01X493814Y7652D02*
X493807Y7657D01*
G01X493743Y7732D02*
X493735Y7737D01*
G01X493804Y7699D02*
X493812Y7694D01*
G01X493910Y7659D02*
X493917Y7654D01*
G01X493851Y7735D02*
X493844Y7740D01*
G01X494016Y7662D02*
X494009Y7667D01*
G01X493967Y7732D02*
X493959Y7737D01*
G01X494137Y7657D02*
X494144Y7652D01*
G01X494041Y7730D02*
X494048Y7725D01*
G01X494301Y7657D02*
X494309Y7652D01*
G01X494348Y7692D02*
X494341Y7697D01*
G01X494338Y7740D02*
X494346Y7735D01*
G01X494803Y7659D02*
X494811Y7654D01*
G01X494860Y7732D02*
X494852Y7737D01*
G01X493007Y7639D02*
X492997Y7647D01*
G01X497372Y7538D02*
X497274D01*
G01X497717D02*
X497643D01*
G01X495472Y7637D02*
X495384D01*
G01X495281D02*
X495266D01*
G01X495364D02*
X495350D01*
G01X495246D02*
X495157D01*
G01X495025D02*
X495010D01*
G01X494917D02*
X494902D01*
G01X494843D02*
X494820D01*
G01X494683D02*
X494668D01*
G01X494767D02*
X494752D01*
G01X494648D02*
X494555D01*
G01X494402D02*
X494387D01*
G01X494163D02*
X494154D01*
G01X494082D02*
X494068D01*
G01X493950D02*
X493927D01*
G01X493726D02*
X493704D01*
G01X493595D02*
X493536D01*
G01X493389D02*
X493366D01*
G01X493484D02*
X493462D01*
G01X493305D02*
X493295D01*
G01X493238D02*
X493179D01*
G01X493113D02*
X493098D01*
G01X493078D02*
X493019D01*
G01X492867D02*
X492862D01*
G01X492800D02*
X492707D01*
G01X494319D02*
X494331D01*
G01X493824D02*
X493834D01*
G01X495079D02*
X495138D01*
G01X493836Y7649D02*
X493822D01*
G01X494609D02*
X494648D01*
G01X494555D02*
X494594D01*
G01X494316D02*
X494333D01*
G01X494156D02*
X494166D01*
G01X493297D02*
X493307D01*
G01X493177D02*
X493224D01*
G01X492859D02*
X492869D01*
G01X492761D02*
X492800D01*
G01X492707D02*
X492746D01*
G01X495076D02*
X495123D01*
G01X493927Y7652D02*
X493950D01*
G01X493704D02*
X493726D01*
G01X493533D02*
X493580D01*
G01X493017D02*
X493064D01*
G01X495384D02*
X495458D01*
G01X495157D02*
X495231D01*
G01X494820D02*
X494843D01*
G01X493802Y7664D02*
X493789D01*
G01X494191D02*
X494203D01*
G01X493332D02*
X493344D01*
G01X492894D02*
X492906D01*
G01X494786Y7667D02*
X494801D01*
G01X493893D02*
X493907D01*
G01X493669D02*
X493684D01*
G01X493822Y7679D02*
X493834D01*
G01X495458Y7684D02*
X495394D01*
G01X495231D02*
X495167D01*
G01X494752D02*
X494683D01*
G01X495123Y7687D02*
X495076D01*
G01X493580D02*
X493533D01*
G01X493224D02*
X493177D01*
G01X493064D02*
X493017D01*
G01X494823Y7690D02*
X494786D01*
G01X493930D02*
X493893D01*
G01X492869D02*
X492859D01*
G01X493819Y7692D02*
X493836D01*
G01X494333Y7699D02*
X494316D01*
G01X494259D02*
X494225D01*
G01X493649D02*
X493615D01*
G01X494683D02*
X494752D01*
G01X492859D02*
X492869D01*
G01X495394D02*
X495458D01*
G01X495167D02*
X495231D01*
G01X495123Y7702D02*
X495081D01*
G01X493580D02*
X493533D01*
G01X493064D02*
X493017D01*
G01X493179D02*
X493224D01*
G01X494801Y7705D02*
X494823D01*
G01X493907D02*
X493930D01*
G01X494331Y7712D02*
X494319D01*
G01X494225D02*
X494259D01*
G01X493615D02*
X493649D01*
G01X493684Y7725D02*
X493669D01*
G01X492909Y7727D02*
X492896D01*
G01X494350D02*
X494363D01*
G01X495458Y7740D02*
X495384D01*
G01X495231D02*
X495157D01*
G01X495010D02*
X494936D01*
G01X494843D02*
X494820D01*
G01X493950D02*
X493927D01*
G01X493726D02*
X493704D01*
G01X493533D02*
X493580D01*
G01X493017D02*
X493064D01*
G01X494186Y7742D02*
X494117D01*
G01X493836D02*
X493819D01*
G01X493327D02*
X493258D01*
G01X492872D02*
X492857D01*
G01X494316D02*
X494331D01*
G01X495062Y7755D02*
X495044D01*
G01X495138D02*
X495123D01*
G01X494328D02*
X494319D01*
G01X493834D02*
X493822D01*
G01X494668D02*
X494683D01*
G01X494752D02*
X494767D01*
G01X494594D02*
X494609D01*
G01X494387D02*
X494402D01*
G01X494117D02*
X494206D01*
G01X494068D02*
X494082D01*
G01X493927D02*
X493950D01*
G01X493704D02*
X493726D01*
G01X493536D02*
X493595D01*
G01X493366D02*
X493381D01*
G01X493470D02*
X493484D01*
G01X493415D02*
X493435D01*
G01X493258D02*
X493346D01*
G01X493224D02*
X493238D01*
G01X493098D02*
X493113D01*
G01X493019D02*
X493078D01*
G01X492854D02*
X492874D01*
G01X492746D02*
X492761D01*
G01X495384D02*
X495472D01*
G01X495305D02*
X495325D01*
G01X495157D02*
X495246D01*
G01X494936D02*
X495025D01*
G01X494902D02*
X494917D01*
G01X494820D02*
X494843D01*
G01X497274Y8129D02*
X497372D01*
G01X497643D02*
X497717D01*
G01X499016Y9448D02*
X495866D01*
G01X492862Y7637D02*
X492844Y7639D01*
G01Y7702D02*
X492859Y7699D01*
G01X493295Y7637D02*
X493280Y7639D01*
G01X494154Y7637D02*
X494139Y7639D01*
G01X492847Y7652D02*
X492859Y7649D01*
G01X493019Y7637D02*
X493007Y7639D01*
G01X493179Y7637D02*
X493167Y7639D01*
G01X493285Y7652D02*
X493297Y7649D01*
G01X492884Y7740D02*
X492872Y7742D01*
G01X493536Y7637D02*
X493524Y7639D01*
G01X493704Y7637D02*
X493691Y7639D01*
G01X493812D02*
X493824Y7637D01*
G01X493927D02*
X493915Y7639D01*
G01X493809Y7682D02*
X493822Y7679D01*
G01X494144Y7652D02*
X494156Y7649D01*
G01X493726Y7755D02*
X493738Y7752D01*
G01X494306Y7639D02*
X494319Y7637D01*
G01X493846Y7752D02*
X493834Y7755D01*
G01X493950D02*
X493962Y7752D01*
G01X494343Y7710D02*
X494331Y7712D01*
G01X494820Y7637D02*
X494808Y7639D01*
G01X494341Y7752D02*
X494328Y7755D01*
G01X495067Y7639D02*
X495079Y7637D01*
G01X494843Y7755D02*
X494855Y7752D01*
G01X492874Y7755D02*
X492884Y7752D01*
G01X493917Y7654D02*
X493927Y7652D01*
G01X493735Y7737D02*
X493726Y7740D01*
G01X493694Y7654D02*
X493704Y7652D01*
G01X493959Y7737D02*
X493950Y7740D01*
G01X494811Y7654D02*
X494820Y7652D01*
G01X494852Y7737D02*
X494843Y7740D01*
G01X493167Y7639D02*
X493157Y7647D01*
G01X493524Y7639D02*
X493514Y7647D01*
G01X495057D02*
X495067Y7639D01*
G01X493005Y7659D02*
X493009Y7654D01*
G01Y7705D02*
X493005Y7710D01*
G01X493521Y7659D02*
X493526Y7654D01*
G01Y7705D02*
X493521Y7710D01*
G01X492835Y7644D02*
X492825Y7654D01*
G01X492894Y7732D02*
X492889Y7737D01*
G01X493165Y7657D02*
X493169Y7652D01*
G01X493270Y7644D02*
X493261Y7654D01*
G01X493681Y7644D02*
X493671Y7654D01*
G01X493789Y7697D02*
X493797Y7690D01*
G01X493748Y7747D02*
X493757Y7737D01*
G01X493799Y7705D02*
X493804Y7699D01*
G01X493905Y7644D02*
X493895Y7654D01*
G01X493972Y7747D02*
X493981Y7737D01*
G01X494129Y7644D02*
X494119Y7654D01*
G01X494798Y7644D02*
X494789Y7654D01*
G01X494865Y7747D02*
X494875Y7737D01*
G01X495064Y7657D02*
X495069Y7652D01*
G01X492997Y7647D02*
X492990Y7657D01*
G01X492997Y7697D02*
X492990Y7707D01*
G01X493157Y7647D02*
X493150Y7657D01*
G01X493514Y7647D02*
X493507Y7657D01*
G01X493514Y7697D02*
X493507Y7707D01*
G01X493792Y7657D02*
X493799Y7647D01*
G01X493866Y7735D02*
X493858Y7745D01*
G01X494287Y7657D02*
X494294Y7647D01*
G01X494363Y7692D02*
X494356Y7702D01*
G01X494360Y7735D02*
X494353Y7745D01*
G01X495049Y7657D02*
X495057Y7647D01*
G01X492835Y7664D02*
X492840Y7657D01*
G01X492828Y7699D02*
X492822Y7707D01*
G01X492901Y7742D02*
X492906Y7735D01*
G01X493273Y7664D02*
X493278Y7657D01*
G01X493748Y7725D02*
X493743Y7732D01*
G01X493807Y7657D02*
X493802Y7664D01*
G01X493856Y7727D02*
X493851Y7735D01*
G01X493972Y7725D02*
X493967Y7732D01*
G01X494131Y7664D02*
X494137Y7657D01*
G01X494296Y7664D02*
X494301Y7657D01*
G01X494353Y7684D02*
X494348Y7692D01*
G01X494346Y7735D02*
X494350Y7727D01*
G01X494843Y7652D02*
X494852Y7654D01*
G01X494820Y7740D02*
X494811Y7737D01*
G01X493950Y7652D02*
X493959Y7654D01*
G01X493726Y7652D02*
X493735Y7654D01*
G01X493927Y7740D02*
X493917Y7737D01*
G01X493704Y7740D02*
X493694Y7737D01*
G01X492844Y7752D02*
X492854Y7755D01*
G01X494855Y7639D02*
X494843Y7637D01*
G01X494331D02*
X494343Y7639D01*
G01X494808Y7752D02*
X494820Y7755D01*
G01X494166Y7649D02*
X494178Y7652D01*
G01X494319Y7712D02*
X494306Y7710D01*
G01X493962Y7639D02*
X493950Y7637D01*
G01X493834D02*
X493846Y7639D01*
G01X494319Y7755D02*
X494306Y7752D01*
G01X493738Y7639D02*
X493726Y7637D01*
G01X493834Y7679D02*
X493846Y7682D01*
G01X493915Y7752D02*
X493927Y7755D01*
G01X493307Y7649D02*
X493320Y7652D01*
G01X493822Y7755D02*
X493809Y7752D01*
G01X493691D02*
X493704Y7755D01*
G01X493524Y7752D02*
X493536Y7755D01*
G01X493167Y7699D02*
X493179Y7702D01*
G01X492869Y7649D02*
X492881Y7652D01*
G01X493007Y7752D02*
X493019Y7755D01*
G01X492857Y7742D02*
X492844Y7740D01*
G01X494181Y7639D02*
X494163Y7637D01*
G01X493322Y7639D02*
X493305Y7637D01*
G01X492884Y7639D02*
X492867Y7637D01*
G01X494865Y7725D02*
X494860Y7732D01*
G01X497372Y8129D02*
X497557Y7840D01*
G01X497495Y7777D02*
X497274Y8129D01*
G01X492832Y7717D02*
X492837Y7707D01*
G01X492896Y7727D02*
X492894Y7732D01*
G01X493757Y7737D02*
X493763Y7727D01*
G01X493981Y7737D02*
X493986Y7727D01*
G01X494875Y7737D02*
X494880Y7727D01*
G01X493785Y7710D02*
X493789Y7697D01*
G01X493871Y7722D02*
X493866Y7735D01*
G01X494281Y7669D02*
X494287Y7657D01*
G01X494368Y7679D02*
X494363Y7692D01*
G01X495044Y7755D02*
X495067Y7697D01*
G01X495081Y7702D02*
X495062Y7755D01*
G01X493435D02*
X493470Y7662D01*
G01X493462Y7637D02*
X493425Y7742D01*
G01X495350Y7637D02*
X495315Y7740D01*
G01X495325Y7755D02*
X495364Y7637D01*
G01X492906Y7735D02*
X492909Y7727D01*
G01X492990Y7657D02*
X492987Y7664D01*
G01X493002Y7667D02*
X493005Y7659D01*
G01X492990Y7707D02*
X492987Y7715D01*
G01X493005Y7710D02*
X493002Y7717D01*
G01X493150Y7657D02*
X493147Y7664D01*
G01X493162D02*
X493165Y7657D01*
G01X493507D02*
X493504Y7664D01*
G01X493519Y7667D02*
X493521Y7659D01*
G01X493507Y7707D02*
X493504Y7715D01*
G01X493521Y7710D02*
X493519Y7717D01*
G01X493684Y7667D02*
X493686Y7659D01*
G01X493789Y7664D02*
X493792Y7657D01*
G01X493797Y7712D02*
X493799Y7705D01*
G01X493858Y7719D02*
X493856Y7727D01*
G01X493907Y7667D02*
X493910Y7659D01*
G01X494294Y7672D02*
X494296Y7664D01*
G01X494356Y7677D02*
X494353Y7684D01*
G01X494363Y7727D02*
X494360Y7735D01*
G01X494801Y7667D02*
X494803Y7659D01*
G01X495047Y7664D02*
X495049Y7657D01*
G01X495062Y7664D02*
X495064Y7657D01*
G01X492825Y7654D02*
X492822Y7664D01*
G01Y7707D02*
X492820Y7717D01*
G01X493261Y7654D02*
X493258Y7664D01*
G01X493750Y7715D02*
X493748Y7725D01*
G01X493974Y7715D02*
X493972Y7725D01*
G01X494119Y7654D02*
X494117Y7664D01*
G01X494867Y7715D02*
X494865Y7725D01*
G01X493671Y7654D02*
X493669Y7667D01*
G01X493763Y7727D02*
X493765Y7715D01*
G01X493895Y7654D02*
X493893Y7667D01*
G01X493986Y7727D02*
X493989Y7715D01*
G01X494789Y7654D02*
X494786Y7667D01*
G01X494880Y7727D02*
X494882Y7715D01*
G01X493873Y7705D02*
X493871Y7722D01*
G01X494279Y7687D02*
X494281Y7669D01*
G01X492707Y7637D02*
Y7649D01*
G01X492746D02*
Y7755D01*
G01X492761D02*
Y7649D01*
G01X492800D02*
Y7637D01*
G01X492820Y7717D02*
Y7727D01*
G01X492822Y7664D02*
Y7669D01*
G01X492832Y7727D02*
Y7717D01*
G01X492835Y7669D02*
Y7664D01*
G01X492869Y7699D02*
Y7690D01*
G01X492987Y7664D02*
Y7674D01*
G01Y7715D02*
Y7727D01*
G01X493002Y7672D02*
Y7667D01*
G01Y7717D02*
Y7725D01*
G01X493064Y7740D02*
Y7702D01*
G01Y7652D02*
Y7687D01*
G01X493078Y7755D02*
Y7637D01*
G01X493098D02*
Y7755D01*
G01X493113D02*
Y7657D01*
G01X493128Y7674D02*
Y7654D01*
G01X493147Y7664D02*
Y7674D01*
G01X493162Y7672D02*
Y7664D01*
G01X493224Y7702D02*
Y7755D01*
G01Y7649D02*
Y7687D01*
G01X493238Y7755D02*
Y7637D01*
G01X493258Y7742D02*
Y7755D01*
G01Y7664D02*
Y7669D01*
G01X493273D02*
Y7664D01*
G01X493346Y7755D02*
Y7742D01*
G01X493366Y7637D02*
Y7755D01*
G01X493381D02*
Y7662D01*
G01X493470D02*
Y7755D01*
G01X493484D02*
Y7637D01*
G01X493504Y7664D02*
Y7674D01*
G01Y7715D02*
Y7727D01*
G01X493519Y7672D02*
Y7667D01*
G01Y7717D02*
Y7725D01*
G01X493580Y7740D02*
Y7702D01*
G01Y7652D02*
Y7687D01*
G01X493595Y7755D02*
Y7637D01*
G01X493615Y7699D02*
Y7712D01*
G01X493649D02*
Y7699D01*
G01X493750Y7677D02*
Y7715D01*
G01X493765D02*
Y7677D01*
G01X493785Y7722D02*
Y7710D01*
G01X493797Y7719D02*
Y7712D01*
G01X493858D02*
Y7719D01*
G01X493861Y7692D02*
Y7687D01*
G01X493873D02*
Y7705D01*
G01X493893Y7690D02*
Y7727D01*
G01X493907Y7725D02*
Y7705D01*
G01X493930D02*
Y7690D01*
G01X493974Y7677D02*
Y7715D01*
G01X493989D02*
Y7677D01*
G01X494068Y7637D02*
Y7755D01*
G01X494082D02*
Y7657D01*
G01X494097Y7674D02*
Y7654D01*
G01X494117Y7742D02*
Y7755D01*
G01Y7664D02*
Y7669D01*
G01X494131D02*
Y7664D01*
G01X494206Y7755D02*
Y7742D01*
G01X494225Y7699D02*
Y7712D01*
G01X494259D02*
Y7699D01*
G01X494279Y7705D02*
Y7687D01*
G01X494291Y7699D02*
Y7705D01*
G01X494294Y7677D02*
Y7672D01*
G01X494356D02*
Y7677D01*
G01X494368Y7669D02*
Y7679D01*
G01X494387Y7637D02*
Y7755D01*
G01X494402D02*
Y7657D01*
G01X494417Y7674D02*
Y7654D01*
G01X494555Y7637D02*
Y7649D01*
G01X494594D02*
Y7755D01*
G01X494609D02*
Y7649D01*
G01X494648D02*
Y7637D01*
G01X494668D02*
Y7755D01*
G01X494683D02*
Y7699D01*
G01Y7684D02*
Y7637D01*
G01X494752Y7699D02*
Y7755D01*
G01Y7637D02*
Y7684D01*
G01X494767Y7755D02*
Y7637D01*
G01X494786Y7690D02*
Y7727D01*
G01X494801Y7725D02*
Y7705D01*
G01X494823D02*
Y7690D01*
G01X494867Y7677D02*
Y7715D01*
G01X494882D02*
Y7677D01*
G01X494902Y7637D02*
Y7755D01*
G01X494917D02*
Y7637D01*
G01X494936Y7740D02*
Y7755D01*
G01X495010Y7637D02*
Y7740D01*
G01X495025Y7755D02*
Y7637D01*
G01X495047Y7674D02*
Y7664D01*
G01X495062Y7672D02*
Y7664D01*
G01X495123Y7755D02*
Y7702D01*
G01Y7649D02*
Y7687D01*
G01X495138Y7637D02*
Y7755D01*
G01X495157Y7637D02*
Y7652D01*
G01Y7740D02*
Y7755D01*
G01X495167Y7684D02*
Y7699D01*
G01X495231D02*
Y7740D01*
G01Y7652D02*
Y7684D01*
G01X495246Y7755D02*
Y7637D01*
G01X495384D02*
Y7652D01*
G01Y7740D02*
Y7755D01*
G01X495394Y7684D02*
Y7699D01*
G01X495458D02*
Y7740D01*
G01Y7652D02*
Y7684D01*
G01X495472Y7755D02*
Y7637D01*
G01X497643Y7928D02*
Y8129D01*
G01Y7538D02*
Y7827D01*
G01X497717Y8129D02*
Y7538D01*
G01X493871Y7669D02*
X493873Y7687D01*
G01X494281Y7722D02*
X494279Y7705D01*
G01X493861Y7687D02*
X493858Y7672D01*
G01X494291Y7705D02*
X494294Y7719D01*
G01X493669Y7725D02*
X493671Y7737D01*
G01X493765Y7677D02*
X493763Y7664D01*
G01X493989Y7677D02*
X493986Y7664D01*
G01X494882Y7677D02*
X494880Y7664D01*
G01X492822Y7669D02*
X492825Y7679D01*
G01X492906Y7664D02*
X492904Y7654D01*
G01X493258Y7669D02*
X493261Y7679D01*
G01X493344Y7664D02*
X493342Y7654D01*
G01X493748Y7667D02*
X493750Y7677D01*
G01X493893Y7727D02*
X493895Y7737D01*
G01X493972Y7667D02*
X493974Y7677D01*
G01X494117Y7669D02*
X494119Y7679D01*
G01X494203Y7664D02*
X494200Y7654D01*
G01X494786Y7727D02*
X494789Y7737D01*
G01X494865Y7667D02*
X494867Y7677D01*
G01X492820Y7727D02*
X492822Y7735D01*
G01X492987Y7727D02*
X492990Y7735D01*
G01X493002Y7725D02*
X493005Y7732D01*
G01X492987Y7674D02*
X492990Y7682D01*
G01X493005Y7679D02*
X493002Y7672D01*
G01X493147Y7674D02*
X493150Y7682D01*
G01X493165Y7679D02*
X493162Y7672D01*
G01X493504Y7727D02*
X493507Y7735D01*
G01X493519Y7725D02*
X493521Y7732D01*
G01X493504Y7674D02*
X493507Y7682D01*
G01X493521Y7679D02*
X493519Y7672D01*
G01X493686Y7732D02*
X493684Y7725D01*
G01X493799Y7727D02*
X493797Y7719D01*
G01X493856Y7705D02*
X493858Y7712D01*
G01Y7672D02*
X493856Y7664D01*
G01X493910Y7732D02*
X493907Y7725D01*
G01X494294Y7719D02*
X494296Y7727D01*
G01Y7684D02*
X494294Y7677D01*
G01X494353Y7664D02*
X494356Y7672D01*
G01X494803Y7732D02*
X494801Y7725D01*
G01X495049Y7682D02*
X495047Y7674D01*
G01X495064Y7679D02*
X495062Y7672D01*
G01X495266Y7637D02*
X495305Y7755D01*
G01X495315Y7740D02*
X495281Y7637D01*
G01X493425Y7742D02*
X493389Y7637D01*
G01X493381Y7662D02*
X493415Y7755D01*
G01X493789Y7735D02*
X493785Y7722D01*
G01X493866Y7657D02*
X493871Y7669D01*
G01X494287Y7735D02*
X494281Y7722D01*
G01X494363Y7657D02*
X494368Y7669D01*
G01X492835Y7732D02*
X492832Y7727D01*
G01X492840Y7679D02*
X492835Y7669D01*
G01X493278Y7679D02*
X493273Y7669D01*
G01X493763Y7664D02*
X493757Y7654D01*
G01X493986Y7664D02*
X493981Y7654D01*
G01X494137Y7679D02*
X494131Y7669D01*
G01X494880Y7664D02*
X494875Y7654D01*
G01X492928Y7667D02*
X492960Y7730D01*
G01X492968Y7725D02*
X492936Y7662D01*
G01X494009Y7667D02*
X494041Y7730D01*
G01X494048Y7725D02*
X494016Y7662D01*
G01X492822Y7735D02*
X492828Y7742D01*
G01X492825Y7679D02*
X492830Y7687D01*
G01X492889Y7657D02*
X492894Y7664D01*
G01X493261Y7679D02*
X493265Y7687D01*
G01X493327Y7657D02*
X493332Y7664D01*
G01X493743Y7659D02*
X493748Y7667D01*
G01X493804Y7735D02*
X493799Y7727D01*
G01X493856Y7664D02*
X493851Y7657D01*
G01X493967Y7659D02*
X493972Y7667D01*
G01X494119Y7679D02*
X494124Y7687D01*
G01X494186Y7657D02*
X494191Y7664D01*
G01X494296Y7727D02*
X494301Y7735D01*
G01Y7692D02*
X494296Y7684D01*
G01X494348Y7657D02*
X494353Y7664D01*
G01X494860Y7659D02*
X494865Y7667D01*
G01X492990Y7735D02*
X492997Y7745D01*
G01X492990Y7682D02*
X492997Y7692D01*
G01X493150Y7682D02*
X493157Y7692D01*
G01X493507Y7735D02*
X493514Y7745D01*
G01X493507Y7682D02*
X493514Y7692D01*
G01X493797Y7745D02*
X493789Y7735D01*
G01X493858Y7647D02*
X493866Y7657D01*
G01X494294Y7745D02*
X494287Y7735D01*
G01X494356Y7647D02*
X494363Y7657D01*
G01X495057Y7692D02*
X495049Y7682D01*
G01X493113Y7657D02*
X493128Y7674D01*
G01Y7654D02*
X493113Y7637D01*
G01X494082Y7657D02*
X494097Y7674D01*
G01Y7654D02*
X494082Y7637D01*
G01X494402Y7657D02*
X494417Y7674D01*
G01Y7654D02*
X494402Y7637D01*
G01X497274Y7538D02*
X497495Y7777D01*
G01X497643Y7827D02*
X497372Y7538D01*
G01X492840Y7737D02*
X492835Y7732D01*
G01X492844Y7684D02*
X492840Y7679D01*
G01X492904Y7654D02*
X492894Y7644D01*
G01X493005Y7732D02*
X493009Y7737D01*
G01Y7684D02*
X493005Y7679D01*
G01X493169Y7684D02*
X493165Y7679D01*
G01X493342Y7654D02*
X493332Y7644D01*
G01X493521Y7732D02*
X493526Y7737D01*
G01Y7684D02*
X493521Y7679D01*
G01X493671Y7737D02*
X493681Y7747D01*
G01X493757Y7654D02*
X493748Y7644D01*
G01X493851Y7699D02*
X493856Y7705D01*
G01X493895Y7737D02*
X493905Y7747D01*
G01X493981Y7654D02*
X493972Y7644D01*
G01X494200Y7654D02*
X494191Y7644D01*
G01X494789Y7737D02*
X494798Y7747D01*
G01X494875Y7654D02*
X494865Y7644D01*
G01X495069Y7684D02*
X495064Y7679D01*
G01X497557Y7840D02*
X497643Y7928D01*
G01X493346Y7742D02*
X493278Y7679D01*
G01X494206Y7742D02*
X494137Y7679D01*
G01X493265Y7687D02*
X493327Y7742D01*
G01X494124Y7687D02*
X494186Y7742D01*
G01X492830Y7687D02*
X492840Y7694D01*
G01X492997Y7745D02*
X493007Y7752D01*
G01X493157Y7692D02*
X493167Y7699D01*
G01X493514Y7745D02*
X493524Y7752D01*
G01X492828Y7742D02*
X492835Y7747D01*
G01X492881Y7652D02*
X492889Y7657D01*
G01X493320Y7652D02*
X493327Y7657D01*
G01X493694Y7737D02*
X493686Y7732D01*
G01X493812Y7740D02*
X493804Y7735D01*
G01X493735Y7654D02*
X493743Y7659D01*
G01X493844Y7694D02*
X493851Y7699D01*
G01X493917Y7737D02*
X493910Y7732D01*
G01X493846Y7682D02*
X493861Y7692D01*
G01X493851Y7657D02*
X493844Y7652D01*
G01X493959Y7654D02*
X493967Y7659D01*
G01X494178Y7652D02*
X494186Y7657D01*
G01X494301Y7735D02*
X494309Y7740D01*
G01X494306Y7710D02*
X494291Y7699D01*
G01X494309Y7697D02*
X494301Y7692D01*
G01X494341Y7652D02*
X494348Y7657D01*
G01X494811Y7737D02*
X494803Y7732D01*
G01X494852Y7654D02*
X494860Y7659D01*
G01X493809Y7752D02*
X493797Y7745D01*
G01X493846Y7639D02*
X493858Y7647D01*
G01X494306Y7752D02*
X494294Y7745D01*
G01X494343Y7639D02*
X494356Y7647D01*
G01X492835Y7747D02*
X492844Y7752D01*
G01Y7740D02*
X492840Y7737D01*
G01X492894Y7644D02*
X492884Y7639D01*
G01X492997Y7692D02*
X493002Y7694D01*
G01X493332Y7644D02*
X493322Y7639D01*
G01X493514Y7692D02*
X493519Y7694D01*
G01X493681Y7747D02*
X493691Y7752D01*
G01X493905Y7747D02*
X493915Y7752D01*
G01X493748Y7644D02*
X493738Y7639D01*
G01X493972Y7644D02*
X493962Y7639D01*
G01X494191Y7644D02*
X494181Y7639D01*
G01X494798Y7747D02*
X494808Y7752D01*
G01X494865Y7644D02*
X494855Y7639D01*
G01X495067Y7697D02*
X495057Y7692D01*
G01X492859Y7690D02*
X492844Y7684D01*
G01X493009Y7737D02*
X493017Y7740D01*
G01Y7687D02*
X493009Y7684D01*
G01X493177Y7687D02*
X493169Y7684D01*
G01X493526Y7737D02*
X493533Y7740D01*
G01Y7687D02*
X493526Y7684D01*
G01X493819Y7742D02*
X493812Y7740D01*
G01X493836Y7692D02*
X493844Y7694D01*
G01Y7652D02*
X493836Y7649D01*
G01X494309Y7740D02*
X494316Y7742D01*
G01Y7699D02*
X494309Y7697D01*
G01X494333Y7649D02*
X494341Y7652D01*
G01X495076Y7687D02*
X495069Y7684D01*
G01X493110Y29920D02*
X489961D01*
G01X491339D02*
X497638D01*
G01X491496Y31160D02*
X491398D01*
G01X491336Y31550D02*
X491558D01*
G01X491324Y31600D02*
X491570D01*
G01X491619Y31751D02*
X491693D01*
G01X491201D02*
X491275D01*
G01X497638Y33070D02*
X491339D01*
G01X489961D02*
X493110D01*
G01X491398Y31160D02*
X491201Y31751D01*
G01X491447Y31210D02*
X491336Y31550D01*
G01X491275Y31751D02*
X491324Y31600D01*
G01X489961Y29920D02*
Y33070D01*
G01X491339D02*
Y29920D01*
G01X492126Y33070D02*
Y29920D01*
G01X492290Y33070D02*
Y29920D01*
G01X491570Y31600D02*
X491619Y31751D01*
G01X491558Y31550D02*
X491447Y31210D01*
G01X491693Y31751D02*
X491496Y31160D01*
G01Y7538D02*
X491398D01*
G01X491336Y7928D02*
X491558D01*
G01X491324Y7978D02*
X491570D01*
G01X491619Y8129D02*
X491693D01*
G01X491201D02*
X491275D01*
G01X497638Y9448D02*
X491339D01*
G01X489961D02*
X493110D01*
G01X491398Y7538D02*
X491201Y8129D01*
G01X491447Y7588D02*
X491336Y7928D01*
G01X491275Y8129D02*
X491324Y7978D01*
G01X491570D02*
X491619Y8129D01*
G01X491558Y7928D02*
X491447Y7588D01*
G01X491693Y8129D02*
X491496Y7538D01*
G01X492844Y54946D02*
X492859Y54943D01*
G01X493295Y54881D02*
X493280Y54883D01*
G01X494154Y54881D02*
X494139Y54883D01*
G01X492847Y54896D02*
X492859Y54893D01*
G01X493019Y54881D02*
X493007Y54883D01*
G01X493179Y54881D02*
X493167Y54883D01*
G01X493285Y54896D02*
X493297Y54893D01*
G01X492884Y54984D02*
X492872Y54986D01*
G01X493536Y54881D02*
X493524Y54883D01*
G01X493704Y54881D02*
X493691Y54883D01*
G01X493812D02*
X493824Y54881D01*
G01X493927D02*
X493915Y54883D01*
G01X493809Y54926D02*
X493822Y54923D01*
G01X494144Y54896D02*
X494156Y54893D01*
G01X493726Y54999D02*
X493738Y54996D01*
G01X494306Y54883D02*
X494319Y54881D01*
G01X493846Y54996D02*
X493834Y54999D01*
G01X493950D02*
X493962Y54996D01*
G01X494343Y54954D02*
X494331Y54956D01*
G01X494820Y54881D02*
X494808Y54883D01*
G01X494341Y54996D02*
X494328Y54999D01*
G01X495067Y54883D02*
X495079Y54881D01*
G01X494843Y54999D02*
X494855Y54996D01*
G01X492874Y54999D02*
X492884Y54996D01*
G01X493917Y54898D02*
X493927Y54896D01*
G01X493735Y54981D02*
X493726Y54984D01*
G01X493694Y54898D02*
X493704Y54896D01*
G01X493959Y54981D02*
X493950Y54984D01*
G01X494811Y54898D02*
X494820Y54896D01*
G01X494852Y54981D02*
X494843Y54984D01*
G01X493009Y54898D02*
X493017Y54896D01*
G01Y54946D02*
X493009Y54949D01*
G01X493169Y54896D02*
X493177Y54893D01*
G01X493526Y54898D02*
X493533Y54896D01*
G01Y54946D02*
X493526Y54949D01*
G01X493822Y54893D02*
X493814Y54896D01*
G01X493812Y54938D02*
X493819Y54936D01*
G01X493844Y54984D02*
X493836Y54986D01*
G01X494309Y54896D02*
X494316Y54893D01*
G01X494341Y54941D02*
X494333Y54943D01*
G01X494331Y54986D02*
X494338Y54984D01*
G01X495069Y54896D02*
X495076Y54893D01*
G01X492840Y54938D02*
X492828Y54943D01*
G01X492844Y54883D02*
X492835Y54888D01*
G01X492889Y54981D02*
X492884Y54984D01*
G01Y54996D02*
X492894Y54992D01*
G01X493002Y54938D02*
X492997Y54941D01*
G01X493280Y54883D02*
X493270Y54888D01*
G01X493519Y54938D02*
X493514Y54941D01*
G01X493691Y54883D02*
X493681Y54888D01*
G01X493915Y54883D02*
X493905Y54888D01*
G01X493738Y54996D02*
X493748Y54992D01*
G01X494139Y54883D02*
X494129Y54888D01*
G01X493962Y54996D02*
X493972Y54992D01*
G01X494808Y54883D02*
X494798Y54888D01*
G01X494855Y54996D02*
X494865Y54992D01*
G01X493799Y54891D02*
X493812Y54883D01*
G01X493797Y54934D02*
X493809Y54926D01*
G01X493858Y54989D02*
X493846Y54996D01*
G01X494294Y54891D02*
X494306Y54883D01*
G01X494356Y54946D02*
X494343Y54954D01*
G01X494353Y54989D02*
X494341Y54996D01*
G01X492840Y54901D02*
X492847Y54896D01*
G01X492837Y54951D02*
X492844Y54946D01*
G01X492936Y54906D02*
X492928Y54911D01*
G01X492894Y54992D02*
X492901Y54986D01*
G01X492960Y54974D02*
X492968Y54969D01*
G01X493278Y54901D02*
X493285Y54896D01*
G01X493686Y54903D02*
X493694Y54898D01*
G01X493814Y54896D02*
X493807Y54901D01*
G01X493743Y54976D02*
X493735Y54981D01*
G01X493804Y54943D02*
X493812Y54938D01*
G01X493910Y54903D02*
X493917Y54898D01*
G01X493851Y54979D02*
X493844Y54984D01*
G01X494016Y54906D02*
X494009Y54911D01*
G01X493967Y54976D02*
X493959Y54981D01*
G01X494137Y54901D02*
X494144Y54896D01*
G01X494041Y54974D02*
X494048Y54969D01*
G01X494301Y54901D02*
X494309Y54896D01*
G01X494348Y54936D02*
X494341Y54941D01*
G01X494338Y54984D02*
X494346Y54979D01*
G01X494803Y54903D02*
X494811Y54898D01*
G01X494860Y54976D02*
X494852Y54981D01*
G01X493007Y54883D02*
X492997Y54891D01*
G01X493167Y54883D02*
X493157Y54891D01*
G01X493524Y54883D02*
X493514Y54891D01*
G01X495057D02*
X495067Y54883D01*
G01X493005Y54903D02*
X493009Y54898D01*
G01Y54949D02*
X493005Y54954D01*
G01X493521Y54903D02*
X493526Y54898D01*
G01Y54949D02*
X493521Y54954D01*
G01X492835Y54888D02*
X492825Y54898D01*
G01X492894Y54976D02*
X492889Y54981D01*
G01X493165Y54901D02*
X493169Y54896D01*
G01X493270Y54888D02*
X493261Y54898D01*
G01X493681Y54888D02*
X493671Y54898D01*
G01X493789Y54941D02*
X493797Y54934D01*
G01X493748Y54992D02*
X493757Y54981D01*
G01X493799Y54949D02*
X493804Y54943D01*
G01X493905Y54888D02*
X493895Y54898D01*
G01X493972Y54992D02*
X493981Y54981D01*
G01X494129Y54888D02*
X494119Y54898D01*
G01X494798Y54888D02*
X494789Y54898D01*
G01X494865Y54992D02*
X494875Y54981D01*
G01X495064Y54901D02*
X495069Y54896D01*
G01X495866Y53542D02*
X499016D01*
G01X497372Y54782D02*
X497274D01*
G01X497717D02*
X497643D01*
G01X495472Y54881D02*
X495384D01*
G01X495281D02*
X495266D01*
G01X495364D02*
X495350D01*
G01X495246D02*
X495157D01*
G01X495025D02*
X495010D01*
G01X494917D02*
X494902D01*
G01X494843D02*
X494820D01*
G01X494683D02*
X494668D01*
G01X494767D02*
X494752D01*
G01X494648D02*
X494555D01*
G01X494402D02*
X494387D01*
G01X494163D02*
X494154D01*
G01X494082D02*
X494068D01*
G01X493950D02*
X493927D01*
G01X493726D02*
X493704D01*
G01X493595D02*
X493536D01*
G01X493389D02*
X493366D01*
G01X493484D02*
X493462D01*
G01X493305D02*
X493295D01*
G01X493238D02*
X493179D01*
G01X493113D02*
X493098D01*
G01X493078D02*
X493019D01*
G01X492867D02*
X492862D01*
G01X492800D02*
X492707D01*
G01X494319D02*
X494331D01*
G01X493824D02*
X493834D01*
G01X495079D02*
X495138D01*
G01X493836Y54893D02*
X493822D01*
G01X494609D02*
X494648D01*
G01X494555D02*
X494594D01*
G01X494316D02*
X494333D01*
G01X494156D02*
X494166D01*
G01X493297D02*
X493307D01*
G01X493177D02*
X493224D01*
G01X492859D02*
X492869D01*
G01X492761D02*
X492800D01*
G01X492707D02*
X492746D01*
G01X495076D02*
X495123D01*
G01X493927Y54896D02*
X493950D01*
G01X493704D02*
X493726D01*
G01X493533D02*
X493580D01*
G01X493017D02*
X493064D01*
G01X495384D02*
X495458D01*
G01X495157D02*
X495231D01*
G01X494820D02*
X494843D01*
G01X493802Y54908D02*
X493789D01*
G01X494191D02*
X494203D01*
G01X493332D02*
X493344D01*
G01X492894D02*
X492906D01*
G01X494786Y54911D02*
X494801D01*
G01X493893D02*
X493907D01*
G01X493669D02*
X493684D01*
G01X493822Y54923D02*
X493834D01*
G01X495458Y54929D02*
X495394D01*
G01X495231D02*
X495167D01*
G01X494752D02*
X494683D01*
G01X495123Y54931D02*
X495076D01*
G01X493580D02*
X493533D01*
G01X493224D02*
X493177D01*
G01X493064D02*
X493017D01*
G01X494823Y54934D02*
X494786D01*
G01X493930D02*
X493893D01*
G01X492869D02*
X492859D01*
G01X493819Y54936D02*
X493836D01*
G01X494333Y54943D02*
X494316D01*
G01X494259D02*
X494225D01*
G01X493649D02*
X493615D01*
G01X494683D02*
X494752D01*
G01X492859D02*
X492869D01*
G01X495394D02*
X495458D01*
G01X495167D02*
X495231D01*
G01X495123Y54946D02*
X495081D01*
G01X493580D02*
X493533D01*
G01X493064D02*
X493017D01*
G01X493179D02*
X493224D01*
G01X494801Y54949D02*
X494823D01*
G01X493907D02*
X493930D01*
G01X494331Y54956D02*
X494319D01*
G01X494225D02*
X494259D01*
G01X493615D02*
X493649D01*
G01X493684Y54969D02*
X493669D01*
G01X492909Y54971D02*
X492896D01*
G01X494350D02*
X494363D01*
G01X495458Y54984D02*
X495384D01*
G01X495231D02*
X495157D01*
G01X495010D02*
X494936D01*
G01X494843D02*
X494820D01*
G01X493950D02*
X493927D01*
G01X493726D02*
X493704D01*
G01X493533D02*
X493580D01*
G01X493017D02*
X493064D01*
G01X494186Y54986D02*
X494117D01*
G01X493836D02*
X493819D01*
G01X493327D02*
X493258D01*
G01X492872D02*
X492857D01*
G01X494316D02*
X494331D01*
G01X495062Y54999D02*
X495044D01*
G01X495138D02*
X495123D01*
G01X494328D02*
X494319D01*
G01X493834D02*
X493822D01*
G01X494668D02*
X494683D01*
G01X494752D02*
X494767D01*
G01X494594D02*
X494609D01*
G01X494387D02*
X494402D01*
G01X494117D02*
X494206D01*
G01X494068D02*
X494082D01*
G01X493927D02*
X493950D01*
G01X493704D02*
X493726D01*
G01X493536D02*
X493595D01*
G01X493366D02*
X493381D01*
G01X493470D02*
X493484D01*
G01X493415D02*
X493435D01*
G01X493258D02*
X493346D01*
G01X493224D02*
X493238D01*
G01X493098D02*
X493113D01*
G01X493019D02*
X493078D01*
G01X492854D02*
X492874D01*
G01X492746D02*
X492761D01*
G01X495384D02*
X495472D01*
G01X495305D02*
X495325D01*
G01X495157D02*
X495246D01*
G01X494936D02*
X495025D01*
G01X494902D02*
X494917D01*
G01X494820D02*
X494843D01*
G01X497274Y55373D02*
X497372D01*
G01X497643D02*
X497717D01*
G01X499016Y56692D02*
X495866D01*
G01X492862Y54881D02*
X492844Y54883D01*
G01X492997Y54891D02*
X492990Y54901D01*
G01X492997Y54941D02*
X492990Y54951D01*
G01X493157Y54891D02*
X493150Y54901D01*
G01X493514Y54891D02*
X493507Y54901D01*
G01X493514Y54941D02*
X493507Y54951D01*
G01X493792Y54901D02*
X493799Y54891D01*
G01X493866Y54979D02*
X493858Y54989D01*
G01X494287Y54901D02*
X494294Y54891D01*
G01X494363Y54936D02*
X494356Y54946D01*
G01X494360Y54979D02*
X494353Y54989D01*
G01X495049Y54901D02*
X495057Y54891D01*
G01X492835Y54908D02*
X492840Y54901D01*
G01X492828Y54943D02*
X492822Y54951D01*
G01X492901Y54986D02*
X492906Y54979D01*
G01X493273Y54908D02*
X493278Y54901D01*
G01X493748Y54969D02*
X493743Y54976D01*
G01X493807Y54901D02*
X493802Y54908D01*
G01X493856Y54971D02*
X493851Y54979D01*
G01X493972Y54969D02*
X493967Y54976D01*
G01X494131Y54908D02*
X494137Y54901D01*
G01X494296Y54908D02*
X494301Y54901D01*
G01X494353Y54929D02*
X494348Y54936D01*
G01X494346Y54979D02*
X494350Y54971D01*
G01X494865Y54969D02*
X494860Y54976D01*
G01X497372Y55373D02*
X497557Y55084D01*
G01X497495Y55021D02*
X497274Y55373D01*
G01X492832Y54961D02*
X492837Y54951D01*
G01X492896Y54971D02*
X492894Y54976D01*
G01X493757Y54981D02*
X493763Y54971D01*
G01X493981Y54981D02*
X493986Y54971D01*
G01X494875Y54981D02*
X494880Y54971D01*
G01X494843Y54896D02*
X494852Y54898D01*
G01X494820Y54984D02*
X494811Y54981D01*
G01X493950Y54896D02*
X493959Y54898D01*
G01X493726Y54896D02*
X493735Y54898D01*
G01X493927Y54984D02*
X493917Y54981D01*
G01X493704Y54984D02*
X493694Y54981D01*
G01X492844Y54996D02*
X492854Y54999D01*
G01X494855Y54883D02*
X494843Y54881D01*
G01X494331D02*
X494343Y54883D01*
G01X494808Y54996D02*
X494820Y54999D01*
G01X494166Y54893D02*
X494178Y54896D01*
G01X494319Y54956D02*
X494306Y54954D01*
G01X493962Y54883D02*
X493950Y54881D01*
G01X493834D02*
X493846Y54883D01*
G01X494319Y54999D02*
X494306Y54996D01*
G01X493738Y54883D02*
X493726Y54881D01*
G01X493834Y54923D02*
X493846Y54926D01*
G01X493915Y54996D02*
X493927Y54999D01*
G01X493307Y54893D02*
X493320Y54896D01*
G01X493822Y54999D02*
X493809Y54996D01*
G01X493691D02*
X493704Y54999D01*
G01X493524Y54996D02*
X493536Y54999D01*
G01X493167Y54943D02*
X493179Y54946D01*
G01X492869Y54893D02*
X492881Y54896D01*
G01X493007Y54996D02*
X493019Y54999D01*
G01X492857Y54986D02*
X492844Y54984D01*
G01X494181Y54883D02*
X494163Y54881D01*
G01X493322Y54883D02*
X493305Y54881D01*
G01X492884Y54883D02*
X492867Y54881D01*
G01X493785Y54954D02*
X493789Y54941D01*
G01X493871Y54966D02*
X493866Y54979D01*
G01X494281Y54914D02*
X494287Y54901D01*
G01X494368Y54923D02*
X494363Y54936D01*
G01X495044Y54999D02*
X495067Y54941D01*
G01X495081Y54946D02*
X495062Y54999D01*
G01X493435D02*
X493470Y54906D01*
G01X493462Y54881D02*
X493425Y54986D01*
G01X495350Y54881D02*
X495315Y54984D01*
G01X495325Y54999D02*
X495364Y54881D01*
G01X492906Y54979D02*
X492909Y54971D01*
G01X492990Y54901D02*
X492987Y54908D01*
G01X493002Y54911D02*
X493005Y54903D01*
G01X492990Y54951D02*
X492987Y54959D01*
G01X493005Y54954D02*
X493002Y54961D01*
G01X493150Y54901D02*
X493147Y54908D01*
G01X493162D02*
X493165Y54901D01*
G01X493507D02*
X493504Y54908D01*
G01X493519Y54911D02*
X493521Y54903D01*
G01X493507Y54951D02*
X493504Y54959D01*
G01X493521Y54954D02*
X493519Y54961D01*
G01X493684Y54911D02*
X493686Y54903D01*
G01X493789Y54908D02*
X493792Y54901D01*
G01X493797Y54956D02*
X493799Y54949D01*
G01X493858Y54964D02*
X493856Y54971D01*
G01X493907Y54911D02*
X493910Y54903D01*
G01X494294Y54916D02*
X494296Y54908D01*
G01X494356Y54921D02*
X494353Y54929D01*
G01X494363Y54971D02*
X494360Y54979D01*
G01X494801Y54911D02*
X494803Y54903D01*
G01X495047Y54908D02*
X495049Y54901D01*
G01X495062Y54908D02*
X495064Y54901D01*
G01X492825Y54898D02*
X492822Y54908D01*
G01Y54951D02*
X492820Y54961D01*
G01X493261Y54898D02*
X493258Y54908D01*
G01X493750Y54959D02*
X493748Y54969D01*
G01X493974Y54959D02*
X493972Y54969D01*
G01X494119Y54898D02*
X494117Y54908D01*
G01X494867Y54959D02*
X494865Y54969D01*
G01X493671Y54898D02*
X493669Y54911D01*
G01X493763Y54971D02*
X493765Y54959D01*
G01X493895Y54898D02*
X493893Y54911D01*
G01X493986Y54971D02*
X493989Y54959D01*
G01X494789Y54898D02*
X494786Y54911D01*
G01X494880Y54971D02*
X494882Y54959D01*
G01X493873Y54949D02*
X493871Y54966D01*
G01X494279Y54931D02*
X494281Y54914D01*
G01X492707Y54881D02*
Y54893D01*
G01X492746D02*
Y54999D01*
G01X492761D02*
Y54893D01*
G01X492800D02*
Y54881D01*
G01X492820Y54961D02*
Y54971D01*
G01X492822Y54908D02*
Y54914D01*
G01X492832Y54971D02*
Y54961D01*
G01X492835Y54914D02*
Y54908D01*
G01X492869Y54943D02*
Y54934D01*
G01X492987Y54908D02*
Y54918D01*
G01Y54959D02*
Y54971D01*
G01X493002Y54916D02*
Y54911D01*
G01Y54961D02*
Y54969D01*
G01X493064Y54984D02*
Y54946D01*
G01Y54896D02*
Y54931D01*
G01X493078Y54999D02*
Y54881D01*
G01X493098D02*
Y54999D01*
G01X493110Y56692D02*
Y53542D01*
G01X493113Y54999D02*
Y54901D01*
G01X493128Y54918D02*
Y54898D01*
G01X493147Y54908D02*
Y54918D01*
G01X493162Y54916D02*
Y54908D01*
G01X493224Y54946D02*
Y54999D01*
G01Y54893D02*
Y54931D01*
G01X493238Y54999D02*
Y54881D01*
G01X493258Y54986D02*
Y54999D01*
G01Y54908D02*
Y54914D01*
G01X493273D02*
Y54908D01*
G01X493346Y54999D02*
Y54986D01*
G01X493366Y54881D02*
Y54999D01*
G01X493381D02*
Y54906D01*
G01X493470D02*
Y54999D01*
G01X493484D02*
Y54881D01*
G01X493504Y54908D02*
Y54918D01*
G01Y54959D02*
Y54971D01*
G01X493519Y54916D02*
Y54911D01*
G01Y54961D02*
Y54969D01*
G01X493580Y54984D02*
Y54946D01*
G01Y54896D02*
Y54931D01*
G01X493595Y54999D02*
Y54881D01*
G01X493615Y54943D02*
Y54956D01*
G01X493649D02*
Y54943D01*
G01X493750Y54921D02*
Y54959D01*
G01X493765D02*
Y54921D01*
G01X493785Y54966D02*
Y54954D01*
G01X493797Y54964D02*
Y54956D01*
G01X493858D02*
Y54964D01*
G01X493861Y54936D02*
Y54931D01*
G01X493873D02*
Y54949D01*
G01X493893Y54934D02*
Y54971D01*
G01X493907Y54969D02*
Y54949D01*
G01X493930D02*
Y54934D01*
G01X493974Y54921D02*
Y54959D01*
G01X493989D02*
Y54921D01*
G01X494068Y54881D02*
Y54999D01*
G01X494082D02*
Y54901D01*
G01X494097Y54918D02*
Y54898D01*
G01X494117Y54986D02*
Y54999D01*
G01Y54908D02*
Y54914D01*
G01X494131D02*
Y54908D01*
G01X494206Y54999D02*
Y54986D01*
G01X494225Y54943D02*
Y54956D01*
G01X494259D02*
Y54943D01*
G01X494279Y54949D02*
Y54931D01*
G01X494291Y54943D02*
Y54949D01*
G01X494294Y54921D02*
Y54916D01*
G01X494356D02*
Y54921D01*
G01X494368Y54914D02*
Y54923D01*
G01X494387Y54881D02*
Y54999D01*
G01X494402D02*
Y54901D01*
G01X494417Y54918D02*
Y54898D01*
G01X494555Y54881D02*
Y54893D01*
G01X494594D02*
Y54999D01*
G01X494609D02*
Y54893D01*
G01X494648D02*
Y54881D01*
G01X494668D02*
Y54999D01*
G01X494683D02*
Y54943D01*
G01Y54929D02*
Y54881D01*
G01X494752Y54943D02*
Y54999D01*
G01Y54881D02*
Y54929D01*
G01X494767Y54999D02*
Y54881D01*
G01X494786Y54934D02*
Y54971D01*
G01X494801Y54969D02*
Y54949D01*
G01X494823D02*
Y54934D01*
G01X494867Y54921D02*
Y54959D01*
G01X494882D02*
Y54921D01*
G01X494902Y54881D02*
Y54999D01*
G01X494917D02*
Y54881D01*
G01X494936Y54984D02*
Y54999D01*
G01X495010Y54881D02*
Y54984D01*
G01X495025Y54999D02*
Y54881D01*
G01X495047Y54918D02*
Y54908D01*
G01X495062Y54916D02*
Y54908D01*
G01X495123Y54999D02*
Y54946D01*
G01Y54893D02*
Y54931D01*
G01X495138Y54881D02*
Y54999D01*
G01X495157Y54881D02*
Y54896D01*
G01Y54984D02*
Y54999D01*
G01X495167Y54929D02*
Y54943D01*
G01X495231D02*
Y54984D01*
G01Y54896D02*
Y54929D01*
G01X495246Y54999D02*
Y54881D01*
G01X495384D02*
Y54896D01*
G01Y54984D02*
Y54999D01*
G01X495394Y54929D02*
Y54943D01*
G01X495458D02*
Y54984D01*
G01Y54896D02*
Y54929D01*
G01X495472Y54999D02*
Y54881D01*
G01X495866Y56692D02*
Y53542D01*
G01X496687D02*
Y56692D01*
G01X496850D02*
Y53542D01*
G01X497638D02*
Y56692D01*
G01X497643Y55172D02*
Y55373D01*
G01Y54782D02*
Y55071D01*
G01X497717Y55373D02*
Y54782D01*
G01X499016Y53542D02*
Y56692D01*
G01X493871Y54914D02*
X493873Y54931D01*
G01X494281Y54966D02*
X494279Y54949D01*
G01X493861Y54931D02*
X493858Y54916D01*
G01X494291Y54949D02*
X494294Y54964D01*
G01X493669Y54969D02*
X493671Y54981D01*
G01X493765Y54921D02*
X493763Y54908D01*
G01X493989Y54921D02*
X493986Y54908D01*
G01X494882Y54921D02*
X494880Y54908D01*
G01X492822Y54914D02*
X492825Y54923D01*
G01X492906Y54908D02*
X492904Y54898D01*
G01X493258Y54914D02*
X493261Y54923D01*
G01X493344Y54908D02*
X493342Y54898D01*
G01X493748Y54911D02*
X493750Y54921D01*
G01X493893Y54971D02*
X493895Y54981D01*
G01X493972Y54911D02*
X493974Y54921D01*
G01X494117Y54914D02*
X494119Y54923D01*
G01X494203Y54908D02*
X494200Y54898D01*
G01X494786Y54971D02*
X494789Y54981D01*
G01X494865Y54911D02*
X494867Y54921D01*
G01X492820Y54971D02*
X492822Y54979D01*
G01X492987Y54971D02*
X492990Y54979D01*
G01X493002Y54969D02*
X493005Y54976D01*
G01X492987Y54918D02*
X492990Y54926D01*
G01X493005Y54923D02*
X493002Y54916D01*
G01X493147Y54918D02*
X493150Y54926D01*
G01X493165Y54923D02*
X493162Y54916D01*
G01X493504Y54971D02*
X493507Y54979D01*
G01X493519Y54969D02*
X493521Y54976D01*
G01X493504Y54918D02*
X493507Y54926D01*
G01X493521Y54923D02*
X493519Y54916D01*
G01X493686Y54976D02*
X493684Y54969D01*
G01X493799Y54971D02*
X493797Y54964D01*
G01X493856Y54949D02*
X493858Y54956D01*
G01Y54916D02*
X493856Y54908D01*
G01X493910Y54976D02*
X493907Y54969D01*
G01X494294Y54964D02*
X494296Y54971D01*
G01Y54929D02*
X494294Y54921D01*
G01X494353Y54908D02*
X494356Y54916D01*
G01X494803Y54976D02*
X494801Y54969D01*
G01X495049Y54926D02*
X495047Y54918D01*
G01X495064Y54923D02*
X495062Y54916D01*
G01X495266Y54881D02*
X495305Y54999D01*
G01X495315Y54984D02*
X495281Y54881D01*
G01X493425Y54986D02*
X493389Y54881D01*
G01X493381Y54906D02*
X493415Y54999D01*
G01X493789Y54979D02*
X493785Y54966D01*
G01X493866Y54901D02*
X493871Y54914D01*
G01X494287Y54979D02*
X494281Y54966D01*
G01X494363Y54901D02*
X494368Y54914D01*
G01X492835Y54976D02*
X492832Y54971D01*
G01X492840Y54923D02*
X492835Y54914D01*
G01X493278Y54923D02*
X493273Y54914D01*
G01X493763Y54908D02*
X493757Y54898D01*
G01X493986Y54908D02*
X493981Y54898D01*
G01X494137Y54923D02*
X494131Y54914D01*
G01X494880Y54908D02*
X494875Y54898D01*
G01X492928Y54911D02*
X492960Y54974D01*
G01X492968Y54969D02*
X492936Y54906D01*
G01X494009Y54911D02*
X494041Y54974D01*
G01X494048Y54969D02*
X494016Y54906D01*
G01X492822Y54979D02*
X492828Y54986D01*
G01X492825Y54923D02*
X492830Y54931D01*
G01X492889Y54901D02*
X492894Y54908D01*
G01X493261Y54923D02*
X493265Y54931D01*
G01X493327Y54901D02*
X493332Y54908D01*
G01X493743Y54903D02*
X493748Y54911D01*
G01X493804Y54979D02*
X493799Y54971D01*
G01X493856Y54908D02*
X493851Y54901D01*
G01X493967Y54903D02*
X493972Y54911D01*
G01X494119Y54923D02*
X494124Y54931D01*
G01X494186Y54901D02*
X494191Y54908D01*
G01X494296Y54971D02*
X494301Y54979D01*
G01Y54936D02*
X494296Y54929D01*
G01X494348Y54901D02*
X494353Y54908D01*
G01X494860Y54903D02*
X494865Y54911D01*
G01X492990Y54979D02*
X492997Y54989D01*
G01X492990Y54926D02*
X492997Y54936D01*
G01X493150Y54926D02*
X493157Y54936D01*
G01X493507Y54979D02*
X493514Y54989D01*
G01X493507Y54926D02*
X493514Y54936D01*
G01X493797Y54989D02*
X493789Y54979D01*
G01X493858Y54891D02*
X493866Y54901D01*
G01X494294Y54989D02*
X494287Y54979D01*
G01X494356Y54891D02*
X494363Y54901D01*
G01X495057Y54936D02*
X495049Y54926D01*
G01X493113Y54901D02*
X493128Y54918D01*
G01Y54898D02*
X493113Y54881D01*
G01X494082Y54901D02*
X494097Y54918D01*
G01Y54898D02*
X494082Y54881D01*
G01X494402Y54901D02*
X494417Y54918D01*
G01Y54898D02*
X494402Y54881D01*
G01X497274Y54782D02*
X497495Y55021D01*
G01X497643Y55071D02*
X497372Y54782D01*
G01X492840Y54981D02*
X492835Y54976D01*
G01X492844Y54929D02*
X492840Y54923D01*
G01X492904Y54898D02*
X492894Y54888D01*
G01X493005Y54976D02*
X493009Y54981D01*
G01Y54929D02*
X493005Y54923D01*
G01X493169Y54929D02*
X493165Y54923D01*
G01X493342Y54898D02*
X493332Y54888D01*
G01X493521Y54976D02*
X493526Y54981D01*
G01Y54929D02*
X493521Y54923D01*
G01X493671Y54981D02*
X493681Y54992D01*
G01X493757Y54898D02*
X493748Y54888D01*
G01X493851Y54943D02*
X493856Y54949D01*
G01X493895Y54981D02*
X493905Y54992D01*
G01X493981Y54898D02*
X493972Y54888D01*
G01X494200Y54898D02*
X494191Y54888D01*
G01X494789Y54981D02*
X494798Y54992D01*
G01X494875Y54898D02*
X494865Y54888D01*
G01X495069Y54929D02*
X495064Y54923D01*
G01X497557Y55084D02*
X497643Y55172D01*
G01X493346Y54986D02*
X493278Y54923D01*
G01X494206Y54986D02*
X494137Y54923D01*
G01X493265Y54931D02*
X493327Y54986D01*
G01X494124Y54931D02*
X494186Y54986D01*
G01X492830Y54931D02*
X492840Y54938D01*
G01X492997Y54989D02*
X493007Y54996D01*
G01X493157Y54936D02*
X493167Y54943D01*
G01X493514Y54989D02*
X493524Y54996D01*
G01X492828Y54986D02*
X492835Y54992D01*
G01X492881Y54896D02*
X492889Y54901D01*
G01X493320Y54896D02*
X493327Y54901D01*
G01X493694Y54981D02*
X493686Y54976D01*
G01X493812Y54984D02*
X493804Y54979D01*
G01X493735Y54898D02*
X493743Y54903D01*
G01X493844Y54938D02*
X493851Y54943D01*
G01X493917Y54981D02*
X493910Y54976D01*
G01X493846Y54926D02*
X493861Y54936D01*
G01X493851Y54901D02*
X493844Y54896D01*
G01X493959Y54898D02*
X493967Y54903D01*
G01X494178Y54896D02*
X494186Y54901D01*
G01X494301Y54979D02*
X494309Y54984D01*
G01X494306Y54954D02*
X494291Y54943D01*
G01X494309Y54941D02*
X494301Y54936D01*
G01X494341Y54896D02*
X494348Y54901D01*
G01X494811Y54981D02*
X494803Y54976D01*
G01X494852Y54898D02*
X494860Y54903D01*
G01X493809Y54996D02*
X493797Y54989D01*
G01X493846Y54883D02*
X493858Y54891D01*
G01X494306Y54996D02*
X494294Y54989D01*
G01X494343Y54883D02*
X494356Y54891D01*
G01X492835Y54992D02*
X492844Y54996D01*
G01Y54984D02*
X492840Y54981D01*
G01X492894Y54888D02*
X492884Y54883D01*
G01X492997Y54936D02*
X493002Y54938D01*
G01X493332Y54888D02*
X493322Y54883D01*
G01X493514Y54936D02*
X493519Y54938D01*
G01X493681Y54992D02*
X493691Y54996D01*
G01X493905Y54992D02*
X493915Y54996D01*
G01X493748Y54888D02*
X493738Y54883D01*
G01X493972Y54888D02*
X493962Y54883D01*
G01X494191Y54888D02*
X494181Y54883D01*
G01X494798Y54992D02*
X494808Y54996D01*
G01X494865Y54888D02*
X494855Y54883D01*
G01X495067Y54941D02*
X495057Y54936D01*
G01X492859Y54934D02*
X492844Y54929D01*
G01X493009Y54981D02*
X493017Y54984D01*
G01Y54931D02*
X493009Y54929D01*
G01X493177Y54931D02*
X493169Y54929D01*
G01X493526Y54981D02*
X493533Y54984D01*
G01Y54931D02*
X493526Y54929D01*
G01X493819Y54986D02*
X493812Y54984D01*
G01X493836Y54936D02*
X493844Y54938D01*
G01Y54896D02*
X493836Y54893D01*
G01X494309Y54984D02*
X494316Y54986D01*
G01Y54943D02*
X494309Y54941D01*
G01X494333Y54893D02*
X494341Y54896D01*
G01X495076Y54931D02*
X495069Y54929D01*
G01X493110Y53542D02*
X489961D01*
G01X491339D02*
X497638D01*
G01X491496Y54782D02*
X491398D01*
G01X491336Y55172D02*
X491558D01*
G01X491324Y55222D02*
X491570D01*
G01X491619Y55373D02*
X491693D01*
G01X491201D02*
X491275D01*
G01X497638Y56692D02*
X491339D01*
G01X489961D02*
X493110D01*
G01X491398Y54782D02*
X491201Y55373D01*
G01X491447Y54832D02*
X491336Y55172D01*
G01X491275Y55373D02*
X491324Y55222D01*
G01X489961Y53542D02*
Y56692D01*
G01X491339D02*
Y53542D01*
G01X492126Y56692D02*
Y53542D01*
G01X492290Y56692D02*
Y53542D01*
G01X491570Y55222D02*
X491619Y55373D01*
G01X491558Y55172D02*
X491447Y54832D01*
G01X491693Y55373D02*
X491496Y54782D01*
G01X497274Y78995D02*
X497372D01*
G01X497643D02*
X497717D01*
G01X499016Y80314D02*
X495866D01*
G01X492840Y78560D02*
X492828Y78566D01*
G01X492844Y78505D02*
X492835Y78510D01*
G01X492889Y78603D02*
X492884Y78606D01*
G01Y78618D02*
X492894Y78614D01*
G01X493002Y78560D02*
X492997Y78563D01*
G01X493280Y78505D02*
X493270Y78510D01*
G01X493519Y78560D02*
X493514Y78563D01*
G01X493691Y78505D02*
X493681Y78510D01*
G01X493915Y78505D02*
X493905Y78510D01*
G01X493738Y78618D02*
X493748Y78614D01*
G01X494139Y78505D02*
X494129Y78510D01*
G01X493962Y78618D02*
X493972Y78614D01*
G01X494808Y78505D02*
X494798Y78510D01*
G01X494855Y78618D02*
X494865Y78614D01*
G01X493799Y78513D02*
X493812Y78505D01*
G01X493797Y78556D02*
X493809Y78548D01*
G01X493858Y78611D02*
X493846Y78618D01*
G01X494294Y78513D02*
X494306Y78505D01*
G01X494356Y78568D02*
X494343Y78576D01*
G01X494353Y78611D02*
X494341Y78618D01*
G01X492840Y78523D02*
X492847Y78518D01*
G01X492837Y78573D02*
X492844Y78568D01*
G01X492936Y78528D02*
X492928Y78533D01*
G01X492894Y78614D02*
X492901Y78608D01*
G01X492960Y78596D02*
X492968Y78591D01*
G01X493278Y78523D02*
X493285Y78518D01*
G01X493686Y78525D02*
X493694Y78520D01*
G01X493814Y78518D02*
X493807Y78523D01*
G01X493743Y78598D02*
X493735Y78603D01*
G01X493804Y78566D02*
X493812Y78560D01*
G01X493910Y78525D02*
X493917Y78520D01*
G01X493851Y78601D02*
X493844Y78606D01*
G01X494016Y78528D02*
X494009Y78533D01*
G01X493967Y78598D02*
X493959Y78603D01*
G01X494137Y78523D02*
X494144Y78518D01*
G01X494041Y78596D02*
X494048Y78591D01*
G01X494301Y78523D02*
X494309Y78518D01*
G01X494348Y78558D02*
X494341Y78563D01*
G01X494338Y78606D02*
X494346Y78601D01*
G01X494803Y78525D02*
X494811Y78520D01*
G01X494860Y78598D02*
X494852Y78603D01*
G01X493007Y78505D02*
X492997Y78513D01*
G01X493167Y78505D02*
X493157Y78513D01*
G01X493524Y78505D02*
X493514Y78513D01*
G01X495057D02*
X495067Y78505D01*
G01X495866Y77164D02*
X499016D01*
G01X497372Y78405D02*
X497274D01*
G01X497717D02*
X497643D01*
G01X495472Y78503D02*
X495384D01*
G01X495281D02*
X495266D01*
G01X495364D02*
X495350D01*
G01X495246D02*
X495157D01*
G01X495025D02*
X495010D01*
G01X494917D02*
X494902D01*
G01X494843D02*
X494820D01*
G01X494683D02*
X494668D01*
G01X494767D02*
X494752D01*
G01X494648D02*
X494555D01*
G01X494402D02*
X494387D01*
G01X494163D02*
X494154D01*
G01X494082D02*
X494068D01*
G01X493950D02*
X493927D01*
G01X493726D02*
X493704D01*
G01X493595D02*
X493536D01*
G01X493389D02*
X493366D01*
G01X493484D02*
X493462D01*
G01X493305D02*
X493295D01*
G01X493238D02*
X493179D01*
G01X493113D02*
X493098D01*
G01X493078D02*
X493019D01*
G01X492867D02*
X492862D01*
G01X492800D02*
X492707D01*
G01X494319D02*
X494331D01*
G01X493824D02*
X493834D01*
G01X495079D02*
X495138D01*
G01X493836Y78516D02*
X493822D01*
G01X494609D02*
X494648D01*
G01X494555D02*
X494594D01*
G01X494316D02*
X494333D01*
G01X494156D02*
X494166D01*
G01X493297D02*
X493307D01*
G01X493177D02*
X493224D01*
G01X492859D02*
X492869D01*
G01X492761D02*
X492800D01*
G01X492707D02*
X492746D01*
G01X495076D02*
X495123D01*
G01X493927Y78518D02*
X493950D01*
G01X493704D02*
X493726D01*
G01X493533D02*
X493580D01*
G01X493017D02*
X493064D01*
G01X495384D02*
X495458D01*
G01X495157D02*
X495231D01*
G01X494820D02*
X494843D01*
G01X493802Y78530D02*
X493789D01*
G01X494191D02*
X494203D01*
G01X493332D02*
X493344D01*
G01X492894D02*
X492906D01*
G01X494786Y78533D02*
X494801D01*
G01X493893D02*
X493907D01*
G01X493669D02*
X493684D01*
G01X493822Y78545D02*
X493834D01*
G01X495458Y78551D02*
X495394D01*
G01X495231D02*
X495167D01*
G01X494752D02*
X494683D01*
G01X495123Y78553D02*
X495076D01*
G01X493580D02*
X493533D01*
G01X493224D02*
X493177D01*
G01X493064D02*
X493017D01*
G01X494823Y78556D02*
X494786D01*
G01X493930D02*
X493893D01*
G01X492869D02*
X492859D01*
G01X493819Y78558D02*
X493836D01*
G01X494333Y78566D02*
X494316D01*
G01X494259D02*
X494225D01*
G01X493649D02*
X493615D01*
G01X494683D02*
X494752D01*
G01X492859D02*
X492869D01*
G01X495394D02*
X495458D01*
G01X495167D02*
X495231D01*
G01X495123Y78568D02*
X495081D01*
G01X493580D02*
X493533D01*
G01X493064D02*
X493017D01*
G01X493179D02*
X493224D01*
G01X494801Y78571D02*
X494823D01*
G01X493907D02*
X493930D01*
G01X494331Y78578D02*
X494319D01*
G01X494225D02*
X494259D01*
G01X493615D02*
X493649D01*
G01X493684Y78591D02*
X493669D01*
G01X492909Y78593D02*
X492896D01*
G01X494350D02*
X494363D01*
G01X495458Y78606D02*
X495384D01*
G01X495231D02*
X495157D01*
G01X495010D02*
X494936D01*
G01X494843D02*
X494820D01*
G01X493950D02*
X493927D01*
G01X493726D02*
X493704D01*
G01X493533D02*
X493580D01*
G01X493017D02*
X493064D01*
G01X494186Y78608D02*
X494117D01*
G01X493836D02*
X493819D01*
G01X493327D02*
X493258D01*
G01X492872D02*
X492857D01*
G01X494316D02*
X494331D01*
G01X495062Y78621D02*
X495044D01*
G01X495138D02*
X495123D01*
G01X494328D02*
X494319D01*
G01X493834D02*
X493822D01*
G01X494668D02*
X494683D01*
G01X494752D02*
X494767D01*
G01X494594D02*
X494609D01*
G01X494387D02*
X494402D01*
G01X494117D02*
X494206D01*
G01X494068D02*
X494082D01*
G01X493927D02*
X493950D01*
G01X493704D02*
X493726D01*
G01X493536D02*
X493595D01*
G01X493366D02*
X493381D01*
G01X493470D02*
X493484D01*
G01X493415D02*
X493435D01*
G01X493258D02*
X493346D01*
G01X493224D02*
X493238D01*
G01X493098D02*
X493113D01*
G01X493019D02*
X493078D01*
G01X492854D02*
X492874D01*
G01X492746D02*
X492761D01*
G01X495384D02*
X495472D01*
G01X495305D02*
X495325D01*
G01X495157D02*
X495246D01*
G01X494936D02*
X495025D01*
G01X494902D02*
X494917D01*
G01X494820D02*
X494843D01*
G01X492862Y78503D02*
X492844Y78505D01*
G01Y78568D02*
X492859Y78566D01*
G01X493295Y78503D02*
X493280Y78505D01*
G01X494154Y78503D02*
X494139Y78505D01*
G01X492847Y78518D02*
X492859Y78516D01*
G01X493019Y78503D02*
X493007Y78505D01*
G01X493179Y78503D02*
X493167Y78505D01*
G01X493285Y78518D02*
X493297Y78516D01*
G01X492884Y78606D02*
X492872Y78608D01*
G01X493536Y78503D02*
X493524Y78505D01*
G01X493704Y78503D02*
X493691Y78505D01*
G01X493812D02*
X493824Y78503D01*
G01X493927D02*
X493915Y78505D01*
G01X493809Y78548D02*
X493822Y78545D01*
G01X494144Y78518D02*
X494156Y78516D01*
G01X493726Y78621D02*
X493738Y78618D01*
G01X494306Y78505D02*
X494319Y78503D01*
G01X493846Y78618D02*
X493834Y78621D01*
G01X493950D02*
X493962Y78618D01*
G01X494343Y78576D02*
X494331Y78578D01*
G01X494820Y78503D02*
X494808Y78505D01*
G01X494341Y78618D02*
X494328Y78621D01*
G01X495067Y78505D02*
X495079Y78503D01*
G01X494843Y78621D02*
X494855Y78618D01*
G01X492874Y78621D02*
X492884Y78618D01*
G01X493917Y78520D02*
X493927Y78518D01*
G01X493735Y78603D02*
X493726Y78606D01*
G01X493694Y78520D02*
X493704Y78518D01*
G01X493959Y78603D02*
X493950Y78606D01*
G01X494811Y78520D02*
X494820Y78518D01*
G01X494852Y78603D02*
X494843Y78606D01*
G01X493009Y78520D02*
X493017Y78518D01*
G01Y78568D02*
X493009Y78571D01*
G01X493169Y78518D02*
X493177Y78516D01*
G01X493526Y78520D02*
X493533Y78518D01*
G01Y78568D02*
X493526Y78571D01*
G01X493822Y78516D02*
X493814Y78518D01*
G01X493812Y78560D02*
X493819Y78558D01*
G01X493844Y78606D02*
X493836Y78608D01*
G01X494309Y78518D02*
X494316Y78516D01*
G01X494341Y78563D02*
X494333Y78566D01*
G01X494331Y78608D02*
X494338Y78606D01*
G01X495069Y78518D02*
X495076Y78516D01*
G01X493005Y78525D02*
X493009Y78520D01*
G01Y78571D02*
X493005Y78576D01*
G01X493521Y78525D02*
X493526Y78520D01*
G01Y78571D02*
X493521Y78576D01*
G01X492835Y78510D02*
X492825Y78520D01*
G01X492894Y78598D02*
X492889Y78603D01*
G01X493165Y78523D02*
X493169Y78518D01*
G01X493270Y78510D02*
X493261Y78520D01*
G01X493681Y78510D02*
X493671Y78520D01*
G01X493789Y78563D02*
X493797Y78556D01*
G01X493748Y78614D02*
X493757Y78603D01*
G01X493799Y78571D02*
X493804Y78566D01*
G01X493905Y78510D02*
X493895Y78520D01*
G01X493972Y78614D02*
X493981Y78603D01*
G01X494129Y78510D02*
X494119Y78520D01*
G01X494798Y78510D02*
X494789Y78520D01*
G01X494865Y78614D02*
X494875Y78603D01*
G01X495064Y78523D02*
X495069Y78518D01*
G01X492997Y78513D02*
X492990Y78523D01*
G01X492997Y78563D02*
X492990Y78573D01*
G01X493157Y78513D02*
X493150Y78523D01*
G01X493514Y78513D02*
X493507Y78523D01*
G01X493514Y78563D02*
X493507Y78573D01*
G01X493792Y78523D02*
X493799Y78513D01*
G01X493866Y78601D02*
X493858Y78611D01*
G01X494287Y78523D02*
X494294Y78513D01*
G01X494363Y78558D02*
X494356Y78568D01*
G01X494360Y78601D02*
X494353Y78611D01*
G01X495049Y78523D02*
X495057Y78513D01*
G01X492835Y78530D02*
X492840Y78523D01*
G01X492828Y78566D02*
X492822Y78573D01*
G01X492901Y78608D02*
X492906Y78601D01*
G01X493273Y78530D02*
X493278Y78523D01*
G01X493748Y78591D02*
X493743Y78598D01*
G01X493807Y78523D02*
X493802Y78530D01*
G01X493856Y78593D02*
X493851Y78601D01*
G01X493972Y78591D02*
X493967Y78598D01*
G01X494131Y78530D02*
X494137Y78523D01*
G01X494296Y78530D02*
X494301Y78523D01*
G01X494353Y78551D02*
X494348Y78558D01*
G01X494346Y78601D02*
X494350Y78593D01*
G01X494865Y78591D02*
X494860Y78598D01*
G01X497372Y78995D02*
X497557Y78706D01*
G01X497495Y78643D02*
X497274Y78995D01*
G01X494843Y78518D02*
X494852Y78520D01*
G01X494820Y78606D02*
X494811Y78603D01*
G01X493950Y78518D02*
X493959Y78520D01*
G01X493726Y78518D02*
X493735Y78520D01*
G01X493927Y78606D02*
X493917Y78603D01*
G01X493704Y78606D02*
X493694Y78603D01*
G01X492844Y78618D02*
X492854Y78621D01*
G01X494855Y78505D02*
X494843Y78503D01*
G01X494331D02*
X494343Y78505D01*
G01X494808Y78618D02*
X494820Y78621D01*
G01X494166Y78516D02*
X494178Y78518D01*
G01X494319Y78578D02*
X494306Y78576D01*
G01X493962Y78505D02*
X493950Y78503D01*
G01X493834D02*
X493846Y78505D01*
G01X494319Y78621D02*
X494306Y78618D01*
G01X493738Y78505D02*
X493726Y78503D01*
G01X493834Y78545D02*
X493846Y78548D01*
G01X493915Y78618D02*
X493927Y78621D01*
G01X493307Y78516D02*
X493320Y78518D01*
G01X493822Y78621D02*
X493809Y78618D01*
G01X493691D02*
X493704Y78621D01*
G01X493524Y78618D02*
X493536Y78621D01*
G01X493167Y78566D02*
X493179Y78568D01*
G01X492869Y78516D02*
X492881Y78518D01*
G01X493007Y78618D02*
X493019Y78621D01*
G01X492857Y78608D02*
X492844Y78606D01*
G01X494181Y78505D02*
X494163Y78503D01*
G01X493322Y78505D02*
X493305Y78503D01*
G01X492884Y78505D02*
X492867Y78503D01*
G01X492832Y78583D02*
X492837Y78573D01*
G01X492896Y78593D02*
X492894Y78598D01*
G01X493757Y78603D02*
X493763Y78593D01*
G01X493981Y78603D02*
X493986Y78593D01*
G01X494875Y78603D02*
X494880Y78593D01*
G01X493785Y78576D02*
X493789Y78563D01*
G01X493871Y78588D02*
X493866Y78601D01*
G01X494281Y78536D02*
X494287Y78523D01*
G01X494368Y78545D02*
X494363Y78558D01*
G01X495044Y78621D02*
X495067Y78563D01*
G01X495081Y78568D02*
X495062Y78621D01*
G01X493435D02*
X493470Y78528D01*
G01X493462Y78503D02*
X493425Y78608D01*
G01X495350Y78503D02*
X495315Y78606D01*
G01X495325Y78621D02*
X495364Y78503D01*
G01X492906Y78601D02*
X492909Y78593D01*
G01X492990Y78523D02*
X492987Y78530D01*
G01X493002Y78533D02*
X493005Y78525D01*
G01X492990Y78573D02*
X492987Y78581D01*
G01X493005Y78576D02*
X493002Y78583D01*
G01X493150Y78523D02*
X493147Y78530D01*
G01X493162D02*
X493165Y78523D01*
G01X493507D02*
X493504Y78530D01*
G01X493519Y78533D02*
X493521Y78525D01*
G01X493507Y78573D02*
X493504Y78581D01*
G01X493521Y78576D02*
X493519Y78583D01*
G01X493684Y78533D02*
X493686Y78525D01*
G01X493789Y78530D02*
X493792Y78523D01*
G01X493797Y78578D02*
X493799Y78571D01*
G01X493858Y78586D02*
X493856Y78593D01*
G01X493907Y78533D02*
X493910Y78525D01*
G01X494294Y78538D02*
X494296Y78530D01*
G01X494356Y78543D02*
X494353Y78551D01*
G01X494363Y78593D02*
X494360Y78601D01*
G01X494801Y78533D02*
X494803Y78525D01*
G01X495047Y78530D02*
X495049Y78523D01*
G01X495062Y78530D02*
X495064Y78523D01*
G01X492825Y78520D02*
X492822Y78530D01*
G01Y78573D02*
X492820Y78583D01*
G01X493261Y78520D02*
X493258Y78530D01*
G01X493750Y78581D02*
X493748Y78591D01*
G01X493974Y78581D02*
X493972Y78591D01*
G01X494119Y78520D02*
X494117Y78530D01*
G01X494867Y78581D02*
X494865Y78591D01*
G01X493671Y78520D02*
X493669Y78533D01*
G01X493763Y78593D02*
X493765Y78581D01*
G01X493895Y78520D02*
X493893Y78533D01*
G01X493986Y78593D02*
X493989Y78581D01*
G01X494789Y78520D02*
X494786Y78533D01*
G01X494880Y78593D02*
X494882Y78581D01*
G01X493873Y78571D02*
X493871Y78588D01*
G01X494279Y78553D02*
X494281Y78536D01*
G01X492707Y78503D02*
Y78516D01*
G01X492746D02*
Y78621D01*
G01X492761D02*
Y78516D01*
G01X492800D02*
Y78503D01*
G01X492820Y78583D02*
Y78593D01*
G01X492822Y78530D02*
Y78536D01*
G01X492832Y78593D02*
Y78583D01*
G01X492835Y78536D02*
Y78530D01*
G01X492869Y78566D02*
Y78556D01*
G01X492987Y78530D02*
Y78540D01*
G01Y78581D02*
Y78593D01*
G01X493002Y78538D02*
Y78533D01*
G01Y78583D02*
Y78591D01*
G01X493064Y78606D02*
Y78568D01*
G01Y78518D02*
Y78553D01*
G01X493078Y78621D02*
Y78503D01*
G01X493098D02*
Y78621D01*
G01X493110Y80314D02*
Y77164D01*
G01X493113Y78621D02*
Y78523D01*
G01X493128Y78540D02*
Y78520D01*
G01X493147Y78530D02*
Y78540D01*
G01X493162Y78538D02*
Y78530D01*
G01X493224Y78568D02*
Y78621D01*
G01Y78516D02*
Y78553D01*
G01X493238Y78621D02*
Y78503D01*
G01X493258Y78608D02*
Y78621D01*
G01Y78530D02*
Y78536D01*
G01X493273D02*
Y78530D01*
G01X493346Y78621D02*
Y78608D01*
G01X493366Y78503D02*
Y78621D01*
G01X493381D02*
Y78528D01*
G01X493470D02*
Y78621D01*
G01X493484D02*
Y78503D01*
G01X493504Y78530D02*
Y78540D01*
G01Y78581D02*
Y78593D01*
G01X493519Y78538D02*
Y78533D01*
G01Y78583D02*
Y78591D01*
G01X493580Y78606D02*
Y78568D01*
G01Y78518D02*
Y78553D01*
G01X493595Y78621D02*
Y78503D01*
G01X493615Y78566D02*
Y78578D01*
G01X493649D02*
Y78566D01*
G01X493750Y78543D02*
Y78581D01*
G01X493765D02*
Y78543D01*
G01X493785Y78588D02*
Y78576D01*
G01X493797Y78586D02*
Y78578D01*
G01X493858D02*
Y78586D01*
G01X493861Y78558D02*
Y78553D01*
G01X493873D02*
Y78571D01*
G01X493893Y78556D02*
Y78593D01*
G01X493907Y78591D02*
Y78571D01*
G01X493930D02*
Y78556D01*
G01X493974Y78543D02*
Y78581D01*
G01X493989D02*
Y78543D01*
G01X494068Y78503D02*
Y78621D01*
G01X494082D02*
Y78523D01*
G01X494097Y78540D02*
Y78520D01*
G01X494117Y78608D02*
Y78621D01*
G01Y78530D02*
Y78536D01*
G01X494131D02*
Y78530D01*
G01X494206Y78621D02*
Y78608D01*
G01X494225Y78566D02*
Y78578D01*
G01X494259D02*
Y78566D01*
G01X494279Y78571D02*
Y78553D01*
G01X494291Y78566D02*
Y78571D01*
G01X494294Y78543D02*
Y78538D01*
G01X494356D02*
Y78543D01*
G01X494368Y78536D02*
Y78545D01*
G01X494387Y78503D02*
Y78621D01*
G01X494402D02*
Y78523D01*
G01X494417Y78540D02*
Y78520D01*
G01X494555Y78503D02*
Y78516D01*
G01X494594D02*
Y78621D01*
G01X494609D02*
Y78516D01*
G01X494648D02*
Y78503D01*
G01X494668D02*
Y78621D01*
G01X494683D02*
Y78566D01*
G01Y78551D02*
Y78503D01*
G01X494752Y78566D02*
Y78621D01*
G01Y78503D02*
Y78551D01*
G01X494767Y78621D02*
Y78503D01*
G01X494786Y78556D02*
Y78593D01*
G01X494801Y78591D02*
Y78571D01*
G01X494823D02*
Y78556D01*
G01X494867Y78543D02*
Y78581D01*
G01X494882D02*
Y78543D01*
G01X494902Y78503D02*
Y78621D01*
G01X494917D02*
Y78503D01*
G01X494936Y78606D02*
Y78621D01*
G01X495010Y78503D02*
Y78606D01*
G01X495025Y78621D02*
Y78503D01*
G01X495047Y78540D02*
Y78530D01*
G01X495062Y78538D02*
Y78530D01*
G01X495123Y78621D02*
Y78568D01*
G01Y78516D02*
Y78553D01*
G01X495138Y78503D02*
Y78621D01*
G01X495157Y78503D02*
Y78518D01*
G01Y78606D02*
Y78621D01*
G01X495167Y78551D02*
Y78566D01*
G01X495231D02*
Y78606D01*
G01Y78518D02*
Y78551D01*
G01X495246Y78621D02*
Y78503D01*
G01X495384D02*
Y78518D01*
G01Y78606D02*
Y78621D01*
G01X495394Y78551D02*
Y78566D01*
G01X495458D02*
Y78606D01*
G01Y78518D02*
Y78551D01*
G01X495472Y78621D02*
Y78503D01*
G01X495866Y80314D02*
Y77164D01*
G01X496687D02*
Y80314D01*
G01X496850D02*
Y77164D01*
G01X497638D02*
Y80314D01*
G01X497643Y78794D02*
Y78995D01*
G01Y78405D02*
Y78693D01*
G01X497717Y78995D02*
Y78405D01*
G01X499016Y77164D02*
Y80314D01*
G01X493871Y78536D02*
X493873Y78553D01*
G01X494281Y78588D02*
X494279Y78571D01*
G01X493861Y78553D02*
X493858Y78538D01*
G01X494291Y78571D02*
X494294Y78586D01*
G01X493669Y78591D02*
X493671Y78603D01*
G01X493765Y78543D02*
X493763Y78530D01*
G01X493989Y78543D02*
X493986Y78530D01*
G01X494882Y78543D02*
X494880Y78530D01*
G01X492822Y78536D02*
X492825Y78545D01*
G01X492906Y78530D02*
X492904Y78520D01*
G01X493258Y78536D02*
X493261Y78545D01*
G01X493344Y78530D02*
X493342Y78520D01*
G01X493748Y78533D02*
X493750Y78543D01*
G01X493893Y78593D02*
X493895Y78603D01*
G01X493972Y78533D02*
X493974Y78543D01*
G01X494117Y78536D02*
X494119Y78545D01*
G01X494203Y78530D02*
X494200Y78520D01*
G01X494786Y78593D02*
X494789Y78603D01*
G01X494865Y78533D02*
X494867Y78543D01*
G01X492820Y78593D02*
X492822Y78601D01*
G01X492987Y78593D02*
X492990Y78601D01*
G01X493002Y78591D02*
X493005Y78598D01*
G01X492987Y78540D02*
X492990Y78548D01*
G01X493005Y78545D02*
X493002Y78538D01*
G01X493147Y78540D02*
X493150Y78548D01*
G01X493165Y78545D02*
X493162Y78538D01*
G01X493504Y78593D02*
X493507Y78601D01*
G01X493519Y78591D02*
X493521Y78598D01*
G01X493504Y78540D02*
X493507Y78548D01*
G01X493521Y78545D02*
X493519Y78538D01*
G01X493686Y78598D02*
X493684Y78591D01*
G01X493799Y78593D02*
X493797Y78586D01*
G01X493856Y78571D02*
X493858Y78578D01*
G01Y78538D02*
X493856Y78530D01*
G01X493910Y78598D02*
X493907Y78591D01*
G01X494294Y78586D02*
X494296Y78593D01*
G01Y78551D02*
X494294Y78543D01*
G01X494353Y78530D02*
X494356Y78538D01*
G01X494803Y78598D02*
X494801Y78591D01*
G01X495049Y78548D02*
X495047Y78540D01*
G01X495064Y78545D02*
X495062Y78538D01*
G01X495266Y78503D02*
X495305Y78621D01*
G01X495315Y78606D02*
X495281Y78503D01*
G01X493425Y78608D02*
X493389Y78503D01*
G01X493381Y78528D02*
X493415Y78621D01*
G01X493789Y78601D02*
X493785Y78588D01*
G01X493866Y78523D02*
X493871Y78536D01*
G01X494287Y78601D02*
X494281Y78588D01*
G01X494363Y78523D02*
X494368Y78536D01*
G01X492835Y78598D02*
X492832Y78593D01*
G01X492840Y78545D02*
X492835Y78536D01*
G01X493278Y78545D02*
X493273Y78536D01*
G01X493763Y78530D02*
X493757Y78520D01*
G01X493986Y78530D02*
X493981Y78520D01*
G01X494137Y78545D02*
X494131Y78536D01*
G01X494880Y78530D02*
X494875Y78520D01*
G01X492928Y78533D02*
X492960Y78596D01*
G01X492968Y78591D02*
X492936Y78528D01*
G01X494009Y78533D02*
X494041Y78596D01*
G01X494048Y78591D02*
X494016Y78528D01*
G01X492822Y78601D02*
X492828Y78608D01*
G01X492825Y78545D02*
X492830Y78553D01*
G01X492889Y78523D02*
X492894Y78530D01*
G01X493261Y78545D02*
X493265Y78553D01*
G01X493327Y78523D02*
X493332Y78530D01*
G01X493743Y78525D02*
X493748Y78533D01*
G01X493804Y78601D02*
X493799Y78593D01*
G01X493856Y78530D02*
X493851Y78523D01*
G01X493967Y78525D02*
X493972Y78533D01*
G01X494119Y78545D02*
X494124Y78553D01*
G01X494186Y78523D02*
X494191Y78530D01*
G01X494296Y78593D02*
X494301Y78601D01*
G01Y78558D02*
X494296Y78551D01*
G01X494348Y78523D02*
X494353Y78530D01*
G01X494860Y78525D02*
X494865Y78533D01*
G01X492990Y78601D02*
X492997Y78611D01*
G01X492990Y78548D02*
X492997Y78558D01*
G01X493150Y78548D02*
X493157Y78558D01*
G01X493507Y78601D02*
X493514Y78611D01*
G01X493507Y78548D02*
X493514Y78558D01*
G01X493797Y78611D02*
X493789Y78601D01*
G01X493858Y78513D02*
X493866Y78523D01*
G01X494294Y78611D02*
X494287Y78601D01*
G01X494356Y78513D02*
X494363Y78523D01*
G01X495057Y78558D02*
X495049Y78548D01*
G01X493113Y78523D02*
X493128Y78540D01*
G01Y78520D02*
X493113Y78503D01*
G01X494082Y78523D02*
X494097Y78540D01*
G01Y78520D02*
X494082Y78503D01*
G01X494402Y78523D02*
X494417Y78540D01*
G01Y78520D02*
X494402Y78503D01*
G01X497274Y78405D02*
X497495Y78643D01*
G01X497643Y78693D02*
X497372Y78405D01*
G01X492840Y78603D02*
X492835Y78598D01*
G01X492844Y78551D02*
X492840Y78545D01*
G01X492904Y78520D02*
X492894Y78510D01*
G01X493005Y78598D02*
X493009Y78603D01*
G01Y78551D02*
X493005Y78545D01*
G01X493169Y78551D02*
X493165Y78545D01*
G01X493342Y78520D02*
X493332Y78510D01*
G01X493521Y78598D02*
X493526Y78603D01*
G01Y78551D02*
X493521Y78545D01*
G01X493671Y78603D02*
X493681Y78614D01*
G01X493757Y78520D02*
X493748Y78510D01*
G01X493851Y78566D02*
X493856Y78571D01*
G01X493895Y78603D02*
X493905Y78614D01*
G01X493981Y78520D02*
X493972Y78510D01*
G01X494200Y78520D02*
X494191Y78510D01*
G01X494789Y78603D02*
X494798Y78614D01*
G01X494875Y78520D02*
X494865Y78510D01*
G01X495069Y78551D02*
X495064Y78545D01*
G01X497557Y78706D02*
X497643Y78794D01*
G01X493346Y78608D02*
X493278Y78545D01*
G01X494206Y78608D02*
X494137Y78545D01*
G01X493265Y78553D02*
X493327Y78608D01*
G01X494124Y78553D02*
X494186Y78608D01*
G01X492830Y78553D02*
X492840Y78560D01*
G01X492997Y78611D02*
X493007Y78618D01*
G01X493157Y78558D02*
X493167Y78566D01*
G01X493514Y78611D02*
X493524Y78618D01*
G01X492828Y78608D02*
X492835Y78614D01*
G01X492881Y78518D02*
X492889Y78523D01*
G01X493320Y78518D02*
X493327Y78523D01*
G01X493694Y78603D02*
X493686Y78598D01*
G01X493812Y78606D02*
X493804Y78601D01*
G01X493735Y78520D02*
X493743Y78525D01*
G01X493844Y78560D02*
X493851Y78566D01*
G01X493917Y78603D02*
X493910Y78598D01*
G01X493846Y78548D02*
X493861Y78558D01*
G01X493851Y78523D02*
X493844Y78518D01*
G01X493959Y78520D02*
X493967Y78525D01*
G01X494178Y78518D02*
X494186Y78523D01*
G01X494301Y78601D02*
X494309Y78606D01*
G01X494306Y78576D02*
X494291Y78566D01*
G01X494309Y78563D02*
X494301Y78558D01*
G01X494341Y78518D02*
X494348Y78523D01*
G01X494811Y78603D02*
X494803Y78598D01*
G01X494852Y78520D02*
X494860Y78525D01*
G01X493809Y78618D02*
X493797Y78611D01*
G01X493846Y78505D02*
X493858Y78513D01*
G01X494306Y78618D02*
X494294Y78611D01*
G01X494343Y78505D02*
X494356Y78513D01*
G01X492835Y78614D02*
X492844Y78618D01*
G01Y78606D02*
X492840Y78603D01*
G01X492894Y78510D02*
X492884Y78505D01*
G01X492997Y78558D02*
X493002Y78560D01*
G01X493332Y78510D02*
X493322Y78505D01*
G01X493514Y78558D02*
X493519Y78560D01*
G01X493681Y78614D02*
X493691Y78618D01*
G01X493905Y78614D02*
X493915Y78618D01*
G01X493748Y78510D02*
X493738Y78505D01*
G01X493972Y78510D02*
X493962Y78505D01*
G01X494191Y78510D02*
X494181Y78505D01*
G01X494798Y78614D02*
X494808Y78618D01*
G01X494865Y78510D02*
X494855Y78505D01*
G01X495067Y78563D02*
X495057Y78558D01*
G01X492859Y78556D02*
X492844Y78551D01*
G01X493009Y78603D02*
X493017Y78606D01*
G01Y78553D02*
X493009Y78551D01*
G01X493177Y78553D02*
X493169Y78551D01*
G01X493526Y78603D02*
X493533Y78606D01*
G01Y78553D02*
X493526Y78551D01*
G01X493819Y78608D02*
X493812Y78606D01*
G01X493836Y78558D02*
X493844Y78560D01*
G01Y78518D02*
X493836Y78516D01*
G01X494309Y78606D02*
X494316Y78608D01*
G01Y78566D02*
X494309Y78563D01*
G01X494333Y78516D02*
X494341Y78518D01*
G01X495076Y78553D02*
X495069Y78551D01*
G01X476357Y80392D02*
X476726Y80266D01*
G01X476357Y79764D02*
X476111Y79890D01*
G01X478326Y79764D02*
X478080Y79890D01*
G01X481893Y79764D02*
X481647Y79890D01*
G01X483862Y79764D02*
X483616Y79890D01*
G01X473035Y79638D02*
X472420Y80015D01*
G01X472297Y79387D02*
X472666Y79136D01*
G01X476480Y79638D02*
X476357Y79764D01*
G01X476726Y80266D02*
X477095Y79890D01*
G01X478448Y79638D02*
X478326Y79764D01*
G01X491619Y78995D02*
X491693D01*
G01X491201D02*
X491275D01*
G01X469221Y79010D02*
X470082D01*
G01X471067Y79512D02*
X471805D01*
G01X483616Y79890D02*
X483247D01*
G01X481647D02*
X481401D01*
G01X478080D02*
X477710D01*
G01X476111D02*
X475865D01*
G01X471805Y80141D02*
X471067D01*
G01X497638Y80314D02*
X491339D01*
G01X489961D02*
X493110D01*
G01X475865Y80392D02*
X476357D01*
G01X474635D02*
X475250D01*
G01X477833D02*
X478326D01*
G01X480171D02*
X480786D01*
G01X481401D02*
X481893D01*
G01X483370D02*
X483862D01*
G01X469836Y81649D02*
X473404D01*
G01Y82277D02*
X469221D01*
G01X472420Y80015D02*
X471805Y80141D01*
G01Y79512D02*
X472297Y79387D01*
G01X478326Y80392D02*
X478694Y80266D01*
G01X481893Y80392D02*
X482263Y80266D01*
G01X483862Y80392D02*
X484231Y80266D01*
G01X478694D02*
X478941Y80015D01*
G01X482017Y79638D02*
X481893Y79764D01*
G01X482263Y80266D02*
X482631Y79890D01*
G01X483985Y79638D02*
X483862Y79764D01*
G01X484231Y80266D02*
X484477Y80015D01*
G01X473404Y79136D02*
X473035Y79638D01*
G01X476603Y79387D02*
X476480Y79638D01*
G01X478572Y79387D02*
X478448Y79638D01*
G01X482139Y79387D02*
X482017Y79638D01*
G01X484108Y79387D02*
X483985Y79638D01*
G01X471067Y80141D02*
X470452Y80015D01*
G01X478941D02*
X479187Y79387D01*
G01X484477Y80015D02*
X484723Y79387D01*
G01X469221Y82277D02*
Y79010D01*
G01X469836Y79638D02*
Y81649D01*
G01X470574Y79387D02*
X471067Y79512D01*
G01X473404Y81649D02*
Y82277D01*
G01X475250Y80392D02*
Y80015D01*
G01X480786Y80392D02*
Y80015D01*
G01X477341Y79638D02*
X477218Y79387D01*
G01X482878Y79638D02*
X482755Y79387D01*
G01X475250Y80015D02*
X475496Y80266D01*
G01Y79764D02*
X475250Y79512D01*
G01X477095Y79890D02*
X477464Y80266D01*
G01Y79764D02*
X477341Y79638D01*
G01X480786Y80015D02*
X481032Y80266D01*
G01Y79764D02*
X480786Y79512D01*
G01X482631Y79890D02*
X483001Y80266D01*
G01Y79764D02*
X482878Y79638D01*
G01X470082Y79010D02*
X470574Y79387D01*
G01X470452Y80015D02*
X469836Y79638D01*
G01X477710Y79890D02*
X477464Y79764D01*
G01X483247Y79890D02*
X483001Y79764D01*
G01X475496Y80266D02*
X475865Y80392D01*
G01Y79890D02*
X475496Y79764D01*
G01X477464Y80266D02*
X477833Y80392D01*
G01X481032Y80266D02*
X481401Y80392D01*
G01Y79890D02*
X481032Y79764D01*
G01X483001Y80266D02*
X483370Y80392D01*
G01X469836Y76874D02*
X470452Y76497D01*
G01X470574Y77125D02*
X470206Y77377D01*
G01X484723Y76371D02*
X484108D01*
G01X482755D02*
X482139D01*
G01X477218D02*
X476603D01*
G01X479187D02*
X478572D01*
G01X480786D02*
X480171D01*
G01X475250D02*
X474635D01*
G01X471067D02*
X471805D01*
G01Y76999D02*
X471067D01*
G01X493110Y77164D02*
X489961D01*
G01X491339D02*
X497638D01*
G01X469959Y77879D02*
X469221D01*
G01X491496Y78405D02*
X491398D01*
G01X491336Y78794D02*
X491558D01*
G01X491324Y78844D02*
X491570D01*
G01X470452Y76497D02*
X471067Y76371D01*
G01Y76999D02*
X470574Y77125D01*
G01X469467Y77377D02*
X469836Y76874D01*
G01X472666Y79136D02*
X472912Y78759D01*
G01X469221Y77879D02*
X469467Y77377D01*
G01X470206D02*
X469959Y77879D01*
G01X472297Y77125D02*
X471805Y76999D01*
G01Y76371D02*
X472420Y76497D01*
G01X473650Y78507D02*
X473404Y79136D01*
G01X491398Y78405D02*
X491201Y78995D01*
G01X472912Y78759D02*
X473035Y78382D01*
G01X491447Y78455D02*
X491336Y78794D01*
G01X491275Y78995D02*
X491324Y78844D01*
G01X473035Y78382D02*
Y78130D01*
G01X473650Y78005D02*
Y78507D01*
G01X474635Y76371D02*
Y80392D01*
G01X475250Y79512D02*
Y76371D01*
G01X476603D02*
Y79387D01*
G01X477218D02*
Y76371D01*
G01X478572D02*
Y79387D01*
G01X479187D02*
Y76371D01*
G01X480171D02*
Y80392D01*
G01X480786Y79512D02*
Y76371D01*
G01X482139D02*
Y79387D01*
G01X482755D02*
Y76371D01*
G01X484108D02*
Y79387D01*
G01X484723D02*
Y76371D01*
G01X489961Y77164D02*
Y80314D01*
G01X491339D02*
Y77164D01*
G01X492126Y80314D02*
Y77164D01*
G01X492290Y80314D02*
Y77164D01*
G01X473035Y78130D02*
X472912Y77753D01*
G01X491570Y78844D02*
X491619Y78995D01*
G01X491558Y78794D02*
X491447Y78455D01*
G01X491693Y78995D02*
X491496Y78405D01*
G01X473404Y77377D02*
X473650Y78005D01*
G01X472912Y77753D02*
X472666Y77377D01*
G01X473035Y76874D02*
X473404Y77377D01*
G01X472666D02*
X472297Y77125D01*
G01X472420Y76497D02*
X473035Y76874D01*
G01X499272Y1033651D02*
X499759Y1035095D01*
X501220Y1035817D01*
X502682Y1035095D01*
X503170Y1033651D01*
X502682Y1032208D01*
X502195Y1031486D01*
X501220Y1030764D01*
X500246Y1031486D01*
X499759Y1032208D01*
X499272Y1033651D01*
Y1036539D01*
X499759Y1037982D01*
X500246Y1038704D01*
X501220Y1039426D01*
X502195Y1038704D01*
X502682Y1037982D01*
G01X485630Y1039426D02*
Y1030764D01*
G01X493425D02*
X492451Y1031486D01*
X491964Y1032208D01*
X491476Y1033651D01*
Y1036539D01*
X491964Y1037982D01*
X492451Y1038704D01*
X493425Y1039426D01*
X494400Y1038704D01*
X494887Y1037982D01*
X495374Y1036539D01*
Y1033651D01*
X494887Y1032208D01*
X494400Y1031486D01*
X493425Y1030764D01*
G01X516147Y-1124413D02*
X511870D01*
X511157Y-1129166D01*
X512583Y-1128215D01*
X514009D01*
X515434Y-1129166D01*
X516147Y-1130117D01*
X516860Y-1132018D01*
X516147Y-1133919D01*
X515434Y-1134870D01*
X514009Y-1135820D01*
X512583D01*
X511157Y-1134870D01*
X510444Y-1133919D01*
G01X517624Y-727083D02*
X663648D01*
G01X578046D02*
X517624D01*
G01X629637D02*
X517624D01*
G01X530438Y-696574D02*
X516975Y-727083D01*
G01X535631Y-645820D02*
X530438Y-696574D01*
G01X534232Y-590739D02*
X535631Y-645820D01*
G01X507784Y-629010D02*
X506809Y-628288D01*
X506322Y-627566D01*
X505835Y-626122D01*
Y-623235D01*
X506322Y-621792D01*
X506809Y-621070D01*
X507784Y-620348D01*
X508758Y-621070D01*
X509245Y-621792D01*
X509733Y-623235D01*
Y-626122D01*
X509245Y-627566D01*
X508758Y-628288D01*
X507784Y-629010D01*
G01X505290Y-601651D02*
X504316Y-600929D01*
X503828Y-600208D01*
X503341Y-598764D01*
Y-595877D01*
X503828Y-594433D01*
X504316Y-593712D01*
X505290Y-592990D01*
X506265Y-593712D01*
X506752Y-594433D01*
X507239Y-595877D01*
Y-598764D01*
X506752Y-600208D01*
X506265Y-600929D01*
X505290Y-601651D01*
G01X530535Y-533321D02*
X534232Y-590739D01*
G01X514235Y-506443D02*
X506361D01*
G01X514235D02*
X506361D01*
G01Y-504433D02*
X514235D01*
G01X506361D02*
X514235D01*
G01Y-500412D02*
X506361D01*
G01X514235D02*
X506361D01*
G01X524078Y-513982D02*
X526732Y-514434D01*
G01X524078Y-513982D02*
X526732Y-514434D01*
G01X524570Y-511469D02*
X526202Y-511803D01*
G01X524570Y-511469D02*
X526202Y-511803D01*
G01X502424Y-490863D02*
Y-514485D01*
G01Y-490863D02*
Y-514485D01*
G01X506361Y-506443D02*
Y-504433D01*
G01Y-506443D02*
Y-504433D01*
G01Y-500412D02*
Y-498402D01*
G01Y-500412D02*
Y-498402D01*
G01X521125Y-497899D02*
X520633Y-500915D01*
G01X521125Y-497899D02*
X520633Y-500915D01*
G01X518664Y-497899D02*
X518172Y-500412D01*
G01X518664Y-497899D02*
X518172Y-500412D01*
G01X521617Y-512475D02*
X524078Y-513982D01*
G01X521617Y-512475D02*
X524078Y-513982D01*
G01X514235Y-498402D02*
Y-500412D01*
G01Y-498402D02*
Y-500412D01*
G01Y-504433D02*
Y-506443D01*
G01Y-504433D02*
Y-506443D01*
G01X518172Y-500412D02*
Y-504936D01*
G01Y-500412D02*
Y-504936D01*
G01X520633Y-500915D02*
Y-504433D01*
G01Y-500915D02*
Y-504433D01*
G01X523093Y-510464D02*
X524570Y-511469D01*
G01X523093Y-510464D02*
X524570Y-511469D01*
G01X520141Y-510967D02*
X521617Y-512475D01*
G01X520141Y-510967D02*
X521617Y-512475D01*
G01X521125Y-507449D02*
X523093Y-510464D01*
G01X521125Y-507449D02*
X523093Y-510464D01*
G01X519156Y-508956D02*
X520141Y-510967D01*
G01X519156Y-508956D02*
X520141Y-510967D01*
G01X518664Y-507449D02*
X519156Y-508956D01*
G01X518664Y-507449D02*
X519156Y-508956D01*
G01X520024Y-481115D02*
X530535Y-533321D01*
G01X518172Y-504936D02*
X518664Y-507449D01*
G01X518172Y-504936D02*
X518664Y-507449D01*
G01X520633Y-504433D02*
X521125Y-507449D01*
G01X520633Y-504433D02*
X521125Y-507449D01*
G01X522306Y-492451D02*
X521617Y-492873D01*
G01X522306Y-492451D02*
X521617Y-492873D01*
G01D02*
X520141Y-494381D01*
G01X521617Y-492873D02*
X520141Y-494381D01*
G01X522866Y-495232D02*
X521125Y-497899D01*
G01X522866Y-495232D02*
X521125Y-497899D01*
G01X506361Y-498402D02*
X514235D01*
G01X506361D02*
X514235D01*
G01X520141Y-494381D02*
X519156Y-496391D01*
G01X520141Y-494381D02*
X519156Y-496391D01*
G01D02*
X518664Y-497899D01*
G01X519156Y-496391D02*
X518664Y-497899D01*
G01X528507Y-89785D02*
Y-98447D01*
G01X534353Y-92672D02*
Y-98447D01*
G01X508531D02*
Y-89785D01*
X510967Y-97003D01*
X513404Y-89785D01*
Y-98447D01*
G01X520711Y-96281D02*
X519737Y-97725D01*
X518763Y-98447D01*
X517788Y-97725D01*
X516814Y-96281D01*
Y-94838D01*
X517788Y-93394D01*
X518763Y-92672D01*
X519737Y-93394D01*
X520711Y-94838D01*
Y-96281D01*
G01X528507D02*
X527532Y-97725D01*
X526558Y-98447D01*
X525583Y-97725D01*
X524609Y-96281D01*
Y-94838D01*
X525583Y-93394D01*
X526558Y-92672D01*
X527532Y-93394D01*
X528507Y-94838D01*
G01X534353Y-89785D02*
Y-90507D01*
G01X540974Y-41835D02*
X530974D01*
G01X541060Y-41635D02*
X530889D01*
G01X540974Y-41461D02*
X530974D01*
G01Y-41403D02*
X540974D01*
G01X530974Y-41135D02*
X540974D01*
G01Y-41107D02*
X530974D01*
G01X531641Y-39467D02*
X540308D01*
G01X539974Y-39440D02*
X531974D01*
G01X530659Y-34319D02*
X541289D01*
G01X535239Y-33775D02*
X527041D01*
G01X535224Y-33102D02*
X527055D01*
G01Y-32967D02*
X535224D01*
G01Y-31261D02*
X527056D01*
G01X527055Y-30829D02*
X535224D01*
G01Y-30744D02*
X527055D01*
G01X535239Y-33775D02*
X535233Y-33744D01*
X535228Y-33713D01*
X535226Y-33682D01*
G01Y-33663D02*
X535228Y-33701D01*
X535233Y-33738D01*
X535239Y-33775D01*
G01X535226Y-33682D02*
X535224Y-33647D01*
G01Y-33621D02*
X535226Y-33663D01*
G01X527055Y-33647D02*
Y-17548D01*
G01X527054Y-33663D02*
Y-33682D01*
G01X530659Y-34319D02*
Y-32749D01*
G01X530974Y-40398D02*
Y-41832D01*
G01X533091Y-34319D02*
Y-32749D01*
G01X533710D02*
Y-34319D01*
G01X535226Y-33682D02*
Y-33663D01*
G01X535224Y-17548D02*
Y-33647D01*
G01X527054Y-33663D02*
X527055Y-33621D01*
G01Y-33647D02*
X527054Y-33682D01*
G01D02*
X527052Y-33713D01*
X527047Y-33744D01*
X527041Y-33775D01*
G01D02*
X527047Y-33738D01*
X527052Y-33701D01*
X527054Y-33663D01*
G01X530181Y-41928D02*
X529767Y-42342D01*
G01X530889Y-41635D02*
G03X530181Y-41928I-1J-1000D01*
G01X529060Y-42635D02*
G03X529767Y-42342I0J1000D01*
G01X531974Y-39440D02*
G03X530974Y-40440I0J-1000D01*
G01X528460Y-41435D02*
G03X529417Y-40679I0J984D01*
G01X531641Y-39467D02*
G03X530974Y-40398I317J-932D01*
G01Y-40845D02*
G03X529417Y-40679I-787J0D01*
G01X526305Y-34378D02*
G03X527041Y-33775I2J748D01*
G01X535239D02*
G03X535974Y-34378I734J145D01*
G01X535225Y-31261D02*
G03X535974Y-32016I748J-7D01*
G01X526305D02*
G03X527055Y-31261I2J748D01*
G01X529060Y-42635D02*
X513821D01*
G01X514821Y-42342D02*
X513821D01*
G01X514121Y-42135D02*
X514221D01*
G01X514821Y-41928D02*
X513821D01*
G01Y-41635D02*
X514833D01*
G01X528460Y-41435D02*
X513427D01*
G01X513821Y-40845D02*
X513427D01*
G01X514884Y-40746D02*
X514821D01*
G01X513821Y-40679D02*
X513427D01*
G01X513821Y-40670D02*
X513430D01*
G01X514921Y-40535D02*
X514821D01*
G01X513624Y-40442D02*
X513427D01*
G01X513821Y-40057D02*
X513427D01*
G01X514884Y-39762D02*
X514821D01*
G01X514921Y-39535D02*
X514821D01*
G01X521561Y-39469D02*
X517727D01*
G01X521364Y-39154D02*
X517727D01*
G01X517358Y-38336D02*
X513821D01*
G01Y-34399D02*
X517358D01*
G01X525569Y-33775D02*
X517386D01*
G01X521561Y-33249D02*
X517727D01*
G01X525555Y-33102D02*
X517386D01*
G01Y-32967D02*
X525555D01*
G01X514821Y-32749D02*
X557128D01*
G01X517189Y-32016D02*
X513427D01*
G01X513821Y-31425D02*
X513427D01*
G01X513821Y-31261D02*
X513428D01*
G01X517386Y-30829D02*
X525555D01*
G01Y-30744D02*
X517386D01*
G01X525555Y-31261D02*
X517386Y-31255D01*
G01X513821Y-40444D02*
X513624Y-40442D01*
G01X513700Y-41435D02*
X513559Y-41381D01*
X513475Y-41220D01*
X513439Y-40972D01*
X513430Y-40670D01*
G01X513821Y-29423D02*
X515821D01*
G01X514821Y-28812D02*
X557128D01*
G01X513821Y-28769D02*
X514821D01*
G01Y-27769D02*
X513821D01*
G01X514821Y-27423D02*
X515821D01*
G01X513821Y-42545D02*
X513826Y-42595D01*
X513840Y-42625D01*
X513865Y-42635D01*
G01X511813Y-23756D02*
X513381Y-30829D01*
G01X512197Y-23671D02*
X513765Y-30744D01*
G01X525569Y-33775D02*
X525563Y-33744D01*
X525559Y-33713D01*
X525556Y-33682D01*
G01X514821Y-42545D02*
X514831Y-42596D01*
X514861Y-42626D01*
X514911Y-42635D01*
G01X525556Y-33663D02*
X525559Y-33701D01*
X525563Y-33738D01*
X525569Y-33775D01*
G01X525556Y-33682D02*
X525555Y-33647D01*
G01Y-33621D02*
X525556Y-33663D01*
G01X513430Y-40670D02*
X513427Y-40442D01*
G01Y-31255D02*
Y-41435D01*
G01X513821Y-42635D02*
Y106958D01*
G01X514821Y-32749D02*
Y-42635D01*
G01Y-29423D02*
Y106958D01*
G01X514884Y-41402D02*
Y-39762D01*
G01X514921Y-39535D02*
Y-41435D01*
G01X515789Y-32016D02*
Y-41435D01*
G01X515821Y106958D02*
Y-32016D01*
G01Y-32749D02*
Y-42635D01*
G01X517136Y-38879D02*
Y-33339D01*
G01X517189Y-32016D02*
Y-33866D01*
G01X517386Y-17548D02*
Y-33866D01*
G01X518358Y-35399D02*
Y-37336D01*
G01X521955Y-33339D02*
Y-38564D01*
G01X522152Y-33839D02*
Y-38879D01*
G01X525556Y-33682D02*
Y-33663D01*
G01X525555Y-17548D02*
Y-33647D01*
G01X513821Y-31261D02*
G03X513765Y-30744I-2362J6D01*
G01X513427Y-31261D02*
G03X513381Y-30829I-1968J9D01*
G01X513427Y-41402D02*
G03X514884I728J0D01*
G01X514221Y-42135D02*
G03X514921Y-41435I0J700D01*
G01X513819Y-42067D02*
G03X514121Y-42135I301J632D01*
G01X518358Y-35399D02*
G03X517358Y-34399I-1000J0D01*
G01Y-38336D02*
G03X518358Y-37336I0J1000D01*
G01X515821Y-29423D02*
G03Y-27423I0J1000D01*
G01X516795Y-32016D02*
G03X517386Y-31425I0J591D01*
G01X521955Y-33339D02*
G03X521364Y-32749I-591J-1D01*
G01X517727D02*
G03X517136Y-33339I0J-591D01*
G01X517727Y-33249D02*
G03X517136Y-33839I0J-591D01*
G01X521561Y-39469D02*
G03X522152Y-38879I0J591D01*
G01X517136D02*
G03X517727Y-39469I591J1D01*
G01X517136Y-38564D02*
G03X517727Y-39154I591J1D01*
G01X521364D02*
G03X521955Y-38564I0J591D01*
G01Y-33839D02*
G03X521364Y-33249I-591J-1D01*
G01X522152Y-33839D02*
G03X521561Y-33249I-591J-1D01*
G01X517189Y-33866D02*
G03X517386I99J0D01*
G01X525569Y-33775D02*
G03X526305Y-34378I734J145D01*
G01X525556Y-31261D02*
G03X526305Y-32016I748J-7D01*
G01X534437Y-16764D02*
X534590Y-16779D01*
X534737Y-16823D01*
X534873Y-16895D01*
X534994Y-16994D01*
X535091Y-17112D01*
X535164Y-17247D01*
X535209Y-17393D01*
X535224Y-17548D01*
G01X527843Y-16798D02*
X527690Y-16813D01*
X527543Y-16857D01*
X527407Y-16929D01*
X527286Y-17028D01*
X527188Y-17146D01*
X527116Y-17281D01*
X527071Y-17427D01*
X527055Y-17582D01*
G01X527843Y-16904D02*
X527690Y-16917D01*
X527543Y-16954D01*
X527407Y-17015D01*
X527286Y-17099D01*
X527188Y-17199D01*
X527116Y-17313D01*
X527071Y-17437D01*
X527055Y-17568D01*
G01X535224Y-18862D02*
X527055D01*
G01Y-18845D02*
X535224D01*
G01Y-18516D02*
X527055D01*
G01Y-18481D02*
X535224D01*
G01Y-18138D02*
X527055D01*
G01Y-18104D02*
X535224D01*
G01X527055Y-17890D02*
X535224D01*
G01Y-17679D02*
X527055D01*
G01X527843Y-17116D02*
X534437D01*
G01Y-16904D02*
X527843D01*
G01Y-16798D02*
X534437D01*
G01Y-16764D02*
X527843D01*
G01X534437Y-17116D02*
X534590Y-17128D01*
X534737Y-17166D01*
X534873Y-17227D01*
X534994Y-17310D01*
X535091Y-17410D01*
X535164Y-17525D01*
X535209Y-17649D01*
X535224Y-17780D01*
G01Y-17582D02*
X535209Y-17430D01*
X535165Y-17284D01*
X535093Y-17149D01*
X534994Y-17028D01*
X534875Y-16931D01*
X534740Y-16858D01*
X534593Y-16814D01*
X534437Y-16798D01*
G01X527425Y-17318D02*
Y-6688D01*
G01Y-1570D02*
Y9060D01*
G01X527843Y-16904D02*
Y-17116D01*
G01Y-16798D02*
Y-16764D01*
G01X535224Y-17568D02*
X535209Y-17439D01*
X535165Y-17315D01*
X535093Y-17201D01*
X534994Y-17099D01*
X534875Y-17016D01*
X534740Y-16955D01*
X534593Y-16917D01*
X534437Y-16904D01*
G01Y-16764D02*
Y-16798D01*
G01Y-17116D02*
Y-16904D01*
G01X527055Y-17548D02*
X527070Y-17396D01*
X527115Y-17249D01*
X527187Y-17114D01*
X527286Y-16994D01*
X527405Y-16896D01*
X527540Y-16824D01*
X527687Y-16779D01*
X527843Y-16764D01*
G01X527055Y-17780D02*
X527070Y-17651D01*
X527115Y-17527D01*
X527187Y-17412D01*
X527286Y-17310D01*
X527405Y-17228D01*
X527540Y-17167D01*
X527687Y-17129D01*
X527843Y-17116D01*
G01X527055Y-24077D02*
X535224D01*
G01Y-23942D02*
X527055D01*
G01X535224Y-23756D02*
X527055D01*
G01Y-23671D02*
X535224D01*
G01X527055Y-23348D02*
X535224D01*
G01Y-23331D02*
X527055D01*
G01Y-23097D02*
X535224D01*
G01Y-23063D02*
X527055D01*
G01X524768Y-16764D02*
X524921Y-16779D01*
X525068Y-16823D01*
X525204Y-16895D01*
X525325Y-16994D01*
X525422Y-17112D01*
X525495Y-17247D01*
X525540Y-17393D01*
X525555Y-17548D01*
G01X516314Y-972D02*
X516261Y-958D01*
G01X516393Y-704D02*
X516445Y-717D01*
G01X514398Y-490D02*
X514359Y-476D01*
G01X516183Y-985D02*
X516248Y-1025D01*
G01X516524Y-690D02*
X516458Y-650D01*
G01X518173Y-16798D02*
X518020Y-16813D01*
X517873Y-16857D01*
X517738Y-16929D01*
X517617Y-17028D01*
X517519Y-17146D01*
X517446Y-17281D01*
X517402Y-17427D01*
X517386Y-17582D01*
G01X518173Y-16904D02*
X518020Y-16917D01*
X517873Y-16954D01*
X517738Y-17015D01*
X517617Y-17099D01*
X517519Y-17199D01*
X517446Y-17313D01*
X517402Y-17437D01*
X517386Y-17568D01*
G01X687049Y-21761D02*
X514821D01*
G01X513821Y-21261D02*
X517758D01*
G01X525555Y-18862D02*
X517386D01*
G01Y-18845D02*
X525555D01*
G01Y-18516D02*
X517386D01*
G01Y-18481D02*
X525555D01*
G01Y-18138D02*
X517386D01*
G01Y-18104D02*
X525555D01*
G01X517386Y-17890D02*
X525555D01*
G01Y-17679D02*
X517386D01*
G01X527425Y-17318D02*
X522504D01*
G01X518173Y-17116D02*
X524768D01*
G01Y-16904D02*
X518173D01*
G01Y-16798D02*
X524768D01*
G01Y-16764D02*
X518173D01*
G01X527425Y-14786D02*
X522504D01*
G01Y-14307D02*
X527425D01*
G01X513821Y-13551D02*
X517758D01*
G01X515821Y-12551D02*
X512561D01*
G01X514821Y-11551D02*
X513955D01*
G01X512561Y-11383D02*
X513821D01*
G01X527425Y-9699D02*
X522504D01*
G01Y-9220D02*
X527425D01*
G01X519333Y-8460D02*
X514089D01*
G01X522504Y-6688D02*
X527425D01*
G01X514089Y-4525D02*
X519333D01*
G01X514821Y-2525D02*
X513821D01*
G01Y-2040D02*
X512561D01*
G01X513821Y-1874D02*
X514821D01*
G01X513821Y-1777D02*
X514821D01*
G01X527425Y-1570D02*
X522504D01*
G01X513821Y-1273D02*
X514821D01*
G01X513821Y-1244D02*
X514821D01*
G01X512561Y-1208D02*
X513821D01*
G01X514109Y-1039D02*
X514031D01*
G01X514910D02*
X514831D01*
G01X515750D02*
X515671D01*
G01X515304D02*
X515225D01*
G01X516012D02*
X515933D01*
G01X516314D02*
X516393D01*
G01Y-972D02*
X516314D01*
G01X516196Y-878D02*
X516117D01*
G01X514821Y-832D02*
X513821D01*
G01X514346Y-757D02*
X514109D01*
G01X516117D02*
X516209D01*
G01X515671Y-744D02*
X515304D01*
G01X516314Y-704D02*
X516393D01*
G01X514109Y-677D02*
X514359D01*
G01X515304Y-664D02*
X515671D01*
G01X516393Y-637D02*
X516314D01*
G01X514359Y-476D02*
X514109D01*
G01X514831D02*
X514621D01*
G01X515120D02*
X514910D01*
G01X516183D02*
X516563D01*
G01Y-409D02*
X516117D01*
G01X514031D02*
X514346D01*
G01X514621D02*
X515120D01*
G01X515671D02*
X515750D01*
G01X515225D02*
X515304D01*
G01X515933D02*
X516012D01*
G01X513821Y153D02*
X514821D01*
G01X513821Y560D02*
X514821D01*
G01X513821Y590D02*
X514821D01*
G01X527425Y962D02*
X522504D01*
G01X513821Y1097D02*
X514821D01*
G01Y1190D02*
X513821D01*
G01X522504Y1441D02*
X527425D01*
G01X514821Y1845D02*
X513821D01*
G01X514821Y3845D02*
X513821D01*
G01X514821Y4436D02*
X513821D01*
G01X527425Y6049D02*
X522504D01*
G01X524768Y-17116D02*
X524921Y-17128D01*
X525068Y-17166D01*
X525204Y-17227D01*
X525325Y-17310D01*
X525422Y-17410D01*
X525495Y-17525D01*
X525540Y-17649D01*
X525555Y-17780D01*
G01X516248Y-1025D02*
X516314Y-1039D01*
G01X514346Y-409D02*
X514411Y-422D01*
G01X516458Y-650D02*
X516393Y-637D01*
G01X516261Y-958D02*
X516222Y-932D01*
G01X516445Y-717D02*
X516485Y-744D01*
G01X514411Y-422D02*
X514464Y-462D01*
G01X514424Y-516D02*
X514398Y-490D01*
G01X514464Y-462D02*
X514503Y-516D01*
G01X516143Y-932D02*
X516183Y-985D01*
G01X516445Y-958D02*
X516393Y-972D01*
G01X516261Y-717D02*
X516314Y-704D01*
G01X516393Y-1039D02*
X516458Y-1025D01*
G01X516314Y-637D02*
X516248Y-650D01*
G01X514411Y-744D02*
X514346Y-757D01*
G01X516563Y-744D02*
X516524Y-690D01*
G01X516485Y-744D02*
X516511Y-784D01*
G01X510763Y-17116D02*
X511257Y-17890D01*
G01X511095Y-16904D02*
X511589Y-17679D01*
G01X516117Y-878D02*
X516143Y-932D01*
G01X516222D02*
X516196Y-878D01*
G01X516590Y-811D02*
X516563Y-744D01*
G01X514437Y-557D02*
X514424Y-516D01*
G01X514503D02*
X514516Y-557D01*
G01X516511Y-784D02*
X516524Y-825D01*
G01X525555Y-17582D02*
X525540Y-17430D01*
X525496Y-17284D01*
X525424Y-17149D01*
X525325Y-17028D01*
X525206Y-16931D01*
X525070Y-16858D01*
X524924Y-16814D01*
X524768Y-16798D01*
G01X512561Y35593D02*
Y-12551D01*
G01X513955Y-11551D02*
Y-12551D01*
G01X514031Y-1039D02*
Y-409D01*
G01X514089Y-4525D02*
Y-8460D01*
G01X514109Y-757D02*
Y-1039D01*
G01Y-476D02*
Y-677D01*
G01X514437Y-597D02*
Y-557D01*
G01X514516D02*
Y-610D01*
G01X514621Y-476D02*
Y-409D01*
G01X514831Y-1039D02*
Y-476D01*
G01X514910D02*
Y-1039D01*
G01X515120Y-409D02*
Y-476D01*
G01X515225Y-1039D02*
Y-409D01*
G01X515304Y-744D02*
Y-1039D01*
G01Y-409D02*
Y-664D01*
G01X515671Y-1039D02*
Y-744D01*
G01Y-664D02*
Y-409D01*
G01X515750D02*
Y-1039D01*
G01X515855Y-610D02*
Y-503D01*
G01X515933Y-1039D02*
Y-516D01*
G01X516012Y-409D02*
Y-1039D01*
G01X516117Y-409D02*
Y-757D01*
G01X516183Y-690D02*
Y-476D01*
G01X516524Y-825D02*
Y-851D01*
G01X516563Y-476D02*
Y-409D01*
G01X516590Y-865D02*
Y-811D01*
G01X518173Y-16904D02*
Y-17116D01*
G01Y-16798D02*
Y-16764D01*
G01X518758Y-14551D02*
Y-20261D01*
G01X520333Y-5525D02*
Y-7460D01*
G01X522504Y9060D02*
Y-1570D01*
G01Y-6688D02*
Y-17318D01*
G01X524768Y-16764D02*
Y-16798D01*
G01Y-17116D02*
Y-16904D01*
G01X525555Y-17568D02*
X525540Y-17439D01*
X525496Y-17315D01*
X525424Y-17201D01*
X525325Y-17099D01*
X525206Y-17016D01*
X525070Y-16955D01*
X524924Y-16917D01*
X524768Y-16904D01*
G01X517386Y-17548D02*
X517401Y-17396D01*
X517445Y-17249D01*
X517518Y-17114D01*
X517617Y-16994D01*
X517735Y-16896D01*
X517871Y-16824D01*
X518018Y-16779D01*
X518173Y-16764D01*
G01X517386Y-17780D02*
X517401Y-17651D01*
X517445Y-17527D01*
X517518Y-17412D01*
X517617Y-17310D01*
X517735Y-17228D01*
X517871Y-17167D01*
X518018Y-17129D01*
X518173Y-17116D01*
G01X514424Y-637D02*
X514437Y-597D01*
G01X514516Y-610D02*
X514503Y-650D01*
G01X516524Y-851D02*
X516511Y-892D01*
G01X516563Y-932D02*
X516590Y-865D01*
G01X516511Y-892D02*
X516485Y-932D01*
G01X514503Y-650D02*
X514464Y-704D01*
G01X516524Y-985D02*
X516563Y-932D01*
G01X515855Y-503D02*
X515933Y-409D01*
G01Y-516D02*
X515855Y-610D01*
G01X514398Y-664D02*
X514424Y-637D01*
G01X514464Y-704D02*
X514411Y-744D01*
G01X516209Y-757D02*
X516261Y-717D01*
G01X516485Y-932D02*
X516445Y-958D01*
G01X511095Y-16904D02*
X510763Y-17116D01*
G01X511518Y-17568D02*
X511186Y-17780D01*
G01X516248Y-650D02*
X516183Y-690D01*
G01X516458Y-1025D02*
X516524Y-985D01*
G01X514359Y-677D02*
X514398Y-664D01*
G01X511956Y-18845D02*
G03X511589Y-17679I-2360J-102D01*
G01X511563Y-18862D02*
G03X511257Y-17890I-1967J-85D01*
G01X518758Y-14551D02*
G03X517758Y-13551I-1000J0D01*
G01Y-21261D02*
G03X518758Y-20261I0J1000D01*
G01X515821Y-14551D02*
G03X514821Y-15551I0J-1000D01*
G01X515821Y-14551D02*
G03Y-12551I0J1000D01*
G01X519333Y-8460D02*
G03X520333Y-7460I0J1000D01*
G01Y-5525D02*
G03X519333Y-4525I-1000J0D01*
G01X514821Y-24510D02*
X687049D01*
G01X513821Y-24261D02*
X514821D01*
G01X517386Y-24077D02*
X525555D01*
G01Y-23942D02*
X517386D01*
G01X687049Y-23803D02*
X514821D01*
G01X525555Y-23756D02*
X517386D01*
G01Y-23671D02*
X525555D01*
G01X517386Y-23348D02*
X525555D01*
G01Y-23331D02*
X517386D01*
G01X513821Y-23261D02*
X514821D01*
G01Y-23175D02*
X687049D01*
G01X517386Y-23097D02*
X525555D01*
G01X514821Y-23095D02*
X557128D01*
G01X525555Y-23063D02*
X517386D01*
G01X557128Y-22468D02*
X514821D01*
G01X511563Y-18862D02*
X511759Y-23348D01*
G01X511956Y-18845D02*
X512152Y-23331D01*
G01X511759Y-23348D02*
G03X511813Y-23756I2360J105D01*
G01X512152Y-23331D02*
G03X512197Y-23671I1967J87D01*
G01X526743Y18393D02*
X527443D01*
G01X529695D02*
X530395D01*
G01X535601D02*
X536301D01*
G01X532648D02*
X533348D01*
G01X536301Y21371D02*
X535601D01*
G01X533348D02*
X532648D01*
G01X530395D02*
X529695D01*
G01X527443D02*
X526743D01*
G01X536301Y24336D02*
X535601D01*
G01X533348D02*
X532648D01*
G01X530395D02*
X529695D01*
G01X527443D02*
X526743D01*
G01X536301Y24561D02*
X535601D01*
G01X533348D02*
X532648D01*
G01X530395D02*
X529695D01*
G01X527443D02*
X526743D01*
G01X535677Y27251D02*
X532319D01*
G01X534596Y34687D02*
X535426Y34292D01*
X536358Y34145D01*
X537287Y34260D01*
X538174Y34632D01*
X538953Y35247D01*
X539549Y36062D01*
X539929Y37073D01*
G01X534596Y34686D02*
X535406Y34298D01*
X536329Y34147D01*
X537261Y34252D01*
X538156Y34621D01*
X538944Y35238D01*
X539546Y36057D01*
X539929Y37073D01*
G01X535677Y28251D02*
X532319D01*
G01X535677Y29251D02*
X532319D01*
G01X535677Y29501D02*
X532319D01*
G01X539236Y29645D02*
X532713D01*
G01X535087Y32851D02*
X532910D01*
G01X544162Y35857D02*
X527739D01*
G01X529848Y39032D02*
X529821D01*
G01X528100Y34257D02*
X532713Y29645D01*
G01X539513Y39341D02*
X538819Y40133D01*
X537981Y40686D01*
X537029Y40994D01*
X536052Y41031D01*
X535128Y40806D01*
X534306Y40333D01*
X533678Y39674D01*
G01X539512Y39341D02*
X538855Y40265D01*
X537956Y40969D01*
X536857Y41398D01*
X535699Y41489D01*
X534561Y41238D01*
X533559Y40682D01*
X532748Y39846D01*
X532214Y38822D01*
X531999Y37666D01*
X532127Y36502D01*
X532576Y35448D01*
X533329Y34547D01*
X534321Y33899D01*
X535460Y33574D01*
X536625Y33592D01*
X537735Y33950D01*
X538694Y34614D01*
X539430Y35547D01*
X539861Y36666D01*
X539939Y37866D01*
X539642Y39065D01*
X539034Y40063D01*
X538176Y40833D01*
X537084Y41340D01*
X535919Y41497D01*
X534776Y41313D01*
X533709Y40790D01*
X532867Y40005D01*
X532283Y39005D01*
X532009Y37852D01*
X532078Y36714D01*
X532471Y35630D01*
X533168Y34697D01*
X534119Y33999D01*
X535219Y33612D01*
X536371Y33560D01*
X537487Y33837D01*
X538428Y34385D01*
X539205Y35195D01*
X539743Y36241D01*
X539951Y37379D01*
X539818Y38551D01*
X539363Y39606D01*
X538609Y40501D01*
X537631Y41136D01*
X536485Y41464D01*
X535357Y41451D01*
X534244Y41101D01*
X533291Y40458D01*
X532544Y39533D01*
X532091Y38387D01*
X532009Y37197D01*
X532264Y36081D01*
X532830Y35079D01*
X533671Y34274D01*
X534732Y33738D01*
X535906Y33540D01*
X537100Y33702D01*
X538152Y34188D01*
X539024Y34961D01*
X539634Y35956D01*
X539930Y37089D01*
X539887Y38249D01*
X539512Y39341D01*
G01X539930Y38246D02*
X539549Y39363D01*
X538860Y40321D01*
X537920Y41039D01*
X536814Y41452D01*
X535635Y41526D01*
X534480Y41253D01*
X533468Y40664D01*
X532657Y39792D01*
X532140Y38731D01*
X531953Y37567D01*
X532113Y36392D01*
X532602Y35327D01*
X533394Y34434D01*
X534401Y33817D01*
X535540Y33520D01*
X536720Y33566D01*
X537835Y33953D01*
X538795Y34651D01*
X539507Y35597D01*
X539913Y36703D01*
X539980Y37880D01*
X539702Y39030D01*
X539102Y40048D01*
X538228Y40850D01*
X537164Y41361D01*
X535998Y41540D01*
X534828Y41373D01*
X533760Y40876D01*
X532876Y40083D01*
X532265Y39072D01*
X531974Y37928D01*
X532027Y36749D01*
X532420Y35636D01*
X533120Y34685D01*
X534067Y33978D01*
X535177Y33577D01*
X536357Y33515D01*
X537504Y33799D01*
X538517Y34402D01*
X539312Y35274D01*
X539820Y36340D01*
X539996Y37508D01*
X539826Y38676D01*
X539324Y39745D01*
X538539Y40618D01*
X537529Y41228D01*
X536384Y41519D01*
X535205Y41466D01*
X534087Y41070D01*
X533148Y40380D01*
X532441Y39439D01*
X532035Y38330D01*
X531969Y37152D01*
X532250Y35999D01*
X532842Y34995D01*
X533706Y34197D01*
X534769Y33682D01*
X535933Y33497D01*
X537103Y33658D01*
X538172Y34150D01*
X539049Y34925D01*
X539670Y35930D01*
X539972Y37069D01*
X539930Y38246D01*
G01X539929Y37073D02*
X539887Y38248D01*
X539493Y39377D01*
X538809Y40312D01*
X537873Y41015D01*
X536735Y41425D01*
X535533Y41473D01*
X534355Y41153D01*
X533393Y40547D01*
X532648Y39701D01*
X532159Y38649D01*
X531996Y37437D01*
X532212Y36222D01*
X532731Y35212D01*
X533535Y34375D01*
X534534Y33809D01*
X535648Y33553D01*
X536867Y33640D01*
X537973Y34077D01*
X538857Y34776D01*
X539515Y35701D01*
X539887Y36795D01*
X539931Y37942D01*
X539627Y39097D01*
X539026Y40073D01*
X538153Y40847D01*
X537135Y41325D01*
X535989Y41498D01*
X534774Y41312D01*
X533747Y40818D01*
X532906Y40051D01*
X532294Y39033D01*
X532014Y37904D01*
X532070Y36751D01*
X532476Y35620D01*
X533171Y34695D01*
X534070Y34025D01*
X535158Y33624D01*
X536367Y33559D01*
X537497Y33842D01*
X538474Y34422D01*
X539273Y35293D01*
X539764Y36305D01*
X539954Y37526D01*
X539763Y38734D01*
X539274Y39744D01*
X538507Y40588D01*
X537532Y41180D01*
X536402Y41475D01*
X535197Y41421D01*
X534091Y41025D01*
X533193Y40364D01*
X532491Y39441D01*
X532094Y38402D01*
X532006Y37241D01*
X532285Y36025D01*
X532870Y35030D01*
X533724Y34237D01*
X534794Y33718D01*
X535944Y33540D01*
X537095Y33700D01*
X538163Y34195D01*
X539013Y34949D01*
X539637Y35962D01*
X539929Y37073D01*
G01X526707Y43930D02*
Y38588D01*
G01X526743Y24561D02*
Y18393D01*
G01X527443Y24561D02*
Y18393D01*
G01X527707Y44408D02*
Y38588D01*
G01X527957Y43930D02*
Y38588D01*
G01X528100Y34257D02*
Y40780D01*
G01X528982Y44408D02*
Y36569D01*
G01X529123Y44408D02*
Y37242D01*
G01X529695Y24561D02*
Y18393D01*
G01X529821Y37940D02*
Y44408D01*
G01X529848Y38069D02*
Y44408D01*
G01X530395Y24561D02*
Y18393D01*
G01X531132Y43339D02*
Y39178D01*
G01X531319Y31038D02*
Y26751D01*
G01X532319Y32261D02*
Y26751D01*
G01X532648Y24561D02*
Y18393D01*
G01X533348Y24561D02*
Y18393D01*
G01X535601Y24561D02*
Y18393D01*
G01X535677Y32261D02*
Y26751D01*
G01X528785Y36767D02*
X527919Y35267D01*
G01X528982Y36569D02*
X529848Y38069D01*
G01X528785Y36767D02*
X529848Y38069D01*
G01X527919Y35267D02*
X528982Y36569D01*
G01X532801Y41985D02*
X529848Y39032D01*
G01X529821Y37940D02*
X527739Y35857D01*
G01X535677Y26751D02*
G03X536677I500J0D01*
G01X531319D02*
G03X532319I500J0D01*
G01X540305Y37519D02*
G03I-4330J0D01*
G01X539124D02*
G03I-3149J0D01*
G01X532910Y32851D02*
G03X532319Y32261I0J-591D01*
G01X535677D02*
G03X535087Y32851I-590J0D01*
G01X530541Y38588D02*
G03X531132Y39178I1J590D01*
G01X553569Y12019D02*
X518333D01*
G01X512443Y14915D02*
X513821D01*
G01X551404Y14955D02*
X520498D01*
G01X513821Y17868D02*
X512443D01*
G01X519333Y18242D02*
X514089D01*
G01X523790Y18393D02*
X524490D01*
G01Y21371D02*
X523790D01*
G01X524490Y24336D02*
X523790D01*
G01X524490Y24561D02*
X523790D01*
G01X513955Y26116D02*
X519333D01*
G01X514821Y27116D02*
X513955D01*
G01X512443Y12946D02*
X513821Y12151D01*
G01X526440Y38588D02*
X526159Y38547D01*
X525926Y38441D01*
X525764Y38279D01*
X525707Y38088D01*
G01X513821Y33593D02*
X512561D01*
G01X520498Y34353D02*
X551404D01*
G01X513955Y34908D02*
X514821D01*
G01X551404Y35141D02*
X520498D01*
G01X553569Y35267D02*
X518333D01*
G01X514561Y35593D02*
X512561D01*
G01X514821Y35908D02*
X513821D01*
G01X528785Y36767D02*
X518333D01*
G01X514821Y36908D02*
X513821D01*
G01X528100Y37588D02*
X526207D01*
G01X526073Y38588D02*
X530541D01*
G01X512443Y19836D02*
Y12946D01*
G01X513955Y35593D02*
Y26116D01*
G01X514089D02*
Y18242D01*
G01X520333Y25116D02*
Y19242D01*
G01X520498Y35141D02*
Y14955D01*
G01X523790Y24561D02*
Y18393D01*
G01X524490Y24561D02*
Y18393D01*
G01X525707Y43930D02*
Y38088D01*
G01X525738Y44408D02*
Y36767D01*
G01X525707Y38088D02*
X525738Y38288D01*
X525821Y38447D01*
X525941Y38552D01*
X526073Y38588D01*
G01X513821Y20632D02*
X512443Y19836D01*
G01X519333Y18242D02*
G03X520333Y19242I0J1000D01*
G01Y25116D02*
G03X519333Y26116I-1000J0D01*
G01X514561Y35593D02*
G03X514821Y38570I0J1500D01*
G01X525707Y38088D02*
G03X526207Y37588I500J0D01*
G01X522504Y6528D02*
X527425D01*
G01X513821Y6877D02*
X514821D01*
G01Y7468D02*
X513821D01*
G01X522504Y9060D02*
X527425D01*
G01X518333Y11019D02*
X553569D01*
G01X518333Y44408D02*
Y11019D01*
G01X520498Y14955D02*
X519317Y11019D01*
G01X520498Y14955D02*
X519317Y11019D01*
G01X532713Y45393D02*
X539236D01*
G01X540872Y45528D02*
X531030D01*
G01X540872Y46512D02*
X531030D01*
G01X526743Y48355D02*
X527443D01*
G01X535601D02*
X536301D01*
G01Y48571D02*
X535601D01*
G01X527443D02*
X526743D01*
G01X536301Y48667D02*
X535601D01*
G01X527443D02*
X526743D01*
G01X536301Y48729D02*
X535601D01*
G01X527443D02*
X526743D01*
G01X536301Y48827D02*
X535601D01*
G01X527443D02*
X526743D01*
G01X536301Y49812D02*
X535601D01*
G01X527443D02*
X526743D01*
G01X536301Y49910D02*
X535601D01*
G01X527443D02*
X526743D01*
G01X536301Y49973D02*
X535601D01*
G01X527443D02*
X526743D01*
G01X536301Y50068D02*
X535601D01*
G01X527443D02*
X526743D01*
G01Y50284D02*
X527443D01*
G01X535601D02*
X536301D01*
G01X529695Y51111D02*
X530395D01*
G01Y51327D02*
X529695D01*
G01X530395Y51423D02*
X529695D01*
G01X530395Y51485D02*
X529695D01*
G01X530395Y51583D02*
X529695D01*
G01X530395Y52568D02*
X529695D01*
G01X530395Y52666D02*
X529695D01*
G01X530395Y52729D02*
X529695D01*
G01X530395Y52823D02*
X529695D01*
G01Y53040D02*
X530395D01*
G01X533348Y53867D02*
X532648D01*
G01Y54083D02*
X533348D01*
G01X532648Y54179D02*
X533348D01*
G01X532648Y54241D02*
X533348D01*
G01Y54339D02*
X532648D01*
G01X533348Y55323D02*
X532648D01*
G01X533348Y55422D02*
X532648D01*
G01Y55484D02*
X533348D01*
G01X532648Y55579D02*
X533348D01*
G01Y55796D02*
X532648D01*
G01X526743Y63316D02*
X527443D01*
G01X535601D02*
X536301D01*
G01Y63532D02*
X535601D01*
G01X527443D02*
X526743D01*
G01X536301Y63627D02*
X535601D01*
G01X527443D02*
X526743D01*
G01X536301Y63690D02*
X535601D01*
G01X527443D02*
X526743D01*
G01X536301Y63788D02*
X535601D01*
G01X527443D02*
X526743D01*
G01X536301Y64772D02*
X535601D01*
G01X527443D02*
X526743D01*
G01X536301Y64871D02*
X535601D01*
G01X527443D02*
X526743D01*
G01X536301Y64933D02*
X535601D01*
G01X527443D02*
X526743D01*
G01X536301Y65028D02*
X535601D01*
G01X527443D02*
X526743D01*
G01Y65245D02*
X527443D01*
G01X535601D02*
X536301D01*
G01X529695Y66071D02*
X530395D01*
G01Y66288D02*
X529695D01*
G01X530395Y66383D02*
X529695D01*
G01X530395Y66445D02*
X529695D01*
G01X530395Y66544D02*
X529695D01*
G01X530395Y67528D02*
X529695D01*
G01X530395Y67627D02*
X529695D01*
G01X530395Y67689D02*
X529695D01*
G01X530395Y67784D02*
X529695D01*
G01Y68001D02*
X530395D01*
G01X533348Y68827D02*
X532648D01*
G01Y69044D02*
X533348D01*
G01X532648Y69139D02*
X533348D01*
G01X532648Y69201D02*
X533348D01*
G01Y69300D02*
X532648D01*
G01X533348Y70284D02*
X532648D01*
G01X533348Y70382D02*
X532648D01*
G01Y70445D02*
X533348D01*
G01Y70540D02*
X532648D01*
G01X533348Y70756D02*
X532648D01*
G01X526743Y48356D02*
Y50282D01*
G01Y63317D02*
Y65243D01*
G01X527443Y48357D02*
Y50283D01*
G01Y63318D02*
Y65243D01*
G01X529695Y51112D02*
Y53038D01*
G01Y66073D02*
Y67999D01*
G01X530395Y51113D02*
Y53039D01*
G01Y66073D02*
Y67999D01*
G01X532648Y53868D02*
Y55794D01*
G01Y68829D02*
Y70755D01*
G01X533348Y53869D02*
Y55795D01*
G01Y68829D02*
Y70755D01*
G01X535601Y48356D02*
Y50282D01*
G01Y63317D02*
Y65243D01*
G01X539100Y41985D02*
X532801D01*
G01X531030Y46512D02*
Y44408D01*
G01X532713Y45393D02*
X528100Y40780D01*
G01X534306Y40332D02*
X535119Y40802D01*
X536028Y41029D01*
X536992Y41001D01*
X537944Y40703D01*
X538797Y40152D01*
X539512Y39341D01*
G01X531132Y43339D02*
G03X530541Y43930I-591J0D01*
G01X514307Y52408D02*
X514372Y52394D01*
G01X514359Y52327D02*
X514320Y52341D01*
G01X512443Y72001D02*
X513821Y71206D01*
G01X514372Y52394D02*
X514425Y52354D01*
G01X513821Y50541D02*
X514821D01*
G01X513821Y50638D02*
X514821D01*
G01X513821Y51142D02*
X514821D01*
G01X513821Y51171D02*
X514821D01*
G01Y51583D02*
X513821D01*
G01X514070Y51778D02*
X513992D01*
G01X514871D02*
X514792D01*
G01X515711D02*
X515632D01*
G01X515265D02*
X515186D01*
G01X515973D02*
X515894D01*
G01X514307Y52059D02*
X514070D01*
G01X515632Y52073D02*
X515265D01*
G01X514070Y52140D02*
X514320D01*
G01X515265Y52153D02*
X515632D01*
G01X514320Y52341D02*
X514070D01*
G01X514792D02*
X514582D01*
G01X515081D02*
X514871D01*
G01X513992Y52408D02*
X514307D01*
G01X514582D02*
X515081D01*
G01X515632D02*
X515711D01*
G01X515186D02*
X515265D01*
G01X515894D02*
X515973D01*
G01X513821Y52568D02*
X514821D01*
G01X513821Y52975D02*
X514821D01*
G01X513821Y53005D02*
X514821D01*
G01X513821Y53512D02*
X514821D01*
G01Y53605D02*
X513821D01*
G01X524490Y53867D02*
X523790D01*
G01Y54083D02*
X524490D01*
G01X523790Y54179D02*
X524490D01*
G01X523790Y54241D02*
X524490D01*
G01X514821Y54260D02*
X513821D01*
G01X514821Y54275D02*
X513821D01*
G01X524490Y54339D02*
X523790D01*
G01X523989Y54546D02*
X523930D01*
G01X524323D02*
X524264D01*
G01X524461D02*
X524402D01*
G01X524796D02*
X524737D01*
G01X524993D02*
X524933D01*
G01X524225Y54667D02*
X524028D01*
G01X524697D02*
X524500D01*
G01X524215Y54707D02*
X524038D01*
G01X524687D02*
X524510D01*
G01X524087Y55019D02*
X524166D01*
G01X524559D02*
X524638D01*
G01X524933D02*
X524993D01*
G01X524490Y55323D02*
X523790D01*
G01X524490Y55422D02*
X523790D01*
G01Y55484D02*
X524490D01*
G01X523790Y55579D02*
X524490D01*
G01Y55796D02*
X523790D01*
G01X513821Y56275D02*
X518341D01*
G01X513821Y68775D02*
X518341D01*
G01X524490Y68827D02*
X523790D01*
G01Y69044D02*
X524490D01*
G01X523790Y69139D02*
X524490D01*
G01X523790Y69201D02*
X524490D01*
G01Y69300D02*
X523790D01*
G01X524490Y70284D02*
X523790D01*
G01X524490Y70382D02*
X523790D01*
G01Y70445D02*
X524490D01*
G01Y70540D02*
X523790D01*
G01X524490Y70756D02*
X523790D01*
G01X513821Y70775D02*
X514821D01*
G01Y71775D02*
X513821D01*
G01X514385Y52301D02*
X514359Y52327D01*
G01X514425Y52354D02*
X514464Y52301D01*
G01X514372Y52073D02*
X514307Y52059D01*
G01X514901Y56275D02*
X514856Y56266D01*
X514830Y56240D01*
X514821Y56195D01*
G01X514398Y52260D02*
X514385Y52301D01*
G01X514464D02*
X514477Y52260D01*
G01X524166Y55019D02*
X524323Y54546D01*
G01X524638Y55019D02*
X524796Y54546D01*
G01X524264D02*
X524225Y54667D01*
G01X524126Y54979D02*
X524215Y54707D01*
G01X524737Y54546D02*
X524697Y54667D01*
G01X524599Y54979D02*
X524687Y54707D01*
G01X514821Y68855D02*
X514830Y68810D01*
X514856Y68783D01*
X514901Y68775D01*
G01X512443Y72001D02*
Y78891D01*
G01X513992Y51778D02*
Y52408D01*
G01X514070Y52059D02*
Y51778D01*
G01Y52341D02*
Y52140D01*
G01X514398Y52220D02*
Y52260D01*
G01X514477D02*
Y52206D01*
G01X514582Y52341D02*
Y52408D01*
G01X514792Y51778D02*
Y52341D01*
G01X514871D02*
Y51778D01*
G01X515081Y52408D02*
Y52341D01*
G01X515186Y51778D02*
Y52408D01*
G01X515265Y52073D02*
Y51778D01*
G01Y52408D02*
Y52153D01*
G01X515632Y51778D02*
Y52073D01*
G01Y52153D02*
Y52408D01*
G01X515711D02*
Y51778D01*
G01X515816Y52206D02*
Y52314D01*
G01X515894Y51778D02*
Y52301D01*
G01X515973Y52408D02*
Y51778D01*
G01X517420Y56275D02*
Y68775D01*
G01X517758D02*
Y92474D01*
G01X519341Y67775D02*
Y57275D01*
G01X523790Y53868D02*
Y55794D01*
G01Y68829D02*
Y70755D01*
G01X524490Y53869D02*
Y55795D01*
G01Y68829D02*
Y70755D01*
G01X524874Y54868D02*
Y54948D01*
G01X524933Y54546D02*
Y54938D01*
G01X524993Y55019D02*
Y54546D01*
G01X514385Y52180D02*
X514398Y52220D01*
G01X514477Y52206D02*
X514464Y52166D01*
G01X524038Y54707D02*
X524126Y54979D01*
G01X524028Y54667D02*
X523989Y54546D01*
G01X524510Y54707D02*
X524599Y54979D01*
G01X524500Y54667D02*
X524461Y54546D01*
G01X523930D02*
X524087Y55019D01*
G01X524402Y54546D02*
X524559Y55019D01*
G01X514464Y52166D02*
X514425Y52113D01*
G01X515816Y52314D02*
X515894Y52408D01*
G01Y52301D02*
X515816Y52206D01*
G01X524874Y54948D02*
X524933Y55019D01*
G01Y54938D02*
X524874Y54868D01*
G01X514359Y52153D02*
X514385Y52180D01*
G01X514425Y52113D02*
X514372Y52073D01*
G01X514320Y52140D02*
X514359Y52153D01*
G01X519341Y67775D02*
G03X518341Y68775I-1000J0D01*
G01Y56275D02*
G03X519341Y57275I0J1000D01*
G01X573848Y43930D02*
X514821D01*
G01X516758Y44408D02*
X555144D01*
G01X516758Y105171D02*
Y44408D01*
G01X517758D02*
Y56275D01*
G01X518385Y105171D02*
Y44408D01*
G01X519799Y105171D02*
Y44408D01*
G01X536301Y79733D02*
X535601D01*
G01X527443D02*
X526743D01*
G01X536301Y79831D02*
X535601D01*
G01X527443D02*
X526743D01*
G01X536301Y79894D02*
X535601D01*
G01X527443D02*
X526743D01*
G01X536301Y79989D02*
X535601D01*
G01X527443D02*
X526743D01*
G01Y80205D02*
X527443D01*
G01X535601D02*
X536301D01*
G01X529695Y81032D02*
X530395D01*
G01Y81249D02*
X529695D01*
G01X530395Y81344D02*
X529695D01*
G01X530395Y81406D02*
X529695D01*
G01X530395Y81505D02*
X529695D01*
G01X530395Y82489D02*
X529695D01*
G01X530395Y82587D02*
X529695D01*
G01X530395Y82650D02*
X529695D01*
G01X530395Y82745D02*
X529695D01*
G01Y82961D02*
X530395D01*
G01X533348Y83788D02*
X532648D01*
G01Y84005D02*
X533348D01*
G01X532648Y84100D02*
X533348D01*
G01X532648Y84162D02*
X533348D01*
G01Y84260D02*
X532648D01*
G01X533348Y85245D02*
X532648D01*
G01X533348Y85343D02*
X532648D01*
G01Y85406D02*
X533348D01*
G01Y85501D02*
X532648D01*
G01X533348Y85717D02*
X532648D01*
G01X526743Y93237D02*
X527443D01*
G01X535601D02*
X536301D01*
G01Y93453D02*
X535601D01*
G01X527443D02*
X526743D01*
G01X536301Y93549D02*
X535601D01*
G01X527443D02*
X526743D01*
G01X536301Y93611D02*
X535601D01*
G01X527443D02*
X526743D01*
G01X536301Y93709D02*
X535601D01*
G01X527443D02*
X526743D01*
G01X536301Y94693D02*
X535601D01*
G01X527443D02*
X526743D01*
G01X536301Y94792D02*
X535601D01*
G01X527443D02*
X526743D01*
G01X536301Y94855D02*
X535601D01*
G01X527443D02*
X526743D01*
G01X536301Y94949D02*
X535601D01*
G01X527443D02*
X526743D01*
G01Y95166D02*
X527443D01*
G01X535601D02*
X536301D01*
G01X529695Y95993D02*
X530395D01*
G01Y96209D02*
X529695D01*
G01X530395Y96305D02*
X529695D01*
G01X530395Y96367D02*
X529695D01*
G01X530395Y96465D02*
X529695D01*
G01X530395Y97449D02*
X529695D01*
G01X530395Y97548D02*
X529695D01*
G01X530395Y97610D02*
X529695D01*
G01X530395Y97705D02*
X529695D01*
G01Y97922D02*
X530395D01*
G01X533348Y98749D02*
X532648D01*
G01Y98965D02*
X533348D01*
G01X532648Y99060D02*
X533348D01*
G01X532648Y99123D02*
X533348D01*
G01Y99221D02*
X532648D01*
G01X533348Y100205D02*
X532648D01*
G01X533348Y100304D02*
X532648D01*
G01Y100366D02*
X533348D01*
G01Y100461D02*
X532648D01*
G01X533348Y100678D02*
X532648D01*
G01X526361Y106958D02*
Y105958D01*
G01X526743Y93238D02*
Y95164D01*
G01X527443Y93239D02*
Y95165D01*
G01X527704Y105958D02*
Y106958D01*
G01X528516D02*
Y105958D01*
G01X528608D02*
Y106958D01*
G01X529094Y105958D02*
Y106958D01*
G01X529146Y105958D02*
Y106958D01*
G01X529553Y105958D02*
Y106958D01*
G01X529695Y81034D02*
Y82960D01*
G01Y95994D02*
Y97920D01*
G01X530395Y81034D02*
Y82960D01*
G01Y95995D02*
Y97921D01*
G01X530537Y106958D02*
Y105958D01*
G01X530949D02*
Y106958D01*
G01X531000Y105958D02*
Y106958D01*
G01X531482Y105958D02*
Y106958D01*
G01X531579Y105958D02*
Y106958D01*
G01X532231Y105958D02*
Y106958D01*
G01X532648Y83790D02*
Y85716D01*
G01Y98750D02*
Y100676D01*
G01X532998Y102336D02*
Y105171D01*
G01Y105958D02*
Y106958D01*
G01X533348Y83790D02*
Y85716D01*
G01Y98751D02*
Y100677D01*
G01X533731Y105958D02*
Y106958D01*
G01X534376Y102336D02*
Y105171D01*
G01X535601Y93238D02*
Y95164D01*
G01X526743Y78276D02*
X527443D01*
G01X535601D02*
X536301D01*
G01Y78493D02*
X535601D01*
G01X527443D02*
X526743D01*
G01X536301Y78588D02*
X535601D01*
G01X527443D02*
X526743D01*
G01X536301Y78650D02*
X535601D01*
G01X527443D02*
X526743D01*
G01X536301Y78749D02*
X535601D01*
G01X527443D02*
X526743D01*
G01Y78278D02*
Y80204D01*
G01X527443Y78278D02*
Y80204D01*
G01X535601Y78278D02*
Y80204D01*
G01X524490Y83788D02*
X523790D01*
G01Y84005D02*
X524490D01*
G01X523790Y84100D02*
X524490D01*
G01X523790Y84162D02*
X524490D01*
G01Y84260D02*
X523790D01*
G01X524490Y85245D02*
X523790D01*
G01X524490Y85343D02*
X523790D01*
G01Y85406D02*
X524490D01*
G01Y85501D02*
X523790D01*
G01X524490Y85717D02*
X523790D01*
G01X524663Y99901D02*
X524712Y99891D01*
G01X524663Y99840D02*
X524702Y99830D01*
G01X524712Y99891D02*
X524752Y99871D01*
G01X524702Y99830D02*
X524732Y99810D01*
G01X524752Y99871D02*
X524791Y99830D01*
G01X524712Y99438D02*
X524663Y99428D01*
G01X514901Y92474D02*
X514856Y92466D01*
X514830Y92439D01*
X514821Y92394D01*
G01X513821Y89474D02*
X514821D01*
G01Y90474D02*
X513821D01*
G01X514821Y91474D02*
X513821D01*
G01X518341Y92474D02*
X513821D01*
G01Y94974D02*
X512640D01*
G01Y96942D02*
X513821D01*
G01X514033Y96943D02*
X512640D01*
G01X524490Y98749D02*
X523790D01*
G01Y98965D02*
X524490D01*
G01X523790Y99060D02*
X524490D01*
G01X523790Y99123D02*
X524490D01*
G01Y99221D02*
X523790D01*
G01X524013Y99428D02*
X523954D01*
G01X524348D02*
X524289D01*
G01X524663D02*
X524427D01*
G01X525017D02*
X524958D01*
G01X524663Y99489D02*
X524486D01*
G01X524250Y99549D02*
X524053D01*
G01X524240Y99589D02*
X524063D01*
G01X524486Y99840D02*
X524663D01*
G01X524112Y99901D02*
X524191D01*
G01X524427D02*
X524663D01*
G01X524958D02*
X525017D01*
G01X524490Y100205D02*
X523790D01*
G01X524490Y100304D02*
X523790D01*
G01Y100366D02*
X524490D01*
G01Y100461D02*
X523790D01*
G01X524490Y100678D02*
X523790D01*
G01X522565Y102336D02*
X549337D01*
G01X514033Y104974D02*
X514821D01*
G01X514033Y105169D02*
X514593D01*
G01X514033Y105171D02*
X687837D01*
G01X513821Y105191D02*
X514033D01*
G01X514821Y105464D02*
X513821D01*
G01X687230Y105958D02*
X514640D01*
G01X688049Y106958D02*
X513821D01*
G01X524732Y99810D02*
X524752Y99780D01*
G01X524791Y99830D02*
X524811Y99790D01*
G01X524702Y99499D02*
X524663Y99489D01*
G01X524191Y99901D02*
X524348Y99428D01*
G01X524289D02*
X524250Y99549D01*
G01X524151Y99860D02*
X524240Y99589D01*
G01X524752Y99780D02*
X524761Y99740D01*
G01X524811Y99790D02*
X524820Y99740D01*
G01X512640Y104958D02*
Y94974D01*
G01X514033Y105753D02*
Y95186D01*
G01X515018Y105958D02*
Y106958D01*
G01X515518D02*
Y105958D01*
G01X516018D02*
Y106958D01*
G01X516518D02*
Y105958D01*
G01X517420Y92474D02*
Y105171D01*
G01X518742Y107942D02*
Y106958D01*
G01X519341Y104171D02*
Y93474D01*
G01X519742Y107942D02*
Y106958D01*
G01X522345Y105958D02*
Y106958D01*
G01X522565Y105171D02*
Y102336D01*
G01X523345Y106958D02*
Y105958D01*
G01X523790Y83790D02*
Y85716D01*
G01Y98750D02*
Y100676D01*
G01X524427Y99428D02*
Y99901D01*
G01X524486Y99489D02*
Y99840D01*
G01X524490Y83790D02*
Y85716D01*
G01Y98751D02*
Y100677D01*
G01X524761Y99740D02*
Y99589D01*
G01X524820Y99740D02*
Y99589D01*
G01X524899Y99750D02*
Y99830D01*
G01X524958Y99428D02*
Y99820D01*
G01X525017Y99901D02*
Y99428D01*
G01X525341Y106958D02*
Y105958D01*
G01X525345Y105171D02*
Y106958D01*
G01X524820Y99589D02*
X524811Y99539D01*
G01X524761Y99589D02*
X524752Y99549D01*
G01X524063Y99589D02*
X524151Y99860D01*
G01X524053Y99549D02*
X524013Y99428D01*
G01X523954D02*
X524112Y99901D01*
G01X524811Y99539D02*
X524791Y99499D01*
G01X524752Y99549D02*
X524732Y99519D01*
G01X524899Y99830D02*
X524958Y99901D01*
G01Y99820D02*
X524899Y99750D01*
G01X524791Y99499D02*
X524752Y99458D01*
G01X514033Y95186D02*
X513821Y94974D01*
G01X524732Y99519D02*
X524702Y99499D01*
G01X513821Y79687D02*
X512443Y78891D01*
G01X524752Y99458D02*
X524712Y99438D01*
G01X514640Y106958D02*
G03X512640Y104958I0J-2000D01*
G01X518341Y92474D02*
G03X519341Y93474I0J1000D01*
G01Y104171D02*
G03X518341Y105171I-1000J0D01*
G01X514640Y105958D02*
G03X514033Y105753I0J-1000D01*
G01X514909Y105958D02*
G03X514821Y105549I912J-410D01*
G01X515821Y107942D02*
G03X514048Y106869I-1J-2000D01*
G01X512443Y73970D02*
X513821D01*
G01Y76923D02*
X512443D01*
G01X514821Y77580D02*
X516758Y75643D01*
G01X519742Y107942D02*
X515821D01*
G01X522441Y871653D02*
Y845668D01*
G01Y871653D02*
Y845668D01*
G01X517323Y840550D02*
G03X522441Y845668I0J5118D01*
G01X517323Y840550D02*
G03X522441Y845668I0J5118D01*
G01X531428Y882703D02*
X531307Y882661D01*
G01X532490Y882703D02*
X532370Y882661D01*
G01X531428Y881153D02*
X531548Y881195D01*
G01X532490Y881153D02*
X532611Y881195D01*
G01X531428Y882912D02*
X531283Y882870D01*
G01X532490Y882912D02*
X532345Y882870D01*
G01X531428Y880944D02*
X531573Y880986D01*
G01X532490Y880944D02*
X532635Y880986D01*
G01X531307Y882661D02*
X531235Y882577D01*
G01X532370Y882661D02*
X532297Y882577D01*
G01X531548Y881195D02*
X531621Y881279D01*
G01X532611Y881195D02*
X532683Y881279D01*
G01X531283Y882870D02*
X531162Y882745D01*
G01X532345Y882870D02*
X532225Y882745D01*
G01X531573Y880986D02*
X531693Y881111D01*
G01X532635Y880986D02*
X532756Y881111D01*
G01X533263Y881279D02*
X533408Y881572D01*
G01Y881237D02*
X533263Y880944D01*
G01X531162Y882745D02*
X531090Y882619D01*
G01X532225Y882745D02*
X532152Y882619D01*
G01X531693Y881111D02*
X531766Y881237D01*
G01X532756Y881111D02*
X532828Y881237D01*
G01X531090Y882619D02*
X531041Y882451D01*
G01X532152Y882619D02*
X532104Y882451D01*
G01X531766Y881237D02*
X531814Y881405D01*
G01X532828Y881237D02*
X532877Y881405D01*
G01X531235Y882577D02*
X531138Y882326D01*
G01X531621Y881279D02*
X531718Y881530D01*
G01X532297Y882577D02*
X532200Y882326D01*
G01X532683Y881279D02*
X532780Y881530D01*
G01X531041Y882451D02*
X531017Y882326D01*
G01X531814Y881405D02*
X531838Y881530D01*
G01X532104Y882451D02*
X532080Y882326D01*
G01X532877Y881405D02*
X532901Y881530D01*
G01X534326Y882410D02*
X534422Y882912D01*
G01X534302Y882242D02*
X534084Y881111D01*
G01X534567Y882912D02*
X534181Y880944D01*
G01X529528Y892519D02*
Y875590D01*
G01Y892519D02*
Y875590D01*
G01X530993Y882116D02*
Y881740D01*
G01X531138Y882326D02*
X531114Y882075D01*
G01X531718Y881530D02*
X531742Y881781D01*
G01X532200Y882326D02*
X532176Y882075D01*
G01X532780Y881530D02*
X532804Y881781D01*
G01X531017Y882326D02*
X530993Y882116D01*
G01X531838Y881530D02*
X531863Y881740D01*
G01X532080Y882326D02*
X532056Y882116D01*
G01X532901Y881530D02*
X532925Y881740D01*
G01X531114Y881781D02*
X531138Y881530D01*
G01X531742Y882075D02*
X531718Y882326D01*
G01X532176Y881781D02*
X532200Y881530D01*
G01X532804Y882075D02*
X532780Y882326D01*
G01X531114Y882075D02*
Y881781D01*
G01X531594Y883464D02*
Y890845D01*
G01X531742Y881781D02*
Y882075D01*
G01X531863Y881740D02*
Y882116D01*
G01X532056D02*
Y881740D01*
G01X532176Y882075D02*
Y881781D01*
G01X532804D02*
Y882075D01*
G01X532925Y881740D02*
Y882116D01*
G01X533118Y880944D02*
Y882912D01*
G01X533263D02*
Y881279D01*
G01X533408Y881572D02*
Y881237D01*
G01X533760Y890845D02*
Y883464D01*
G01X534744D02*
Y892519D01*
G01X530993Y881740D02*
X531017Y881530D01*
G01X531863Y882116D02*
X531838Y882326D01*
G01X532056Y881740D02*
X532080Y881530D01*
G01X532925Y882116D02*
X532901Y882326D01*
G01X533987Y880944D02*
X533601Y882912D01*
G01X531017Y881530D02*
X531041Y881405D01*
G01X531838Y882326D02*
X531814Y882451D01*
G01X532080Y881530D02*
X532104Y881405D01*
G01X532901Y882326D02*
X532877Y882451D01*
G01X534084Y881111D02*
X533867Y882242D01*
G01X533746Y882912D02*
X533843Y882410D01*
G01X531138Y881530D02*
X531235Y881279D01*
G01X531718Y882326D02*
X531621Y882577D01*
G01X532200Y881530D02*
X532297Y881279D01*
G01X531041Y881405D02*
X531090Y881237D01*
G01X532104Y881405D02*
X532152Y881237D01*
G01X531814Y882451D02*
X531766Y882619D01*
G01X532877Y882451D02*
X532828Y882619D01*
G01X532780Y882326D02*
X532683Y882577D01*
G01X531090Y881237D02*
X531162Y881111D01*
G01X532152Y881237D02*
X532225Y881111D01*
G01X531766Y882619D02*
X531693Y882745D01*
G01X532828Y882619D02*
X532756Y882745D01*
G01X531235Y881279D02*
X531307Y881195D01*
G01X532297Y881279D02*
X532370Y881195D01*
G01X531621Y882577D02*
X531548Y882661D01*
G01X532683Y882577D02*
X532611Y882661D01*
G01X531162Y881111D02*
X531283Y880986D01*
G01X532225Y881111D02*
X532345Y880986D01*
G01X531693Y882745D02*
X531573Y882870D01*
G01X532756Y882745D02*
X532635Y882870D01*
G01X531283Y880986D02*
X531428Y880944D01*
G01X532345Y880986D02*
X532490Y880944D01*
G01X531573Y882870D02*
X531428Y882912D01*
G01X532635Y882870D02*
X532490Y882912D01*
G01X531307Y881195D02*
X531428Y881153D01*
G01X532370Y881195D02*
X532490Y881153D01*
G01X531548Y882661D02*
X531428Y882703D01*
G01X532611Y882661D02*
X532490Y882703D01*
G01X534181Y880944D02*
X533987D01*
G01X533263D02*
X533118D01*
G01X533867Y882242D02*
X534302D01*
G01X533843Y882410D02*
X534326D01*
G01X534422Y882912D02*
X534567D01*
G01X533601D02*
X533746D01*
G01X533118D02*
X533263D01*
G01X536909Y883464D02*
X534744D01*
G01X533760D02*
X531594D01*
G01X527559Y873621D02*
G03X529528Y875590I0J1969D01*
G01X527559Y873621D02*
G03X529528Y875590I0J1969D01*
G01X527559Y873621D02*
X524409D01*
G01X527559D02*
X524409D01*
G01D02*
G03X522441Y871653I1J-1969D01*
G01X524409Y873621D02*
G03X522441Y871653I1J-1969D01*
G01X533465Y897637D02*
X529528Y892519D01*
G01D02*
X533465Y897637D01*
G01X531594Y890845D02*
X533760D01*
G01X529528Y892519D02*
X709449D01*
G01X534744D02*
X536909D01*
G01X533465Y897637D02*
X705512D01*
G01X533465D02*
X705512D01*
G01X713780Y1028599D02*
X505118D01*
G01X516811Y1030764D02*
X515837Y1031486D01*
X515350Y1032208D01*
X514862Y1033651D01*
Y1036539D01*
X515350Y1037982D01*
X515837Y1038704D01*
X516811Y1039426D01*
X517785Y1038704D01*
X518273Y1037982D01*
X518760Y1036539D01*
Y1033651D01*
X518273Y1032208D01*
X517785Y1031486D01*
X516811Y1030764D01*
G01X524606D02*
X523632Y1031486D01*
X523145Y1032208D01*
X522658Y1033651D01*
Y1036539D01*
X523145Y1037982D01*
X523632Y1038704D01*
X524606Y1039426D01*
X525581Y1038704D01*
X526068Y1037982D01*
X526555Y1036539D01*
Y1033651D01*
X526068Y1032208D01*
X525581Y1031486D01*
X524606Y1030764D01*
G01X509016D02*
X508529D01*
Y1031486D01*
X509016Y1030764D01*
G01X516147Y2167300D02*
X511870D01*
X511157Y2162547D01*
X512583Y2163497D01*
X514009D01*
X515434Y2162547D01*
X516147Y2161596D01*
X516860Y2159695D01*
X516147Y2157793D01*
X515434Y2156843D01*
X514009Y2155892D01*
X512583D01*
X511157Y2156843D01*
X510444Y2157793D01*
G01X566170Y-698638D02*
X567613Y-699125D01*
X568335Y-700587D01*
X567613Y-702049D01*
X566170Y-702536D01*
X564726Y-702049D01*
X564004Y-701562D01*
X563283Y-700587D01*
X564004Y-699613D01*
X564726Y-699125D01*
X566170Y-698638D01*
X569057D01*
X570500Y-699125D01*
X571222Y-699613D01*
X571944Y-700587D01*
X571222Y-701562D01*
X570500Y-702049D01*
G01X571944Y-684997D02*
X568335Y-684509D01*
X566170Y-684022D01*
X564726Y-683535D01*
X563283Y-683048D01*
Y-686945D01*
G01X571944Y-677201D02*
X571222Y-678176D01*
X570500Y-678663D01*
X569057Y-679150D01*
X566170D01*
X564726Y-678663D01*
X564004Y-678176D01*
X563283Y-677201D01*
X564004Y-676227D01*
X564726Y-675740D01*
X566170Y-675253D01*
X569057D01*
X570500Y-675740D01*
X571222Y-676227D01*
X571944Y-677201D01*
G01X566137Y-625016D02*
X567581Y-625503D01*
X568303Y-626965D01*
X567581Y-628427D01*
X566137Y-628914D01*
X564694Y-628427D01*
X563972Y-627940D01*
X563250Y-626965D01*
X563972Y-625991D01*
X564694Y-625503D01*
X566137Y-625016D01*
X569024D01*
X570468Y-625503D01*
X571190Y-625991D01*
X571911Y-626965D01*
X571190Y-627940D01*
X570468Y-628427D01*
G01X571911Y-603579D02*
X571190Y-604554D01*
X570468Y-605041D01*
X569024Y-605528D01*
X566137D01*
X564694Y-605041D01*
X563972Y-604554D01*
X563250Y-603579D01*
X563972Y-602605D01*
X564694Y-602118D01*
X566137Y-601631D01*
X569024D01*
X570468Y-602118D01*
X571190Y-602605D01*
X571911Y-603579D01*
G01Y-611375D02*
X571190Y-612349D01*
X570468Y-612836D01*
X569024Y-613323D01*
X566137D01*
X564694Y-612836D01*
X563972Y-612349D01*
X563250Y-611375D01*
X563972Y-610400D01*
X564694Y-609913D01*
X566137Y-609426D01*
X569024D01*
X570468Y-609913D01*
X571190Y-610400D01*
X571911Y-611375D01*
G01X562124Y-460419D02*
X561149Y-459697D01*
X560662Y-458975D01*
Y-458254D01*
X561149Y-457532D01*
X562124Y-456810D01*
X563098D01*
X564072Y-457532D01*
X564559Y-458254D01*
Y-458975D01*
X564072Y-459697D01*
X563098Y-460419D01*
G01X564338Y-436739D02*
X563363Y-436017D01*
X562876Y-435295D01*
X562389Y-433851D01*
Y-430964D01*
X562876Y-429521D01*
X563363Y-428799D01*
X564338Y-428077D01*
X565312Y-428799D01*
X565799Y-429521D01*
X566287Y-430964D01*
Y-433851D01*
X565799Y-435295D01*
X565312Y-436017D01*
X564338Y-436739D01*
G01X560175Y-462584D02*
X561149Y-461141D01*
X562124Y-460419D01*
X563098D01*
X564072Y-461141D01*
G01X565047Y-463306D02*
X564072Y-464750D01*
X563098Y-465471D01*
X562124D01*
G01D02*
X561149Y-464750D01*
G01D02*
X560175Y-463306D01*
Y-462584D01*
G01X564072Y-461141D02*
X565047Y-462584D01*
Y-463306D01*
G01X545071Y-458254D02*
X545559Y-457532D01*
X546533Y-456810D01*
X547507D01*
X548482Y-457532D01*
X548969Y-458254D01*
Y-459697D01*
X548482Y-460419D01*
G01X550696Y-430964D02*
X550209Y-432408D01*
X548747Y-433130D01*
X547285Y-432408D01*
X546798Y-430964D01*
X547285Y-429521D01*
X547773Y-428799D01*
X548747Y-428077D01*
X549722Y-428799D01*
X550209Y-429521D01*
X550696Y-430964D01*
Y-433851D01*
X550209Y-435295D01*
X549722Y-436017D01*
X548747Y-436739D01*
X547773Y-436017D01*
X547285Y-435295D01*
G01X556543Y-436739D02*
X556056D01*
Y-436017D01*
X556543Y-436739D01*
G01X540952Y-428077D02*
Y-436739D01*
G01X548482Y-460419D02*
X546533Y-461863D01*
X545559Y-463306D01*
X545071Y-465471D01*
X548969D01*
G01X553354D02*
X556277Y-459697D01*
G01X553354D02*
X556277Y-465471D01*
G01X565540Y-407884D02*
X564565Y-407162D01*
X564078Y-406440D01*
X563591Y-404997D01*
Y-402110D01*
X564078Y-400666D01*
X564565Y-399944D01*
X565540Y-399222D01*
X566515Y-399944D01*
X567002Y-400666D01*
X567489Y-402110D01*
Y-404997D01*
X567002Y-406440D01*
X566515Y-407162D01*
X565540Y-407884D01*
G01X543616Y-402831D02*
X541667Y-404275D01*
X540693Y-405718D01*
X540206Y-407884D01*
X544103D01*
G01X540206Y-400666D02*
X540693Y-399944D01*
X541667Y-399222D01*
X542641D01*
X543616Y-399944D01*
X544103Y-400666D01*
Y-402110D01*
X543616Y-402831D01*
G01X557744Y-407884D02*
X557257D01*
Y-407162D01*
X557744Y-407884D01*
G01X551411D02*
Y-399222D01*
X548001Y-405718D01*
X552385D01*
G01X567483Y-89785D02*
Y-98447D01*
G01Y-96281D02*
X566509Y-97725D01*
X565534Y-98447D01*
X564560Y-97725D01*
X563585Y-96281D01*
Y-94838D01*
X564560Y-93394D01*
X565534Y-92672D01*
X566509Y-93394D01*
X567483Y-94838D01*
G01X542148Y-98447D02*
Y-91229D01*
X543123Y-89785D01*
X543610D01*
X544097Y-90507D01*
G01X549944Y-92672D02*
Y-98447D01*
G01X559200Y-97003D02*
X558713Y-97725D01*
X557739Y-98447D01*
X556765Y-97725D01*
X555790Y-96281D01*
Y-94838D01*
X556765Y-93394D01*
X557739Y-92672D01*
X558713Y-93394D01*
X559200Y-94838D01*
X555790D01*
G01X549944Y-89785D02*
Y-90507D01*
G01X541174Y-93394D02*
X543123D01*
G01X564868Y-39469D02*
X561034D01*
G01X564671Y-39154D02*
X561034D01*
G01X560201Y-34338D02*
X560135D01*
G01X568876Y-33775D02*
X560693D01*
G01X564868Y-33249D02*
X561034D01*
G01X568862Y-33102D02*
X560693D01*
G01Y-32967D02*
X568862D01*
G01X560693Y-30829D02*
X568862D01*
G01Y-30744D02*
X560693D01*
G01X568862Y-31261D02*
X560693Y-31255D01*
G01X568876Y-33775D02*
X568870Y-33744D01*
X568866Y-33713D01*
X568863Y-33682D01*
G01Y-33663D02*
X568866Y-33701D01*
X568870Y-33738D01*
X568876Y-33775D01*
G01X568863Y-33682D02*
X568862Y-33647D01*
G01Y-33621D02*
X568863Y-33663D01*
G01X560443Y-38879D02*
Y-33339D01*
G01X560693Y-17548D02*
Y-33845D01*
G01X561665Y-35399D02*
Y-37336D01*
G01X565262Y-33339D02*
Y-38564D01*
G01X565459Y-33839D02*
Y-38879D01*
G01X568863Y-33682D02*
Y-33663D01*
G01X568862Y-17548D02*
Y-33647D01*
G01X560665Y-38336D02*
G03X561665Y-37336I0J1000D01*
G01X564671Y-39154D02*
G03X565262Y-38564I0J591D01*
G01X564868Y-39469D02*
G03X565459Y-38879I0J591D01*
G01X560443D02*
G03X561034Y-39469I591J1D01*
G01X560443Y-38564D02*
G03X561034Y-39154I591J1D01*
G01X561665Y-35399D02*
G03X560665Y-34399I-1000J0D01*
G01X565262Y-33339D02*
G03X564671Y-32749I-591J-1D01*
G01X561034D02*
G03X560443Y-33339I0J-591D01*
G01X561034Y-33249D02*
G03X560443Y-33839I0J-591D01*
G01X565262D02*
G03X564671Y-33249I-591J-1D01*
G01X565459Y-33839D02*
G03X564868Y-33249I-591J-1D01*
G01X560201Y-34338D02*
G03X560693Y-33845I0J492D01*
G01X560193Y-32016D02*
G03X560693Y-31524I8J492D01*
G01X568876Y-33775D02*
G03X569612Y-34378I734J145D01*
G01D02*
G03X570348Y-33775I2J748D01*
G01X569612Y-32016D02*
G03X570362Y-31261I2J748D01*
G01X568863D02*
G03X569612Y-32016I748J-7D01*
G01X554563Y-31255D02*
X546394Y-31261D01*
G01X572367Y-42635D02*
X542889D01*
G01X571767Y-41435D02*
X543489D01*
G01X554222Y-39469D02*
X550388D01*
G01X554026Y-39154D02*
X549798D01*
G01X560665Y-38336D02*
X557394D01*
G01Y-34399D02*
X560665D01*
G01X555121Y-34338D02*
X555055D01*
G01X554563Y-33775D02*
X546380D01*
G01X544908D02*
X536710D01*
G01X554222Y-33249D02*
X550388D01*
G01X554563Y-33102D02*
X546394D01*
G01X544894D02*
X536724D01*
G01Y-32967D02*
X544894D01*
G01X546394D02*
X554563D01*
G01X600435Y-32749D02*
X558128D01*
G01X556613Y-32023D02*
X558643D01*
G01X544893Y-31261D02*
X536725D01*
G01X536724Y-30829D02*
X544894D01*
G01X546394D02*
X554563D01*
G01Y-30744D02*
X546394D01*
G01X544894D02*
X536724D01*
G01X600435Y-28812D02*
X558128D01*
G01X541767Y-41928D02*
X542181Y-42342D01*
G01X544908Y-33775D02*
X544902Y-33744D01*
X544898Y-33713D01*
X544895Y-33682D01*
G01Y-33663D02*
X544898Y-33701D01*
X544902Y-33738D01*
X544908Y-33775D01*
G01X544895Y-33682D02*
X544894Y-33647D01*
G01Y-33621D02*
X544895Y-33663D01*
G01X558128Y-32749D02*
X558133Y-42635D01*
G01X536724Y-33647D02*
Y-17548D01*
G01Y-33663D02*
Y-33682D01*
G01X538239Y-34319D02*
Y-32749D01*
G01X538859D02*
Y-34319D01*
G01X540974Y-40398D02*
Y-41832D01*
G01X541289Y-32749D02*
Y-34319D01*
G01X544895Y-33663D02*
Y-33682D01*
G01X544894Y-17548D02*
Y-33647D01*
G01X546394D02*
Y-17548D01*
G01X546393Y-33663D02*
Y-33682D01*
G01X549798Y-39154D02*
Y-33339D01*
G01X554563Y-17548D02*
Y-33845D01*
G01X554616Y-33339D02*
Y-38564D01*
G01X554813Y-33839D02*
Y-38879D01*
G01X555563Y-22238D02*
Y-31524D01*
G01X555613Y-33023D02*
Y-33845D01*
G01X557128Y-42635D02*
Y-32749D01*
G01Y-28812D02*
Y105958D01*
G01X557394Y-34399D02*
Y-38336D01*
G01X558128Y-42635D02*
Y-32749D01*
G01Y-28812D02*
Y105958D01*
G01X559128Y-38336D02*
Y-34399D01*
G01X559643Y-33023D02*
Y-33845D01*
G01X559693Y-22238D02*
Y-31524D01*
G01X558135Y-14225D02*
X558128Y-28812D01*
G01X536724Y-33663D02*
Y-33621D01*
G01X546393Y-33663D02*
X546394Y-33621D01*
G01X536724Y-33647D02*
Y-33682D01*
G01X546394Y-33647D02*
X546393Y-33682D01*
G01X536724D02*
X536721Y-33713D01*
X536717Y-33744D01*
X536710Y-33775D01*
G01X546393Y-33682D02*
X546390Y-33713D01*
X546386Y-33744D01*
X546380Y-33775D01*
G01X536710D02*
X536717Y-33738D01*
X536721Y-33701D01*
X536724Y-33663D01*
G01X546380Y-33775D02*
X546386Y-33738D01*
X546390Y-33701D01*
X546393Y-33663D01*
G01X542181Y-42342D02*
G03X542889Y-42635I707J707D01*
G01X541767Y-41928D02*
G03X541060Y-41635I-707J-707D01*
G01X540974Y-40440D02*
G03X539974Y-39440I-1000J0D01*
G01X542530Y-40670D02*
G03X543489Y-41435I959J219D01*
G01X540974Y-40398D02*
G03X540308Y-39467I-984J0D01*
G01X542530Y-40670D02*
G03X540974Y-40845I-768J-173D01*
G01X535974Y-34378D02*
G03X536710Y-33775I2J748D01*
G01X535974Y-32016D02*
G03X536724Y-31261I2J748D01*
G01X554222Y-39469D02*
G03X554813Y-38879I1J590D01*
G01X554026Y-39154D02*
G03X554616Y-38564I0J590D01*
G01X549798Y-38879D02*
G03X550388Y-39469I590J0D01*
G01X544908Y-33775D02*
G03X545644Y-34378I734J145D01*
G01D02*
G03X546380Y-33775I2J748D01*
G01X550388Y-32749D02*
G03X549798Y-33339I0J-590D01*
G01X550388Y-33249D02*
G03X549798Y-33839I0J-590D01*
G01X554616Y-33339D02*
G03X554026Y-32749I-590J0D01*
G01X554813Y-33839D02*
G03X554222Y-33249I-590J0D01*
G01X554616Y-33839D02*
G03X554026Y-33249I-590J0D01*
G01X554563Y-33845D02*
G03X555055Y-34338I492J-1D01*
G01X555121D02*
G03X555613Y-33845I0J492D01*
G01X545644Y-32016D02*
G03X546394Y-31261I2J748D01*
G01X544894D02*
G03X545644Y-32016I748J-7D01*
G01X555063D02*
G03X555563Y-31524I8J492D01*
G01X554563D02*
G03X555063Y-32016I492J0D01*
G01X559643Y-33845D02*
G03X560135Y-34338I492J-1D01*
G01X556613Y-32023D02*
G03X555613Y-33023I0J-1000D01*
G01X559643D02*
G03X558643Y-32023I-1000J0D01*
G01X559693Y-31524D02*
G03X560193Y-32016I492J0D01*
G01X561480Y-16798D02*
X561328Y-16813D01*
X561180Y-16857D01*
X561045Y-16929D01*
X560924Y-17028D01*
X560826Y-17146D01*
X560754Y-17281D01*
X560709Y-17427D01*
X560693Y-17582D01*
G01X563788Y-16904D02*
X563630Y-16918D01*
X563478Y-16958D01*
X563339Y-17023D01*
X563216Y-17112D01*
X563119Y-17218D01*
X563048Y-17341D01*
G01X567066Y-18862D02*
X562489D01*
G01Y-18845D02*
X567066D01*
G01X568862Y-18516D02*
X560693D01*
G01Y-18481D02*
X568862D01*
G01Y-18138D02*
X560693D01*
G01Y-18104D02*
X568862D01*
G01X562902Y-17890D02*
X566654D01*
G01Y-17679D02*
X562902D01*
G01X570732Y-17318D02*
X565811D01*
G01X563788Y-17116D02*
X565768D01*
G01Y-16904D02*
X563788D01*
G01X561480Y-16798D02*
X568075D01*
G01Y-16764D02*
X561480D01*
G01X570732Y-14786D02*
X565811D01*
G01Y-14307D02*
X570732D01*
G01Y-9699D02*
X565811D01*
G01Y-9220D02*
X570732D01*
G01X565811Y-6688D02*
X570732D01*
G01Y-1570D02*
X565811D01*
G01X570732Y962D02*
X565811D01*
G01Y1441D02*
X570732D01*
G01Y6049D02*
X565811D01*
G01X565768Y-17116D02*
X565926Y-17129D01*
X566078Y-17170D01*
X566217Y-17234D01*
X566340Y-17323D01*
X566437Y-17430D01*
X566507Y-17553D01*
G01X568075Y-16764D02*
X568228Y-16779D01*
X568375Y-16823D01*
X568511Y-16895D01*
X568632Y-16994D01*
X568729Y-17112D01*
X568802Y-17247D01*
X568847Y-17393D01*
X568862Y-17548D01*
G01X566507Y-17341D02*
X566438Y-17220D01*
X566342Y-17114D01*
X566222Y-17025D01*
X566080Y-16959D01*
X565929Y-16918D01*
X565768Y-16904D01*
G01X566654Y-17890D02*
X566791Y-18195D01*
X566928Y-18522D01*
X567066Y-18862D01*
G01X566507Y-17553D02*
X566654Y-17890D01*
G01Y-17679D02*
X566507Y-17341D01*
G01X567066Y-18845D02*
X566928Y-18437D01*
X566791Y-18044D01*
X566654Y-17679D01*
G01X568862Y-17582D02*
X568847Y-17430D01*
X568803Y-17284D01*
X568731Y-17149D01*
X568632Y-17028D01*
X568513Y-16931D01*
X568378Y-16858D01*
X568231Y-16814D01*
X568075Y-16798D01*
G01X561480D02*
Y-16764D01*
G01X562256Y-12273D02*
Y-16178D01*
G01X562489Y-18862D02*
Y-18845D01*
G01X562569Y-9725D02*
Y-13990D01*
G01X562902Y-17679D02*
Y-17890D01*
G01X563048Y-17553D02*
Y-17341D01*
G01X563640Y-9060D02*
Y-14934D01*
G01X563788Y-16904D02*
Y-17116D01*
G01X565768D02*
Y-16904D01*
G01X565811Y9060D02*
Y-1570D01*
G01Y-6688D02*
Y-17318D01*
G01X566507Y-17341D02*
Y-17553D01*
G01X566654Y-17890D02*
Y-17679D01*
G01X567066Y-18845D02*
Y-18862D01*
G01X568075Y-16764D02*
Y-16798D01*
G01X560693Y-17548D02*
X560708Y-17396D01*
X560752Y-17249D01*
X560825Y-17114D01*
X560924Y-16994D01*
X561043Y-16896D01*
X561178Y-16824D01*
X561325Y-16779D01*
X561480Y-16764D01*
G01X562902Y-17679D02*
X562765Y-18044D01*
X562627Y-18437D01*
X562489Y-18845D01*
G01Y-18862D02*
X562627Y-18522D01*
X562765Y-18195D01*
X562902Y-17890D01*
G01X563048Y-17341D02*
X562902Y-17679D01*
G01Y-17890D02*
X563048Y-17553D01*
G01D02*
X563117Y-17432D01*
X563214Y-17325D01*
X563334Y-17237D01*
X563475Y-17170D01*
X563627Y-17130D01*
X563788Y-17116D01*
G01X562256Y-12273D02*
G03X561256Y-11273I-1000J0D01*
G01Y-17178D02*
G03X562256Y-16178I0J1000D01*
G01X562640Y-15934D02*
G03X563640Y-14934I0J1000D01*
G01Y-9060D02*
G03X562640Y-8060I-1000J0D01*
G01X562509Y-14327D02*
G03X562569Y-13990I-924J338D01*
G01Y-9725D02*
G03X561585Y-8741I-984J0D01*
G01X560693Y-24077D02*
X568862D01*
G01Y-23942D02*
X560693D01*
G01X568835Y-23756D02*
X560720D01*
G01Y-23671D02*
X568835D01*
G01X560855Y-23348D02*
X568700D01*
G01Y-23331D02*
X560855D01*
G01X560693Y-23097D02*
X568862D01*
G01Y-23063D02*
X560693D01*
G01X568815Y-23615D02*
X568700Y-23331D01*
G01X567066Y-18862D02*
X568700Y-23348D01*
G01Y-23331D02*
X567066Y-18845D01*
G01X568700Y-23348D02*
X568815Y-23689D01*
G01D02*
X568822Y-23711D01*
X568829Y-23734D01*
X568835Y-23756D01*
G01Y-23671D02*
X568829Y-23652D01*
X568822Y-23633D01*
X568815Y-23615D01*
G01X568835Y-23756D02*
X568843Y-23787D01*
X568850Y-23821D01*
X568855Y-23853D01*
X568859Y-23888D01*
X568861Y-23923D01*
X568862Y-23958D01*
G01Y-23872D02*
Y-23840D01*
X568859Y-23805D01*
X568856Y-23773D01*
X568850Y-23739D01*
X568843Y-23705D01*
X568835Y-23671D01*
G01X560720Y-23756D02*
Y-23671D01*
G01X560741Y-23615D02*
Y-23689D01*
G01X560855Y-23331D02*
Y-23339D01*
G01D02*
Y-23348D01*
G01X568815Y-23689D02*
Y-23615D01*
G01X568835Y-23671D02*
Y-23756D01*
G01X568700Y-23348D02*
Y-23331D01*
G01X560693Y-23958D02*
X560694Y-23925D01*
X560696Y-23891D01*
X560700Y-23858D01*
X560705Y-23824D01*
X560712Y-23790D01*
X560720Y-23756D01*
G01Y-23671D02*
X560713Y-23702D01*
X560706Y-23736D01*
X560700Y-23768D01*
X560696Y-23803D01*
X560694Y-23838D01*
X560693Y-23872D01*
G01X560720Y-23756D02*
X560727Y-23734D01*
X560733Y-23711D01*
X560741Y-23689D01*
G01D02*
X560855Y-23348D01*
G01X562489Y-18845D02*
X560855Y-23331D01*
G01Y-23348D02*
X562489Y-18862D01*
G01X560741Y-23615D02*
X560733Y-23633D01*
X560727Y-23652D01*
X560720Y-23671D01*
G01X560855Y-23331D02*
X560741Y-23615D01*
G01X547181Y-16798D02*
X547028Y-16813D01*
X546881Y-16857D01*
X546746Y-16929D01*
X546624Y-17028D01*
X546527Y-17146D01*
X546454Y-17281D01*
X546409Y-17427D01*
X546394Y-17582D01*
G01X537512Y-16798D02*
X537359Y-16813D01*
X537212Y-16857D01*
X537076Y-16929D01*
X536955Y-17028D01*
X536857Y-17146D01*
X536785Y-17281D01*
X536740Y-17427D01*
X536724Y-17582D01*
G01X549489Y-16904D02*
X549330Y-16918D01*
X549178Y-16958D01*
X549039Y-17023D01*
X548917Y-17112D01*
X548819Y-17218D01*
X548749Y-17341D01*
G01X537512Y-16904D02*
X537359Y-16917D01*
X537212Y-16954D01*
X537076Y-17015D01*
X536955Y-17099D01*
X536857Y-17199D01*
X536785Y-17313D01*
X536740Y-17437D01*
X536724Y-17568D01*
G01X552767Y-18862D02*
X548190D01*
G01X544894D02*
X536724D01*
G01Y-18845D02*
X544894D01*
G01X548190D02*
X552767D01*
G01X554563Y-18516D02*
X546394D01*
G01X544894D02*
X536724D01*
G01Y-18481D02*
X544894D01*
G01X546394D02*
X554563D01*
G01Y-18138D02*
X546394D01*
G01X544894D02*
X536724D01*
G01Y-18104D02*
X544894D01*
G01X546394D02*
X554563D01*
G01X536724Y-17890D02*
X544894D01*
G01X548603D02*
X552354D01*
G01Y-17679D02*
X548603D01*
G01X544894D02*
X536724D01*
G01X549445Y-17318D02*
X544524D01*
G01X557396Y-17178D02*
X561256D01*
G01X537512Y-17116D02*
X544106D01*
G01X549489D02*
X551469D01*
G01Y-16904D02*
X549489D01*
G01X544106D02*
X537512D01*
G01Y-16798D02*
X544106D01*
G01X547181D02*
X553776D01*
G01Y-16764D02*
X547181D01*
G01X544106D02*
X537512D01*
G01X557396Y-15934D02*
X562640D01*
G01X549445Y-14786D02*
X544524D01*
G01Y-14307D02*
X549445D01*
G01X561256Y-11273D02*
X557396D01*
G01X549445Y-9699D02*
X544524D01*
G01Y-9220D02*
X549445D01*
G01X561585Y-8741D02*
X553672D01*
G01X562640Y-8060D02*
X557396D01*
G01X544524Y-6688D02*
X549445D01*
G01X558128Y-2525D02*
X557128D01*
G01Y-1874D02*
X558128D01*
G01X557128Y-1777D02*
X558128D01*
G01X549445Y-1570D02*
X544524D01*
G01X557128Y-1273D02*
X558128D01*
G01X557128Y-1244D02*
X558128D01*
G01Y-832D02*
X557128D01*
G01Y153D02*
X558128D01*
G01X557128Y560D02*
X558128D01*
G01X557128Y590D02*
X558128D01*
G01X549445Y962D02*
X544524D01*
G01X557128Y1097D02*
X558128D01*
G01Y1190D02*
X557128D01*
G01X544524Y1441D02*
X549445D01*
G01X558128Y1845D02*
X557128D01*
G01X558128Y3845D02*
X557128D01*
G01X558128Y4436D02*
X557128D01*
G01X549445Y6049D02*
X544524D01*
G01X544106Y-17116D02*
X544259Y-17128D01*
X544407Y-17166D01*
X544542Y-17227D01*
X544663Y-17310D01*
X544761Y-17410D01*
X544833Y-17525D01*
X544878Y-17649D01*
X544894Y-17780D01*
G01X551469Y-17116D02*
X551627Y-17129D01*
X551779Y-17170D01*
X551918Y-17234D01*
X552041Y-17323D01*
X552138Y-17430D01*
X552208Y-17553D01*
G01X544106Y-16764D02*
X544259Y-16779D01*
X544407Y-16823D01*
X544542Y-16895D01*
X544663Y-16994D01*
X544761Y-17112D01*
X544833Y-17247D01*
X544878Y-17393D01*
X544894Y-17548D01*
G01X553776Y-16764D02*
X553929Y-16779D01*
X554076Y-16823D01*
X554211Y-16895D01*
X554333Y-16994D01*
X554430Y-17112D01*
X554503Y-17247D01*
X554548Y-17393D01*
X554563Y-17548D01*
G01X552208Y-17341D02*
X552139Y-17220D01*
X552043Y-17114D01*
X551922Y-17025D01*
X551781Y-16959D01*
X551630Y-16918D01*
X551469Y-16904D01*
G01X552354Y-17890D02*
X552492Y-18195D01*
X552629Y-18522D01*
X552767Y-18862D01*
G01X552208Y-17553D02*
X552354Y-17890D01*
G01Y-17679D02*
X552208Y-17341D01*
G01X552747Y-14327D02*
X555504Y-21902D01*
G01X552767Y-18845D02*
X552629Y-18437D01*
X552492Y-18044D01*
X552354Y-17679D01*
G01X544894Y-17582D02*
X544879Y-17430D01*
X544835Y-17284D01*
X544762Y-17149D01*
X544663Y-17028D01*
X544544Y-16931D01*
X544409Y-16858D01*
X544262Y-16814D01*
X544106Y-16798D01*
G01X554563Y-17582D02*
X554548Y-17430D01*
X554504Y-17284D01*
X554431Y-17149D01*
X554333Y-17028D01*
X554214Y-16931D01*
X554078Y-16858D01*
X553931Y-16814D01*
X553776Y-16798D01*
G01X544894Y-17568D02*
X544879Y-17439D01*
X544835Y-17315D01*
X544762Y-17201D01*
X544663Y-17099D01*
X544544Y-17016D01*
X544409Y-16955D01*
X544262Y-16917D01*
X544106Y-16904D01*
G01X537512D02*
Y-17116D01*
G01Y-16798D02*
Y-16764D01*
G01X544106D02*
Y-16798D01*
G01Y-17116D02*
Y-16904D01*
G01X544524Y9060D02*
Y-1570D01*
G01Y-6688D02*
Y-17318D01*
G01X547181Y-16798D02*
Y-16764D01*
G01X548190Y-18862D02*
Y-18845D01*
G01X548603Y-17679D02*
Y-17890D01*
G01X548749Y-17553D02*
Y-17341D01*
G01X549445Y-17318D02*
Y-6688D01*
G01Y-1570D02*
Y9060D01*
G01X549489Y-16904D02*
Y-17116D01*
G01X551469D02*
Y-16904D01*
G01X552208Y-17341D02*
Y-17553D01*
G01X552354Y-17890D02*
Y-17679D01*
G01X552687Y-9725D02*
Y-13990D01*
G01X552767Y-18845D02*
Y-18862D01*
G01X553776Y-16764D02*
Y-16798D01*
G01X557396Y-8060D02*
Y-17178D01*
G01X558133Y31917D02*
X558135Y-6351D01*
G01X558146Y-14225D02*
Y-6351D01*
G01X559128Y-15934D02*
Y-8060D01*
G01X559132Y-11273D02*
Y-17178D01*
G01X536724Y-17548D02*
X536740Y-17396D01*
X536784Y-17249D01*
X536856Y-17114D01*
X536955Y-16994D01*
X537074Y-16896D01*
X537209Y-16824D01*
X537356Y-16779D01*
X537512Y-16764D01*
G01X536724Y-17780D02*
X536740Y-17651D01*
X536784Y-17527D01*
X536856Y-17412D01*
X536955Y-17310D01*
X537074Y-17228D01*
X537209Y-17167D01*
X537356Y-17129D01*
X537512Y-17116D01*
G01X546394Y-17548D02*
X546409Y-17396D01*
X546453Y-17249D01*
X546526Y-17114D01*
X546624Y-16994D01*
X546743Y-16896D01*
X546879Y-16824D01*
X547026Y-16779D01*
X547181Y-16764D01*
G01X562509Y-14327D02*
X559752Y-21902D01*
G01X548603Y-17679D02*
X548465Y-18044D01*
X548328Y-18437D01*
X548190Y-18845D01*
G01Y-18862D02*
X548328Y-18522D01*
X548465Y-18195D01*
X548603Y-17890D01*
G01X548749Y-17341D02*
X548603Y-17679D01*
G01Y-17890D02*
X548749Y-17553D01*
G01D02*
X548818Y-17432D01*
X548915Y-17325D01*
X549035Y-17237D01*
X549176Y-17170D01*
X549328Y-17130D01*
X549489Y-17116D01*
G01X559752Y-21902D02*
G03X559693Y-22238I925J-336D01*
G01X553672Y-8741D02*
G03X552687Y-9725I-1J-984D01*
G01Y-13990D02*
G03X552747Y-14327I984J1D01*
G01X555563Y-22238D02*
G03X555504Y-21902I-984J0D01*
G01X536724Y-24077D02*
X544894D01*
G01X546394D02*
X554563D01*
G01Y-23942D02*
X546394D01*
G01X544894D02*
X536724D01*
G01X554535Y-23756D02*
X546421D01*
G01X544894D02*
X536724D01*
G01Y-23671D02*
X544894D01*
G01X546421D02*
X554535D01*
G01X536724Y-23348D02*
X544894D01*
G01X546556D02*
X554401D01*
G01Y-23331D02*
X546556D01*
G01X544894D02*
X536724D01*
G01Y-23097D02*
X544894D01*
G01X546394D02*
X554563D01*
G01X558128Y-23095D02*
X600435D01*
G01X554563Y-23063D02*
X546394D01*
G01X544894D02*
X536724D01*
G01X600435Y-22468D02*
X558128D01*
G01X554516Y-23615D02*
X554401Y-23331D01*
G01X552767Y-18862D02*
X554401Y-23348D01*
G01Y-23331D02*
X552767Y-18845D01*
G01X554401Y-23348D02*
X554516Y-23689D01*
G01D02*
X554523Y-23711D01*
X554530Y-23734D01*
X554535Y-23756D01*
G01Y-23671D02*
X554530Y-23652D01*
X554523Y-23633D01*
X554516Y-23615D01*
G01X554535Y-23756D02*
X554544Y-23787D01*
X554551Y-23821D01*
X554556Y-23853D01*
X554560Y-23888D01*
X554562Y-23923D01*
X554563Y-23958D01*
G01Y-23872D02*
Y-23840D01*
X554560Y-23805D01*
X554557Y-23773D01*
X554551Y-23739D01*
X554544Y-23705D01*
X554535Y-23671D01*
G01X546421Y-23756D02*
Y-23671D01*
G01X546441Y-23615D02*
Y-23689D01*
G01X546556Y-23331D02*
Y-23339D01*
G01D02*
Y-23348D01*
G01X554516Y-23689D02*
Y-23615D01*
G01X554535Y-23671D02*
Y-23756D01*
G01X554401Y-23348D02*
Y-23331D01*
G01X546394Y-23958D02*
Y-23925D01*
X546397Y-23891D01*
X546400Y-23858D01*
X546406Y-23824D01*
X546413Y-23790D01*
X546421Y-23756D01*
G01Y-23671D02*
X546413Y-23702D01*
X546406Y-23736D01*
X546401Y-23768D01*
X546397Y-23803D01*
X546394Y-23838D01*
Y-23872D01*
G01X546421Y-23756D02*
X546428Y-23734D01*
X546434Y-23711D01*
X546441Y-23689D01*
G01D02*
X546556Y-23348D01*
G01X548190Y-18845D02*
X546556Y-23331D01*
G01Y-23348D02*
X548190Y-18862D01*
G01X546441Y-23615D02*
X546434Y-23633D01*
X546428Y-23652D01*
X546421Y-23671D01*
G01X546556Y-23331D02*
X546441Y-23615D01*
G01X596876Y12019D02*
X561640D01*
G01X594711Y14955D02*
X563805D01*
G01X567097Y18393D02*
X567797D01*
G01Y21371D02*
X567097D01*
G01X567797Y24336D02*
X567097D01*
G01X567797Y24561D02*
X567097D01*
G01X569747Y38588D02*
X569466Y38547D01*
X569233Y38441D01*
X569071Y38279D01*
X569014Y38088D01*
G01X563805Y34353D02*
X594711D01*
G01Y35141D02*
X563805D01*
G01X596876Y35267D02*
X561640D01*
G01X572092Y36767D02*
X561640D01*
G01X571407Y37588D02*
X569514D01*
G01X569380Y38588D02*
X573848D01*
G01X571014Y39392D02*
X569045D01*
G01X562256Y43759D02*
Y39853D01*
G01X563640Y19242D02*
Y25116D01*
G01X563805Y35141D02*
Y14955D01*
G01X567097Y24561D02*
Y18393D01*
G01X567797Y24561D02*
Y18393D01*
G01X569014Y43930D02*
Y38088D01*
G01X569045Y44408D02*
Y36767D01*
G01X569014Y38088D02*
X569045Y38288D01*
X569128Y38447D01*
X569248Y38552D01*
X569380Y38588D01*
G01X562640Y18242D02*
G03X563640Y19242I0J1000D01*
G01Y25116D02*
G03X562640Y26116I-1000J0D01*
G01X561256Y38853D02*
G03X562256Y39853I0J1000D01*
G01X569014Y38088D02*
G03X569514Y37588I500J0D01*
G01X565811Y6528D02*
X570732D01*
G01X565811Y9060D02*
X570732D01*
G01X561640Y11019D02*
X596876D01*
G01X561640Y44408D02*
Y11019D01*
G01X563805Y14955D02*
X562624Y11019D01*
G01X563805Y14955D02*
X562624Y11019D01*
G01X537419Y12877D02*
X539419D01*
G01X537419Y14058D02*
X538419D01*
G01X562640Y18242D02*
X557396D01*
G01X538553Y18393D02*
X539253D01*
G01X541506D02*
X542206D01*
G01X544459D02*
X545159D01*
G01X547411D02*
X548111D01*
G01X538419Y18585D02*
X537419D01*
G01X539419Y19766D02*
X537419D01*
G01X548111Y21371D02*
X547411D01*
G01X545159D02*
X544459D01*
G01X542206D02*
X541506D01*
G01X539253D02*
X538553D01*
G01X548111Y24336D02*
X547411D01*
G01X545159D02*
X544459D01*
G01X542206D02*
X541506D01*
G01X539253D02*
X538553D01*
G01X548111Y24561D02*
X547411D01*
G01X545159D02*
X544459D01*
G01X542206D02*
X541506D01*
G01X539253D02*
X538553D01*
G01X557396Y26116D02*
X562640D01*
G01X539630Y27251D02*
X536677D01*
G01X545876Y38588D02*
X546009Y38552D01*
X546128Y38447D01*
X546211Y38288D01*
X546242Y38088D01*
G01X539630Y28251D02*
X536677D01*
G01X539630Y29251D02*
X536677D01*
G01X539630Y29501D02*
X536677D01*
G01X537268Y31367D02*
X539039D01*
G01X558321Y31917D02*
X558128D01*
G01X553569Y36767D02*
X543116D01*
G01X545742Y37588D02*
X543848D01*
G01X541408Y38588D02*
X545876D01*
G01X557396Y38853D02*
X561256D01*
G01X542080Y39032D02*
X542053D01*
G01X558128Y39791D02*
X558321D01*
G01X542080Y37940D02*
X544162Y35857D01*
G01X539100Y41985D02*
X542053Y39032D01*
G01X542919Y36569D02*
X543982Y35267D01*
G01X542053Y38069D02*
X543116Y36767D01*
G01X542053Y38069D02*
X542919Y36569D01*
G01X543982Y35267D02*
X543116Y36767D01*
G01X539512Y39341D02*
X539837Y38627D01*
X539979Y37855D01*
X539929Y37073D01*
G01X539837Y38627D02*
X539979Y37855D01*
X539929Y37073D01*
G01X546242Y38088D02*
X546231Y38173D01*
X546197Y38258D01*
X546139Y38341D01*
X546056Y38418D01*
X545950Y38484D01*
X545822Y38538D01*
X545674Y38574D01*
X545509Y38588D01*
G01X536301Y24561D02*
Y18393D01*
G01X536677Y30777D02*
Y26751D01*
G01X537419Y19766D02*
Y12877D01*
G01X538419D02*
Y19766D01*
G01X538553Y24561D02*
Y18393D01*
G01X539253Y24561D02*
Y18393D01*
G01X539419Y19766D02*
Y12877D01*
G01X539630Y30777D02*
Y26751D01*
G01X540630Y31038D02*
Y26751D01*
G01X540817Y43339D02*
Y39178D01*
G01X541506Y24561D02*
Y18393D01*
G01X542053Y44408D02*
Y38069D01*
G01X542080Y44408D02*
Y37940D01*
G01X542206Y24561D02*
Y18393D01*
G01X542778Y44408D02*
Y37242D01*
G01X542919Y36569D02*
Y44408D01*
G01X543848Y40780D02*
Y34257D01*
G01X543992Y43930D02*
Y38588D01*
G01X544242Y44408D02*
Y38588D01*
G01X544459Y24561D02*
Y18393D01*
G01X545159Y24561D02*
Y18393D01*
G01X545242Y43930D02*
Y38588D01*
G01X546211Y36767D02*
Y44408D01*
G01X546242Y43930D02*
Y38088D01*
G01X547411Y24561D02*
Y18393D01*
G01X548111Y24561D02*
Y18393D01*
G01X551404Y35141D02*
Y14955D01*
G01X557396Y26116D02*
Y18242D01*
G01Y38853D02*
Y44759D01*
G01X558321Y31917D02*
Y39791D01*
G01X559128Y44759D02*
Y38853D01*
G01Y18242D02*
Y26116D01*
G01X543848Y34257D02*
X539236Y29645D01*
G01X539630Y30777D02*
G03X539039Y31367I-591J-1D01*
G01X537268D02*
G03X536677Y30777I0J-591D01*
G01X539630Y26751D02*
G03X540630I500J0D01*
G01X540817Y39178D02*
G03X541408Y38588I591J1D01*
G01X545742Y37588D02*
G03X546242Y38088I0J500D01*
G01X544524Y6528D02*
X549445D01*
G01X557128Y6877D02*
X558128D01*
G01Y7468D02*
X557128D01*
G01X544524Y9060D02*
X549445D01*
G01X551404Y14955D02*
X552585Y11019D01*
G01X551404Y14955D02*
X552585Y11019D01*
G01X553569D02*
Y44408D01*
G01X567797Y53867D02*
X567097D01*
G01Y54083D02*
X567797D01*
G01X567097Y54179D02*
X567797D01*
G01X567097Y54241D02*
X567797D01*
G01Y54339D02*
X567097D01*
G01X567538Y54546D02*
X567223D01*
G01X567893D02*
X567814D01*
G01X568339D02*
X568260D01*
G01X568601D02*
X568522D01*
G01X567551Y54627D02*
X567302D01*
G01X568207Y54707D02*
X567945D01*
G01X568194Y54761D02*
X567958D01*
G01X567302Y54828D02*
X567551D01*
G01X567302Y54908D02*
X567551D01*
G01Y55096D02*
X567302D01*
G01X567223Y55176D02*
X567538D01*
G01X568024D02*
X568129D01*
G01X568522D02*
X568601D01*
G01X567797Y55323D02*
X567097D01*
G01X567797Y55422D02*
X567097D01*
G01Y55484D02*
X567797D01*
G01X567097Y55579D02*
X567797D01*
G01Y55796D02*
X567097D01*
G01X567797Y68827D02*
X567097D01*
G01Y69044D02*
X567797D01*
G01X567097Y69139D02*
X567797D01*
G01X567097Y69201D02*
X567797D01*
G01Y69300D02*
X567097D01*
G01X567797Y70284D02*
X567097D01*
G01X567797Y70382D02*
X567097D01*
G01Y70445D02*
X567797D01*
G01Y70540D02*
X567097D01*
G01X567797Y70756D02*
X567097D01*
G01X567538Y55176D02*
X567604Y55163D01*
G01X567551Y54828D02*
X567591Y54814D01*
G01Y55082D02*
X567551Y55096D01*
G01X567630Y54868D02*
X567656Y54855D01*
G01X567604Y55163D02*
X567656Y55123D01*
G01X567591Y54814D02*
X567617Y54788D01*
G01Y55056D02*
X567591Y55082D01*
G01X567604Y54560D02*
X567538Y54546D01*
G01X567656Y54855D02*
X567696Y54801D01*
G01X567656Y55123D02*
X567696Y55069D01*
G01X568129Y55176D02*
X568339Y54546D01*
G01X567617Y54788D02*
X567630Y54747D01*
G01X567696Y54801D02*
X567709Y54761D01*
G01X567630Y55015D02*
X567617Y55056D01*
G01X567696Y55069D02*
X567709Y55029D01*
G01X568260Y54546D02*
X568207Y54707D01*
G01X568076Y55123D02*
X568194Y54761D01*
G01X560727Y68043D02*
Y77812D01*
G01X562648Y76812D02*
Y69043D01*
G01X567097Y53868D02*
Y55794D01*
G01Y68829D02*
Y70755D01*
G01X567223Y54546D02*
Y55176D01*
G01X567302Y55096D02*
Y54908D01*
G01Y54627D02*
Y54828D01*
G01X567630Y54747D02*
Y54707D01*
G01Y54988D02*
Y55015D01*
G01X567709Y55029D02*
Y54975D01*
G01Y54761D02*
Y54693D01*
G01X567797Y53869D02*
Y55795D01*
G01Y68829D02*
Y70755D01*
G01X568444Y54975D02*
Y55082D01*
G01X568522Y54546D02*
Y55069D01*
G01X568601Y55176D02*
Y54546D01*
G01X567617Y54948D02*
X567630Y54988D01*
G01X567709Y54975D02*
X567696Y54935D01*
G01X567630Y54707D02*
X567617Y54667D01*
G01X567709Y54693D02*
X567696Y54653D01*
G01X567958Y54761D02*
X568076Y55123D01*
G01X567945Y54707D02*
X567893Y54546D01*
G01X567814D02*
X568024Y55176D01*
G01X567696Y54935D02*
X567656Y54881D01*
G01X567696Y54653D02*
X567656Y54600D01*
G01X568444Y55082D02*
X568522Y55176D01*
G01Y55069D02*
X568444Y54975D01*
G01X567591Y54921D02*
X567617Y54948D01*
G01Y54667D02*
X567591Y54640D01*
G01X567656Y54600D02*
X567604Y54560D01*
G01X567656Y54881D02*
X567630Y54868D01*
G01X567551Y54908D02*
X567591Y54921D01*
G01Y54640D02*
X567551Y54627D01*
G01X561648Y68043D02*
G03X562648Y69043I0J1000D01*
G01X571014Y41062D02*
X569045D01*
G01X560065Y44408D02*
X598451D01*
G01X560065Y105171D02*
Y44408D01*
G01X561065D02*
Y68043D01*
G01X561693Y105171D02*
Y44408D01*
G01X563106Y105171D02*
Y44408D01*
G01X562256Y43759D02*
G03X561256Y44759I-1000J0D01*
G01X558128Y45223D02*
X557128D01*
G01Y46475D02*
X558128D01*
G01Y47182D02*
X557128D01*
G01X544459Y48355D02*
X545159D01*
G01Y48571D02*
X544459D01*
G01X545159Y48667D02*
X544459D01*
G01X545159Y48729D02*
X544459D01*
G01X545159Y48827D02*
X544459D01*
G01X545159Y49812D02*
X544459D01*
G01X545159Y49910D02*
X544459D01*
G01X545159Y49973D02*
X544459D01*
G01X545159Y50068D02*
X544459D01*
G01Y50284D02*
X545159D01*
G01X557128Y50541D02*
X558128D01*
G01X557128Y50638D02*
X558128D01*
G01X538553Y51111D02*
X539253D01*
G01X547411D02*
X548111D01*
G01X557128Y51142D02*
X558128D01*
G01X557128Y51171D02*
X558128D01*
G01X548111Y51327D02*
X547411D01*
G01X539253D02*
X538553D01*
G01X548111Y51423D02*
X547411D01*
G01X539253D02*
X538553D01*
G01X548111Y51485D02*
X547411D01*
G01X539253D02*
X538553D01*
G01X548111Y51583D02*
X547411D01*
G01X539253D02*
X538553D01*
G01X558128D02*
X557128D01*
G01X548112Y52568D02*
X547412D01*
G01X539254D02*
X538554D01*
G01X557128D02*
X558128D01*
G01X548111Y52666D02*
X547411D01*
G01X539253D02*
X538553D01*
G01X548111Y52729D02*
X547411D01*
G01X539253D02*
X538553D01*
G01X548111Y52823D02*
X547411D01*
G01X539253D02*
X538553D01*
G01X557128Y52975D02*
X558128D01*
G01X557128Y53005D02*
X558128D01*
G01X538553Y53040D02*
X539253D01*
G01X547411D02*
X548111D01*
G01X557128Y53512D02*
X558128D01*
G01Y53605D02*
X557128D01*
G01X542206Y53867D02*
X541506D01*
G01Y54083D02*
X542206D01*
G01X541506Y54179D02*
X542206D01*
G01X541506Y54241D02*
X542206D01*
G01X558128Y54260D02*
X557128D01*
G01X558128Y54275D02*
X557128D01*
G01X542206Y54339D02*
X541506D01*
G01X542206Y55323D02*
X541506D01*
G01X542206Y55422D02*
X541506D01*
G01Y55484D02*
X542206D01*
G01X541506Y55579D02*
X542206D01*
G01Y55796D02*
X541506D01*
G01X558128Y56275D02*
X553608D01*
G01X544459Y63316D02*
X545159D01*
G01Y63532D02*
X544459D01*
G01X545159Y63627D02*
X544459D01*
G01X545159Y63690D02*
X544459D01*
G01X545159Y63788D02*
X544459D01*
G01X545159Y64772D02*
X544459D01*
G01X545159Y64871D02*
X544459D01*
G01X545159Y64933D02*
X544459D01*
G01X545159Y65028D02*
X544459D01*
G01Y65245D02*
X545159D01*
G01X553608Y66043D02*
X558128D01*
G01X538553Y66071D02*
X539253D01*
G01X547411D02*
X548111D01*
G01Y66288D02*
X547411D01*
G01X539253D02*
X538553D01*
G01X548111Y66383D02*
X547411D01*
G01X539253D02*
X538553D01*
G01X548111Y66445D02*
X547411D01*
G01X539253D02*
X538553D01*
G01X548111Y66544D02*
X547411D01*
G01X539253D02*
X538553D01*
G01X548112Y67528D02*
X547412D01*
G01X539254D02*
X538554D01*
G01X548111Y67627D02*
X547411D01*
G01X539253D02*
X538553D01*
G01X548111Y67689D02*
X547411D01*
G01X539253D02*
X538553D01*
G01X548111Y67784D02*
X547411D01*
G01X539253D02*
X538553D01*
G01Y68001D02*
X539253D01*
G01X547411D02*
X548111D01*
G01X561648Y68043D02*
X557128D01*
G01X542206Y68827D02*
X541506D01*
G01Y69044D02*
X542206D01*
G01X541506Y69139D02*
X542206D01*
G01X541506Y69201D02*
X542206D01*
G01Y69300D02*
X541506D01*
G01X542206Y70284D02*
X541506D01*
G01X542206Y70382D02*
X541506D01*
G01Y70445D02*
X542206D01*
G01Y70540D02*
X541506D01*
G01X542206Y70756D02*
X541506D01*
G01X536301Y48357D02*
Y50283D01*
G01Y63318D02*
Y65243D01*
G01X538553Y51112D02*
Y53038D01*
G01Y66073D02*
Y67999D01*
G01X539253Y51113D02*
Y53039D01*
G01Y66073D02*
Y67999D01*
G01X541506Y53868D02*
Y55794D01*
G01Y68829D02*
Y70755D01*
G01X542206Y53869D02*
Y55795D01*
G01Y68829D02*
Y70755D01*
G01X544459Y48356D02*
Y50282D01*
G01Y63317D02*
Y65243D01*
G01X545159Y48357D02*
Y50283D01*
G01Y63318D02*
Y65243D01*
G01X547411Y51112D02*
Y53038D01*
G01Y66073D02*
Y67999D01*
G01X548111Y51113D02*
Y53039D01*
G01Y66073D02*
Y67999D01*
G01X552608Y65043D02*
Y57275D01*
G01X554144Y66043D02*
Y86182D01*
G01X554481Y66043D02*
Y56275D01*
G01X556128Y66043D02*
Y56275D01*
G01X556923D02*
Y66043D01*
G01X558333Y77812D02*
Y68043D01*
G01X559128D02*
Y77812D01*
G01X552608Y57275D02*
G03X553608Y56275I1000J0D01*
G01Y66043D02*
G03X552608Y65043I0J-1000D01*
G01X557128Y44516D02*
X558128D01*
G01X557396Y44759D02*
X561256D01*
G01X539236Y45393D02*
X543848Y40780D01*
G01X540872Y46512D02*
Y44408D01*
G01X552102Y105171D02*
Y44408D01*
G01X553516Y105171D02*
Y44408D01*
G01X554144D02*
Y56275D01*
G01X555144Y44408D02*
Y105171D01*
G01X541408Y43930D02*
G03X540817Y43339I0J-591D01*
G01X567797Y83788D02*
X567097D01*
G01Y84005D02*
X567797D01*
G01X567097Y84100D02*
X567797D01*
G01X567097Y84162D02*
X567797D01*
G01Y84260D02*
X567097D01*
G01X567797Y85245D02*
X567097D01*
G01X567797Y85343D02*
X567097D01*
G01Y85406D02*
X567797D01*
G01Y85501D02*
X567097D01*
G01X567797Y85717D02*
X567097D01*
G01X567797Y98749D02*
X567097D01*
G01Y98965D02*
X567797D01*
G01X567097Y99060D02*
X567797D01*
G01X567097Y99123D02*
X567797D01*
G01Y99221D02*
X567097D01*
G01X567797Y100205D02*
X567097D01*
G01X567797Y100304D02*
X567097D01*
G01Y100366D02*
X567797D01*
G01Y100461D02*
X567097D01*
G01X567797Y100678D02*
X567097D01*
G01X565872Y102336D02*
X592644D01*
G01X560727Y96578D02*
Y105171D01*
G01X562049Y107942D02*
Y106958D01*
G01X562256Y92636D02*
Y96542D01*
G01X562648Y104171D02*
Y97578D01*
G01X563049Y107942D02*
Y106958D01*
G01X565652Y105958D02*
Y106958D01*
G01X565872Y105171D02*
Y102336D01*
G01X566652Y106958D02*
Y105958D01*
G01X567097Y83790D02*
Y85716D01*
G01Y98750D02*
Y100676D01*
G01X567797Y83790D02*
Y85716D01*
G01Y98751D02*
Y100677D01*
G01X568648Y106958D02*
Y105958D01*
G01X568652Y105171D02*
Y106958D01*
G01X561648Y96578D02*
G03X562648Y97578I0J1000D01*
G01Y104171D02*
G03X561648Y105171I-1000J0D01*
G01X562256Y96542D02*
G03X561256Y97542I-1000J0D01*
G01Y91636D02*
G03X562256Y92636I0J1000D01*
G01X561065Y77812D02*
Y96578D01*
G01X562648Y76812D02*
G03X561648Y77812I-1000J0D01*
G01X545159Y79733D02*
X544459D01*
G01X545159Y79831D02*
X544459D01*
G01X545159Y79894D02*
X544459D01*
G01X545159Y79989D02*
X544459D01*
G01Y80205D02*
X545159D01*
G01X538553Y81032D02*
X539253D01*
G01X547411D02*
X548111D01*
G01Y81249D02*
X547411D01*
G01X539253D02*
X538553D01*
G01X548111Y81344D02*
X547411D01*
G01X539253D02*
X538553D01*
G01X548111Y81406D02*
X547411D01*
G01X539253D02*
X538553D01*
G01X548111Y81505D02*
X547411D01*
G01X539253D02*
X538553D01*
G01X548112Y82489D02*
X547412D01*
G01X539254D02*
X538554D01*
G01X548111Y82587D02*
X547411D01*
G01X539253D02*
X538553D01*
G01X548111Y82650D02*
X547411D01*
G01X539253D02*
X538553D01*
G01X548111Y82745D02*
X547411D01*
G01X539253D02*
X538553D01*
G01Y82961D02*
X539253D01*
G01X547411D02*
X548111D01*
G01X542206Y83788D02*
X541506D01*
G01Y84005D02*
X542206D01*
G01X541506Y84100D02*
X542206D01*
G01X541506Y84162D02*
X542206D01*
G01Y84260D02*
X541506D01*
G01X557128Y85182D02*
X558128D01*
G01X542206Y85245D02*
X541506D01*
G01X542206Y85343D02*
X541506D01*
G01Y85406D02*
X542206D01*
G01Y85501D02*
X541506D01*
G01X542206Y85717D02*
X541506D01*
G01X558128Y86182D02*
X553608D01*
G01X557396Y91636D02*
X561256D01*
G01X544459Y93237D02*
X545159D01*
G01Y93453D02*
X544459D01*
G01X545159Y93549D02*
X544459D01*
G01X545159Y93611D02*
X544459D01*
G01X545159Y93709D02*
X544459D01*
G01X553608Y94578D02*
X558128D01*
G01X545159Y94693D02*
X544459D01*
G01X545159Y94792D02*
X544459D01*
G01X545159Y94855D02*
X544459D01*
G01X545159Y94949D02*
X544459D01*
G01Y95166D02*
X545159D01*
G01X538553Y95993D02*
X539253D01*
G01X547411D02*
X548111D01*
G01Y96209D02*
X547411D01*
G01X539253D02*
X538553D01*
G01X548111Y96305D02*
X547411D01*
G01X539253D02*
X538553D01*
G01X548111Y96367D02*
X547411D01*
G01X539253D02*
X538553D01*
G01X548111Y96465D02*
X547411D01*
G01X539253D02*
X538553D01*
G01X561648Y96578D02*
X557128D01*
G01X548112Y97449D02*
X547412D01*
G01X539254D02*
X538554D01*
G01X561256Y97542D02*
X557396D01*
G01X548111Y97548D02*
X547411D01*
G01X539253D02*
X538553D01*
G01X548111Y97610D02*
X547411D01*
G01X539253D02*
X538553D01*
G01X548111Y97705D02*
X547411D01*
G01X539253D02*
X538553D01*
G01Y97922D02*
X539253D01*
G01X547411D02*
X548111D01*
G01X542206Y98749D02*
X541506D01*
G01Y98965D02*
X542206D01*
G01X541506Y99060D02*
X542206D01*
G01X541506Y99123D02*
X542206D01*
G01Y99221D02*
X541506D01*
G01X542206Y100205D02*
X541506D01*
G01X542206Y100304D02*
X541506D01*
G01Y100366D02*
X542206D01*
G01Y100461D02*
X541506D01*
G01X542206Y100678D02*
X541506D01*
G01X557128Y103048D02*
X558128D01*
G01Y103974D02*
X557128D01*
G01X558128Y104974D02*
X557128D01*
G01X557309Y105169D02*
X557900D01*
G01X536301Y93239D02*
Y95165D01*
G01X538553Y81034D02*
Y82960D01*
G01Y95994D02*
Y97920D01*
G01X538904Y105958D02*
Y106958D01*
G01X539253Y81034D02*
Y82960D01*
G01Y95995D02*
Y97921D01*
G01X541506Y83790D02*
Y85716D01*
G01Y98750D02*
Y100676D01*
G01X542206Y83790D02*
Y85716D01*
G01Y98751D02*
Y100677D01*
G01X543431Y105171D02*
Y102336D01*
G01X544077Y106958D02*
Y105958D01*
G01X544459Y93238D02*
Y95164D01*
G01X544809Y105171D02*
Y102336D01*
G01X545159Y93239D02*
Y95165D01*
G01X545577Y105958D02*
Y106958D01*
G01X546232D02*
Y105958D01*
G01X546325D02*
Y106958D01*
G01X546585D02*
Y105958D01*
G01X546589Y105171D02*
Y106958D01*
G01X546811Y105958D02*
Y106958D01*
G01X546862Y105958D02*
Y106958D01*
G01X547270Y105958D02*
Y106958D01*
G01X547411Y81034D02*
Y82960D01*
G01Y95994D02*
Y97920D01*
G01X548111Y81034D02*
Y82960D01*
G01Y95995D02*
Y97921D01*
G01X548254Y106958D02*
Y105958D01*
G01X548585Y106958D02*
Y105958D01*
G01X548666D02*
Y106958D01*
G01X548717Y105958D02*
Y106958D01*
G01X549199Y105958D02*
Y106958D01*
G01X549296Y105958D02*
Y106958D01*
G01X549337Y105171D02*
Y102336D01*
G01X549585Y106958D02*
Y105958D01*
G01X550103Y106958D02*
Y105958D01*
G01X551447D02*
Y106958D01*
G01X552608Y93578D02*
Y87182D01*
G01X554144Y94578D02*
Y105171D01*
G01X554481Y94578D02*
Y86182D01*
G01X556128Y94578D02*
Y86182D01*
G01X556923D02*
Y94578D01*
G01X557396Y91636D02*
Y97542D01*
G01X558333Y105171D02*
Y96578D01*
G01X559128Y91636D02*
Y105171D01*
G01X553608Y94578D02*
G03X552608Y93578I0J-1000D01*
G01Y87182D02*
G03X553608Y86182I1000J0D01*
G01X559128Y107942D02*
G03X557405Y106958I0J-2000D01*
G01X557128Y77812D02*
X561648D01*
G01X544459Y78276D02*
X545159D01*
G01Y78493D02*
X544459D01*
G01X545159Y78588D02*
X544459D01*
G01X545159Y78650D02*
X544459D01*
G01X545159Y78749D02*
X544459D01*
G01X558128Y78812D02*
X557128D01*
G01X558128Y77580D02*
X560065Y75643D01*
G01X536301Y78278D02*
Y80204D01*
G01X544459Y78278D02*
Y80204D01*
G01X545159Y78278D02*
Y80204D01*
G01X557128Y77628D02*
X555144Y75643D01*
G01X558297Y137794D02*
X555344D01*
G01D02*
Y161416D01*
G01X558297Y148851D02*
Y137794D01*
G01X563049Y107942D02*
X559128D01*
G01X572077Y148851D02*
X558297D01*
G01Y151867D02*
X572077D01*
G01X555344Y161416D02*
X558297D01*
G01D02*
Y151867D01*
G01X562106Y892519D02*
Y883464D01*
G01X563091D02*
Y892519D01*
G01X565256D02*
Y883464D01*
G01X566240D02*
Y892519D01*
G01X568406D02*
Y883464D01*
G01X569390D02*
Y892519D01*
G01X571555Y883464D02*
X569390D01*
G01X568406D02*
X566240D01*
G01X565256D02*
X563091D01*
G01X536909Y892519D02*
Y883464D01*
G01X537894D02*
Y892519D01*
G01X540059D02*
Y883464D01*
G01X541043D02*
Y892519D01*
G01X543209D02*
Y883464D01*
G01X544193D02*
Y892519D01*
G01X546358D02*
Y883464D01*
G01X547343D02*
Y892519D01*
G01X549508D02*
Y883464D01*
G01X550492D02*
Y892519D01*
G01X552657D02*
Y883464D01*
G01X553642D02*
Y892519D01*
G01X555807D02*
Y883464D01*
G01X556791D02*
Y892519D01*
G01X558957D02*
Y883464D01*
G01X559941D02*
Y892519D01*
G01X562106Y883464D02*
X559941D01*
G01X558957D02*
X556791D01*
G01X555807D02*
X553642D01*
G01X552657D02*
X550492D01*
G01X549508D02*
X547343D01*
G01X546358D02*
X544193D01*
G01X543209D02*
X541043D01*
G01X540059D02*
X537894D01*
G01X563091Y892519D02*
X565256D01*
G01X569390D02*
X571555D01*
G01X566240D02*
X568406D01*
G01X541043D02*
X543209D01*
G01X537894D02*
X540059D01*
G01X544193D02*
X546358D01*
G01X550492D02*
X552657D01*
G01X547343D02*
X549508D01*
G01X553642D02*
X555807D01*
G01X559941D02*
X562106D01*
G01X556791D02*
X558957D01*
G01X574109Y-727083D02*
Y-688894D01*
G01Y-650705D02*
Y-688894D01*
G01X571944Y-692792D02*
Y-693279D01*
X571222D01*
X571944Y-692792D01*
G01X574077Y-650705D02*
Y-615272D01*
G01Y-579839D02*
Y-615272D01*
G01X571911Y-619170D02*
Y-619657D01*
X571190D01*
X571911Y-619170D01*
G01X572133Y-436739D02*
X571159Y-436017D01*
X570671Y-435295D01*
X570184Y-433851D01*
Y-430964D01*
X570671Y-429521D01*
X571159Y-428799D01*
X572133Y-428077D01*
X573107Y-428799D01*
X573594Y-429521D01*
X574082Y-430964D01*
Y-433851D01*
X573594Y-435295D01*
X573107Y-436017D01*
X572133Y-436739D01*
G01X570406Y-465471D02*
X569919D01*
Y-464750D01*
X570406Y-465471D01*
G01X578201D02*
X577227Y-464750D01*
X576740Y-464028D01*
X576252Y-462584D01*
Y-459697D01*
X576740Y-458254D01*
X577227Y-457532D01*
X578201Y-456810D01*
X579176Y-457532D01*
X579663Y-458254D01*
X580150Y-459697D01*
Y-462584D01*
X579663Y-464028D01*
X579176Y-464750D01*
X578201Y-465471D01*
G01X585996D02*
X585022Y-464750D01*
X584535Y-464028D01*
X584048Y-462584D01*
Y-459697D01*
X584535Y-458254D01*
X585022Y-457532D01*
X585996Y-456810D01*
X586971Y-457532D01*
X587458Y-458254D01*
X587945Y-459697D01*
Y-462584D01*
X587458Y-464028D01*
X586971Y-464750D01*
X585996Y-465471D01*
G01X573335Y-407884D02*
X572361Y-407162D01*
X571874Y-406440D01*
X571386Y-404997D01*
Y-402110D01*
X571874Y-400666D01*
X572361Y-399944D01*
X573335Y-399222D01*
X574310Y-399944D01*
X574797Y-400666D01*
X575284Y-402110D01*
Y-404997D01*
X574797Y-406440D01*
X574310Y-407162D01*
X573335Y-407884D01*
G01X604024Y-94838D02*
X603049Y-96281D01*
X602562Y-98447D01*
X606459D01*
G01X587459D02*
Y-92672D01*
G01X583074Y-96281D02*
X582099Y-97725D01*
X581125Y-98447D01*
X580150Y-97725D01*
X579176Y-96281D01*
Y-94838D01*
X580150Y-93394D01*
X581125Y-92672D01*
X582099Y-93394D01*
X583074Y-94838D01*
Y-96281D01*
G01X587459Y-94116D02*
X588433Y-92672D01*
X589407D01*
X590382Y-94116D01*
Y-98447D01*
G01X602562Y-91229D02*
X603049Y-90507D01*
X604024Y-89785D01*
X604998D01*
X605972Y-90507D01*
X606459Y-91229D01*
Y-92672D01*
X605972Y-93394D01*
X604024Y-94838D01*
G01X603972Y-38336D02*
X600701D01*
G01Y-34399D02*
X603972D01*
G01X598428Y-34338D02*
X598362D01*
G01X643742Y-32749D02*
X601435D01*
G01X599920Y-32023D02*
X601950D01*
G01X643742Y-28812D02*
X601435D01*
G01Y-32749D02*
X601440Y-42635D01*
G01X597870Y-17548D02*
Y-33845D01*
G01X597923Y-33339D02*
Y-38564D01*
G01X598120Y-33839D02*
Y-38879D01*
G01X598870Y-22238D02*
Y-31524D01*
G01X598920Y-33023D02*
Y-33845D01*
G01X600435Y-32749D02*
Y-42635D01*
G01Y-28812D02*
Y105958D01*
G01X600701Y-34399D02*
Y-38336D01*
G01X601435Y-42635D02*
Y-32749D01*
G01Y-28812D02*
Y105958D01*
G01X602435Y-38336D02*
Y-34399D01*
G01X602950Y-33023D02*
Y-33845D01*
G01X603000Y-22238D02*
Y-31524D01*
G01X601442Y-14225D02*
X601435Y-28812D01*
G01X597530Y-39469D02*
G03X598120Y-38879I0J590D01*
G01X597333Y-39154D02*
G03X597923Y-38564I0J590D01*
G01Y-33339D02*
G03X597333Y-32749I-590J0D01*
G01X598120Y-33839D02*
G03X597530Y-33249I-590J0D01*
G01X597923Y-33839D02*
G03X597333Y-33249I-590J0D01*
G01X597870Y-33845D02*
G03X598362Y-34338I492J-1D01*
G01X598428D02*
G03X598920Y-33845I0J492D01*
G01X598370Y-32016D02*
G03X598870Y-31524I8J492D01*
G01X597870D02*
G03X598370Y-32016I492J0D01*
G01X602950Y-33845D02*
G03X603442Y-34338I492J-1D01*
G01X599920Y-32023D02*
G03X598920Y-33023I0J-1000D01*
G01X602950D02*
G03X601950Y-32023I-1000J0D01*
G01X603000Y-31524D02*
G03X603500Y-32016I492J0D01*
G01X597870Y-31255D02*
X589702Y-31261D01*
G01X615674Y-42635D02*
X586196D01*
G01X584281Y-41835D02*
X574281D01*
G01Y-41754D02*
X584281D01*
G01X584367Y-41635D02*
X574196D01*
G01X584281Y-41461D02*
X574281D01*
G01X615074Y-41435D02*
X586796D01*
G01X574281Y-41403D02*
X584281D01*
G01X574281Y-41135D02*
X584281D01*
G01Y-41107D02*
X574281D01*
G01X597530Y-39469D02*
X593695D01*
G01X574948Y-39467D02*
X583615D01*
G01X583281Y-39440D02*
X575281D01*
G01X597333Y-39154D02*
X593695D01*
G01X573967Y-34319D02*
X584596D01*
G01X597870Y-33775D02*
X589687D01*
G01X588215D02*
X580017D01*
G01X578546D02*
X570348D01*
G01X597530Y-33249D02*
X593695D01*
G01X597870Y-33102D02*
X589701D01*
G01X588201D02*
X580031D01*
G01X578531D02*
X570362D01*
G01Y-32967D02*
X578531D01*
G01X580031D02*
X588201D01*
G01X589701D02*
X597870D01*
G01X588200Y-31261D02*
X580032D01*
G01X578531D02*
X570363D01*
G01X570362Y-30829D02*
X578531D01*
G01X580031D02*
X588201D01*
G01X589701D02*
X597870D01*
G01Y-30744D02*
X589701D01*
G01X588201D02*
X580031D01*
G01X578531D02*
X570362D01*
G01X585074Y-41928D02*
X585489Y-42342D01*
G01X578546Y-33775D02*
X578540Y-33744D01*
X578535Y-33713D01*
X578533Y-33682D01*
G01X588215Y-33775D02*
X588209Y-33744D01*
X588205Y-33713D01*
X588202Y-33682D01*
G01X578533Y-33663D02*
X578535Y-33701D01*
X578540Y-33738D01*
X578546Y-33775D01*
G01X588202Y-33663D02*
X588205Y-33701D01*
X588209Y-33738D01*
X588215Y-33775D01*
G01X578533Y-33682D02*
X578531Y-33647D01*
G01X588202Y-33682D02*
X588201Y-33647D01*
G01X578531Y-33621D02*
X578533Y-33663D01*
G01X588201Y-33621D02*
X588202Y-33663D01*
G01X570362Y-33647D02*
Y-17548D01*
G01X570361Y-33663D02*
Y-33682D01*
G01X573967Y-34319D02*
Y-32749D01*
G01X574281Y-40398D02*
Y-41835D01*
G01X576398Y-34319D02*
Y-32749D01*
G01X577017D02*
Y-34319D01*
G01X578533Y-33682D02*
Y-33663D01*
G01X578531Y-17548D02*
Y-33647D01*
G01X580031D02*
Y-17548D01*
G01Y-33663D02*
Y-33682D01*
G01X581546Y-34319D02*
Y-32749D01*
G01X582166D02*
Y-34319D01*
G01X584281Y-41835D02*
Y-40398D01*
G01X584596Y-32749D02*
Y-34319D01*
G01X588202Y-33663D02*
Y-33682D01*
G01X588201Y-17548D02*
Y-33647D01*
G01X570361Y-33663D02*
X570362Y-33621D01*
G01Y-33647D02*
X570361Y-33682D01*
G01X589701Y-33647D02*
Y-17548D01*
G01X589700Y-33663D02*
Y-33682D01*
G01X593105Y-38879D02*
Y-33339D01*
G01X580031Y-33663D02*
Y-33621D01*
G01X589700Y-33663D02*
X589701Y-33621D01*
G01X580031Y-33647D02*
Y-33682D01*
G01X589701Y-33647D02*
X589700Y-33682D01*
G01X570361D02*
X570359Y-33713D01*
X570354Y-33744D01*
X570348Y-33775D01*
G01X580031Y-33682D02*
X580028Y-33713D01*
X580024Y-33744D01*
X580017Y-33775D01*
G01X589700Y-33682D02*
X589697Y-33713D01*
X589693Y-33744D01*
X589687Y-33775D01*
G01X570348D02*
X570354Y-33738D01*
X570359Y-33701D01*
X570361Y-33663D01*
G01X580017Y-33775D02*
X580024Y-33738D01*
X580028Y-33701D01*
X580031Y-33663D01*
G01X589687Y-33775D02*
X589693Y-33738D01*
X589697Y-33701D01*
X589700Y-33663D01*
G01X573489Y-41928D02*
X573074Y-42342D01*
G01X574196Y-41635D02*
G03X573489Y-41928I0J-1000D01*
G01X572367Y-42635D02*
G03X573074Y-42342I0J1000D01*
G01X575281Y-39440D02*
G03X574281Y-40440I0J-1000D01*
G01X571767Y-41435D02*
G03X572724Y-40679I0J984D01*
G01X574948Y-39467D02*
G03X574281Y-40398I317J-932D01*
G01Y-40845D02*
G03X572724Y-40679I-787J0D01*
G01X585489Y-42342D02*
G03X586196Y-42635I707J707D01*
G01X585074Y-41928D02*
G03X584367Y-41635I-707J-707D01*
G01X584281Y-40440D02*
G03X583281Y-39440I-1000J0D01*
G01X585837Y-40670D02*
G03X586796Y-41435I959J219D01*
G01X584281Y-40398D02*
G03X583615Y-39467I-984J0D01*
G01X585837Y-40670D02*
G03X584281Y-40845I-768J-173D01*
G01X578546Y-33775D02*
G03X579281Y-34378I734J145D01*
G01D02*
G03X580017Y-33775I2J748D01*
G01X579281Y-32016D02*
G03X580031Y-31261I2J748D01*
G01X578532D02*
G03X579281Y-32016I748J-7D01*
G01X593105Y-38879D02*
G03X593695Y-39469I590J0D01*
G01X593105Y-38564D02*
G03X593695Y-39154I590J0D01*
G01X588215Y-33775D02*
G03X588951Y-34378I734J145D01*
G01D02*
G03X589687Y-33775I2J748D01*
G01X593695Y-33249D02*
G03X593105Y-33839I0J-590D01*
G01X593695Y-32749D02*
G03X593105Y-33339I0J-590D01*
G01X588951Y-32016D02*
G03X589701Y-31261I2J748D01*
G01X588201D02*
G03X588951Y-32016I748J-7D01*
G01X600703Y-17178D02*
X604563D01*
G01X600703Y-15934D02*
X605947D01*
G01X604563Y-11273D02*
X600703D01*
G01X604892Y-8741D02*
X596979D01*
G01X600703Y-8060D02*
X605947D01*
G01X601435Y-2525D02*
X600435D01*
G01Y-1874D02*
X601435D01*
G01X600435Y-1777D02*
X601435D01*
G01X600435Y-1273D02*
X601435D01*
G01X600435Y-1244D02*
X601435D01*
G01Y-832D02*
X600435D01*
G01Y153D02*
X601435D01*
G01X600435Y560D02*
X601435D01*
G01X600435Y590D02*
X601435D01*
G01X600435Y1097D02*
X601435D01*
G01Y1190D02*
X600435D01*
G01X601435Y1845D02*
X600435D01*
G01X601435Y3845D02*
X600435D01*
G01X601435Y4436D02*
X600435D01*
G01X594776Y-17116D02*
X594934Y-17129D01*
X595086Y-17170D01*
X595225Y-17234D01*
X595348Y-17323D01*
X595445Y-17430D01*
X595515Y-17553D01*
G01X597083Y-16764D02*
X597236Y-16779D01*
X597383Y-16823D01*
X597519Y-16895D01*
X597640Y-16994D01*
X597737Y-17112D01*
X597810Y-17247D01*
X597855Y-17393D01*
X597870Y-17548D01*
G01X595515Y-17341D02*
X595446Y-17220D01*
X595350Y-17114D01*
X595230Y-17025D01*
X595088Y-16959D01*
X594937Y-16918D01*
X594776Y-16904D01*
G01X595661Y-17890D02*
X595799Y-18195D01*
X595936Y-18522D01*
X596074Y-18862D01*
G01X595515Y-17553D02*
X595661Y-17890D01*
G01Y-17679D02*
X595515Y-17341D01*
G01X596054Y-14327D02*
X598811Y-21902D01*
G01X596074Y-18845D02*
X595936Y-18437D01*
X595799Y-18044D01*
X595661Y-17679D01*
G01X597870Y-17582D02*
X597855Y-17430D01*
X597811Y-17284D01*
X597739Y-17149D01*
X597640Y-17028D01*
X597521Y-16931D01*
X597385Y-16858D01*
X597239Y-16814D01*
X597083Y-16798D01*
G01X594776Y-17116D02*
Y-16904D01*
G01X595515Y-17341D02*
Y-17553D01*
G01X595661Y-17890D02*
Y-17679D01*
G01X595994Y-9725D02*
Y-13990D01*
G01X596074Y-18845D02*
Y-18862D01*
G01X597083Y-16764D02*
Y-16798D01*
G01X600703Y-8060D02*
Y-17178D01*
G01X601440Y31917D02*
X601442Y-6351D01*
G01X601453Y-14225D02*
Y-6351D01*
G01X602435Y-15934D02*
Y-8060D01*
G01X602439Y-11273D02*
Y-17178D01*
G01X605817Y-14327D02*
X603059Y-21902D01*
G01D02*
G03X603000Y-22238I925J-336D01*
G01X596979Y-8741D02*
G03X595994Y-9725I-1J-984D01*
G01Y-13990D02*
G03X596054Y-14327I984J1D01*
G01X598870Y-22238D02*
G03X598811Y-21902I-984J0D01*
G01X601435Y-23095D02*
X643742D01*
G01Y-22468D02*
X601435D01*
G01X597823Y-23615D02*
X597708Y-23331D01*
G01X596074Y-18862D02*
X597708Y-23348D01*
G01Y-23331D02*
X596074Y-18845D01*
G01X597708Y-23348D02*
X597823Y-23689D01*
G01D02*
X597830Y-23711D01*
X597837Y-23734D01*
X597843Y-23756D01*
G01Y-23671D02*
X597837Y-23652D01*
X597830Y-23633D01*
X597823Y-23615D01*
G01X597843Y-23756D02*
X597851Y-23787D01*
X597858Y-23821D01*
X597863Y-23853D01*
X597867Y-23888D01*
X597869Y-23923D01*
X597870Y-23958D01*
G01Y-23872D02*
Y-23840D01*
X597867Y-23805D01*
X597864Y-23773D01*
X597858Y-23739D01*
X597851Y-23705D01*
X597843Y-23671D01*
G01X597823Y-23689D02*
Y-23615D01*
G01X597843Y-23671D02*
Y-23756D01*
G01X597708Y-23348D02*
Y-23331D01*
G01X590488Y-16798D02*
X590335Y-16813D01*
X590188Y-16857D01*
X590053Y-16929D01*
X589931Y-17028D01*
X589834Y-17146D01*
X589761Y-17281D01*
X589717Y-17427D01*
X589701Y-17582D01*
G01X580819Y-16798D02*
X580666Y-16813D01*
X580519Y-16857D01*
X580383Y-16929D01*
X580262Y-17028D01*
X580165Y-17146D01*
X580092Y-17281D01*
X580047Y-17427D01*
X580031Y-17582D01*
G01X571150Y-16798D02*
X570997Y-16813D01*
X570850Y-16857D01*
X570714Y-16929D01*
X570593Y-17028D01*
X570495Y-17146D01*
X570423Y-17281D01*
X570378Y-17427D01*
X570362Y-17582D01*
G01X592796Y-16904D02*
X592637Y-16918D01*
X592485Y-16958D01*
X592346Y-17023D01*
X592224Y-17112D01*
X592126Y-17218D01*
X592056Y-17341D01*
G01X580819Y-16904D02*
X580666Y-16917D01*
X580519Y-16954D01*
X580383Y-17015D01*
X580262Y-17099D01*
X580165Y-17199D01*
X580092Y-17313D01*
X580047Y-17437D01*
X580031Y-17568D01*
G01X571150Y-16904D02*
X570997Y-16917D01*
X570850Y-16954D01*
X570714Y-17015D01*
X570593Y-17099D01*
X570495Y-17199D01*
X570423Y-17313D01*
X570378Y-17437D01*
X570362Y-17568D01*
G01X596074Y-18862D02*
X591497D01*
G01X588201D02*
X580031D01*
G01X578531D02*
X570362D01*
G01Y-18845D02*
X578531D01*
G01X580031D02*
X588201D01*
G01X591497D02*
X596074D01*
G01X597870Y-18516D02*
X589701D01*
G01X588201D02*
X580031D01*
G01X578531D02*
X570362D01*
G01Y-18481D02*
X578531D01*
G01X580031D02*
X588201D01*
G01X589701D02*
X597870D01*
G01Y-18138D02*
X589701D01*
G01X588201D02*
X580031D01*
G01X578531D02*
X570362D01*
G01Y-18104D02*
X578531D01*
G01X580031D02*
X588201D01*
G01X589701D02*
X597870D01*
G01X570362Y-17890D02*
X578531D01*
G01X580031D02*
X588201D01*
G01X591910D02*
X595661D01*
G01Y-17679D02*
X591910D01*
G01X588201D02*
X580031D01*
G01X578531D02*
X570362D01*
G01X592752Y-17318D02*
X587831D01*
G01X571150Y-17116D02*
X577744D01*
G01X580819D02*
X587413D01*
G01X592796D02*
X594776D01*
G01Y-16904D02*
X592796D01*
G01X587413D02*
X580819D01*
G01X577744D02*
X571150D01*
G01Y-16798D02*
X577744D01*
G01X580819D02*
X587413D01*
G01X590488D02*
X597083D01*
G01Y-16764D02*
X590488D01*
G01X587413D02*
X580819D01*
G01X577744D02*
X571150D01*
G01X592752Y-14786D02*
X587831D01*
G01Y-14307D02*
X592752D01*
G01Y-9699D02*
X587831D01*
G01Y-9220D02*
X592752D01*
G01X587831Y-6688D02*
X592752D01*
G01Y-1570D02*
X587831D01*
G01X592752Y962D02*
X587831D01*
G01Y1441D02*
X592752D01*
G01Y6049D02*
X587831D01*
G01X577744Y-17116D02*
X577897Y-17128D01*
X578044Y-17166D01*
X578180Y-17227D01*
X578301Y-17310D01*
X578398Y-17410D01*
X578471Y-17525D01*
X578516Y-17649D01*
X578531Y-17780D01*
G01X587413Y-17116D02*
X587567Y-17128D01*
X587714Y-17166D01*
X587849Y-17227D01*
X587970Y-17310D01*
X588068Y-17410D01*
X588141Y-17525D01*
X588185Y-17649D01*
X588201Y-17780D01*
G01X577744Y-16764D02*
X577897Y-16779D01*
X578044Y-16823D01*
X578180Y-16895D01*
X578301Y-16994D01*
X578398Y-17112D01*
X578471Y-17247D01*
X578516Y-17393D01*
X578531Y-17548D01*
G01X587413Y-16764D02*
X587567Y-16779D01*
X587714Y-16823D01*
X587849Y-16895D01*
X587970Y-16994D01*
X588068Y-17112D01*
X588141Y-17247D01*
X588185Y-17393D01*
X588201Y-17548D01*
G01X578531Y-17568D02*
X578517Y-17439D01*
X578472Y-17315D01*
X578400Y-17201D01*
X578301Y-17099D01*
X578182Y-17016D01*
X578047Y-16955D01*
X577900Y-16917D01*
X577744Y-16904D01*
G01X578531Y-17582D02*
X578517Y-17430D01*
X578472Y-17284D01*
X578400Y-17149D01*
X578301Y-17028D01*
X578182Y-16931D01*
X578047Y-16858D01*
X577900Y-16814D01*
X577744Y-16798D01*
G01X588201Y-17582D02*
X588186Y-17430D01*
X588142Y-17284D01*
X588069Y-17149D01*
X587970Y-17028D01*
X587852Y-16931D01*
X587716Y-16858D01*
X587569Y-16814D01*
X587413Y-16798D01*
G01X570732Y-17318D02*
Y-6688D01*
G01Y-1570D02*
Y9060D01*
G01X571150Y-16904D02*
Y-17116D01*
G01Y-16798D02*
Y-16764D01*
G01X577744D02*
Y-16798D01*
G01Y-17116D02*
Y-16904D01*
G01X580819D02*
Y-17116D01*
G01Y-16798D02*
Y-16764D01*
G01X587413D02*
Y-16798D01*
G01Y-17116D02*
Y-16904D01*
G01X587831Y9060D02*
Y-1570D01*
G01Y-6688D02*
Y-17318D01*
G01X588201Y-17568D02*
X588186Y-17439D01*
X588142Y-17315D01*
X588069Y-17201D01*
X587970Y-17099D01*
X587852Y-17016D01*
X587716Y-16955D01*
X587569Y-16917D01*
X587413Y-16904D01*
G01X590488Y-16798D02*
Y-16764D01*
G01X591497Y-18862D02*
Y-18845D01*
G01X591910Y-17679D02*
Y-17890D01*
G01X592056Y-17553D02*
Y-17341D01*
G01X592752Y-17318D02*
Y-6688D01*
G01Y-1570D02*
Y9060D01*
G01X592796Y-16904D02*
Y-17116D01*
G01X570362Y-17548D02*
X570378Y-17396D01*
X570422Y-17249D01*
X570494Y-17114D01*
X570593Y-16994D01*
X570712Y-16896D01*
X570847Y-16824D01*
X570994Y-16779D01*
X571150Y-16764D01*
G01X580031Y-17548D02*
X580047Y-17396D01*
X580091Y-17249D01*
X580163Y-17114D01*
X580262Y-16994D01*
X580381Y-16896D01*
X580517Y-16824D01*
X580663Y-16779D01*
X580819Y-16764D01*
G01X589701Y-17548D02*
X589716Y-17396D01*
X589760Y-17249D01*
X589833Y-17114D01*
X589931Y-16994D01*
X590050Y-16896D01*
X590186Y-16824D01*
X590333Y-16779D01*
X590488Y-16764D01*
G01X570362Y-17780D02*
X570378Y-17651D01*
X570422Y-17527D01*
X570494Y-17412D01*
X570593Y-17310D01*
X570712Y-17228D01*
X570847Y-17167D01*
X570994Y-17129D01*
X571150Y-17116D01*
G01X580031Y-17780D02*
X580047Y-17651D01*
X580091Y-17527D01*
X580163Y-17412D01*
X580262Y-17310D01*
X580381Y-17228D01*
X580517Y-17167D01*
X580663Y-17129D01*
X580819Y-17116D01*
G01X591910Y-17679D02*
X591772Y-18044D01*
X591635Y-18437D01*
X591497Y-18845D01*
G01Y-18862D02*
X591635Y-18522D01*
X591772Y-18195D01*
X591910Y-17890D01*
G01X592056Y-17341D02*
X591910Y-17679D01*
G01Y-17890D02*
X592056Y-17553D01*
G01D02*
X592125Y-17432D01*
X592222Y-17325D01*
X592342Y-17237D01*
X592483Y-17170D01*
X592635Y-17130D01*
X592796Y-17116D01*
G01X570362Y-24077D02*
X578531D01*
G01X580031D02*
X588201D01*
G01X589701D02*
X597870D01*
G01Y-23942D02*
X589701D01*
G01X588201D02*
X580031D01*
G01X578531D02*
X570362D01*
G01X597843Y-23756D02*
X589728D01*
G01X588201D02*
X580031D01*
G01X578531D02*
X570362D01*
G01Y-23671D02*
X578531D01*
G01X580031D02*
X588201D01*
G01X589728D02*
X597843D01*
G01X570362Y-23348D02*
X578531D01*
G01X580031D02*
X588201D01*
G01X589863D02*
X597708D01*
G01Y-23331D02*
X589863D01*
G01X588201D02*
X580031D01*
G01X578531D02*
X570362D01*
G01Y-23097D02*
X578531D01*
G01X580031D02*
X588201D01*
G01X589701D02*
X597870D01*
G01Y-23063D02*
X589701D01*
G01X588201D02*
X580031D01*
G01X578531D02*
X570362D01*
G01X589728Y-23756D02*
Y-23671D01*
G01X589748Y-23615D02*
Y-23689D01*
G01X589863Y-23331D02*
Y-23339D01*
G01D02*
Y-23348D01*
G01X589701Y-23958D02*
X589702Y-23925D01*
X589704Y-23891D01*
X589707Y-23858D01*
X589713Y-23824D01*
X589720Y-23790D01*
X589728Y-23756D01*
G01Y-23671D02*
X589720Y-23702D01*
X589713Y-23736D01*
X589708Y-23768D01*
X589704Y-23803D01*
X589702Y-23838D01*
X589701Y-23872D01*
G01X589728Y-23756D02*
X589735Y-23734D01*
X589741Y-23711D01*
X589748Y-23689D01*
G01D02*
X589863Y-23348D01*
G01X591497Y-18845D02*
X589863Y-23331D01*
G01Y-23348D02*
X591497Y-18862D01*
G01X589748Y-23615D02*
X589741Y-23633D01*
X589735Y-23652D01*
X589728Y-23671D01*
G01X589863Y-23331D02*
X589748Y-23615D01*
G01X605947Y18242D02*
X600703D01*
G01Y26116D02*
X605947D01*
G01X601628Y31917D02*
X601435D01*
G01X600703Y38853D02*
X604563D01*
G01X601435Y39791D02*
X601628D01*
G01X594711Y35141D02*
Y14955D01*
G01X600703Y26116D02*
Y18242D01*
G01Y38853D02*
Y44759D01*
G01X601628Y31917D02*
Y39791D01*
G01X602435Y44759D02*
Y38853D01*
G01Y18242D02*
Y26116D01*
G01X600435Y6877D02*
X601435D01*
G01Y7468D02*
X600435D01*
G01X594711Y14955D02*
X595892Y11019D01*
G01X594711Y14955D02*
X595892Y11019D01*
G01X596876D02*
Y44408D01*
G01X580726Y12877D02*
X582726D01*
G01X580726Y14058D02*
X581726D01*
G01X570050Y18393D02*
X570750D01*
G01X573002D02*
X573702D01*
G01X578908D02*
X579608D01*
G01X575955D02*
X576655D01*
G01X581860D02*
X582560D01*
G01X587766D02*
X588466D01*
G01X584813D02*
X585513D01*
G01X590719D02*
X591419D01*
G01X581726Y18585D02*
X580726D01*
G01X582726Y19766D02*
X580726D01*
G01X591419Y21371D02*
X590719D01*
G01X588466D02*
X587766D01*
G01X585513D02*
X584813D01*
G01X582560D02*
X581860D01*
G01X579608D02*
X578908D01*
G01X576655D02*
X575955D01*
G01X570750D02*
X570050D01*
G01X573702D02*
X573002D01*
G01X591419Y24336D02*
X590719D01*
G01X588466D02*
X587766D01*
G01X585513D02*
X584813D01*
G01X582560D02*
X581860D01*
G01X579608D02*
X578908D01*
G01X576655D02*
X575955D01*
G01X570750D02*
X570050D01*
G01X573702D02*
X573002D01*
G01X591419Y24561D02*
X590719D01*
G01X588466D02*
X587766D01*
G01X585513D02*
X584813D01*
G01X582560D02*
X581860D01*
G01X579608D02*
X578908D01*
G01X576655D02*
X575955D01*
G01X573702D02*
X573002D01*
G01X570750D02*
X570050D01*
G01X582937Y27251D02*
X579984D01*
G01X578984D02*
X575626D01*
G01X589183Y38588D02*
X589316Y38552D01*
X589435Y38447D01*
X589518Y38288D01*
X589549Y38088D01*
G01X577903Y34686D02*
X578713Y34298D01*
X579636Y34147D01*
X580568Y34252D01*
X581463Y34621D01*
X582251Y35238D01*
X582853Y36057D01*
X583236Y37073D01*
G01X582937Y28251D02*
X579984D01*
G01X578984D02*
X575626D01*
G01X582937Y29251D02*
X579984D01*
G01X578984D02*
X575626D01*
G01X582937Y29501D02*
X579984D01*
G01X578984D02*
X575626D01*
G01X582543Y29645D02*
X576020D01*
G01X580575Y31367D02*
X582346D01*
G01X578394Y32851D02*
X576217D01*
G01X587469Y35857D02*
X571046D01*
G01X596876Y36767D02*
X586423D01*
G01X589049Y37588D02*
X587156D01*
G01X584715Y38588D02*
X589183D01*
G01X585387Y39032D02*
X585360D01*
G01X573156D02*
X573128D01*
G01X589518Y39392D02*
X587549D01*
G01X571407Y34257D02*
X576020Y29645D01*
G01X585387Y37940D02*
X587469Y35857D01*
G01X582407Y41985D02*
X585360Y39032D01*
G01X582819Y39341D02*
X582147Y40116D01*
X581321Y40669D01*
X580373Y40987D01*
X579386Y41034D01*
X578450Y40811D01*
X577617Y40337D01*
X576986Y39675D01*
G01X586226Y36569D02*
X587289Y35267D01*
G01X585360Y38069D02*
X586423Y36767D01*
G01X582819Y39341D02*
X582162Y40265D01*
X581263Y40969D01*
X580164Y41398D01*
X579006Y41489D01*
X577868Y41238D01*
X576866Y40682D01*
X576056Y39846D01*
X575521Y38822D01*
X575306Y37666D01*
X575434Y36502D01*
X575883Y35448D01*
X576636Y34547D01*
X577628Y33899D01*
X578767Y33574D01*
X579932Y33592D01*
X581042Y33950D01*
X582001Y34614D01*
X582737Y35547D01*
X583168Y36666D01*
X583246Y37866D01*
X582949Y39065D01*
X582341Y40063D01*
X581483Y40833D01*
X580391Y41340D01*
X579226Y41497D01*
X578083Y41313D01*
X577016Y40790D01*
X576174Y40005D01*
X575591Y39005D01*
X575317Y37852D01*
X575385Y36714D01*
X575778Y35630D01*
X576475Y34697D01*
X577426Y33999D01*
X578526Y33612D01*
X579678Y33560D01*
X580794Y33837D01*
X581735Y34385D01*
X582512Y35195D01*
X583050Y36241D01*
X583258Y37379D01*
X583125Y38551D01*
X582670Y39606D01*
X581916Y40501D01*
X580938Y41136D01*
X579792Y41464D01*
X578664Y41451D01*
X577551Y41101D01*
X576598Y40458D01*
X575851Y39533D01*
X575398Y38387D01*
X575316Y37197D01*
X575571Y36081D01*
X576137Y35079D01*
X576978Y34274D01*
X578039Y33738D01*
X579213Y33540D01*
X580407Y33702D01*
X581459Y34188D01*
X582331Y34961D01*
X582941Y35956D01*
X583237Y37089D01*
X583194Y38249D01*
X582819Y39341D01*
G01X585360Y38069D02*
X586226Y36569D01*
G01X587289Y35267D02*
X586423Y36767D01*
G01X582819Y39341D02*
X583144Y38627D01*
X583286Y37855D01*
X583236Y37073D01*
G01X583237Y38246D02*
X582856Y39363D01*
X582167Y40321D01*
X581227Y41039D01*
X580121Y41452D01*
X578943Y41526D01*
X577787Y41253D01*
X576775Y40664D01*
X575964Y39792D01*
X575447Y38731D01*
X575260Y37567D01*
X575420Y36392D01*
X575909Y35327D01*
X576701Y34434D01*
X577708Y33817D01*
X578847Y33520D01*
X580028Y33566D01*
X581142Y33953D01*
X582102Y34651D01*
X582815Y35597D01*
X583220Y36703D01*
X583287Y37880D01*
X583009Y39030D01*
X582409Y40048D01*
X581535Y40850D01*
X580471Y41361D01*
X579305Y41540D01*
X578135Y41373D01*
X577067Y40876D01*
X576183Y40083D01*
X575572Y39072D01*
X575281Y37928D01*
X575334Y36749D01*
X575727Y35636D01*
X576427Y34685D01*
X577374Y33978D01*
X578484Y33577D01*
X579664Y33515D01*
X580811Y33799D01*
X581824Y34402D01*
X582619Y35274D01*
X583127Y36340D01*
X583304Y37508D01*
X583133Y38676D01*
X582631Y39745D01*
X581846Y40618D01*
X580836Y41228D01*
X579691Y41519D01*
X578512Y41466D01*
X577394Y41070D01*
X576456Y40380D01*
X575748Y39439D01*
X575343Y38330D01*
X575276Y37152D01*
X575557Y35999D01*
X576149Y34995D01*
X577013Y34197D01*
X578076Y33682D01*
X579241Y33497D01*
X580410Y33658D01*
X581479Y34150D01*
X582356Y34925D01*
X582977Y35930D01*
X583279Y37069D01*
X583237Y38246D01*
G01X583144Y38627D02*
X583286Y37855D01*
X583236Y37073D01*
G01D02*
X583194Y38248D01*
X582800Y39377D01*
X582117Y40312D01*
X581180Y41015D01*
X580042Y41425D01*
X578841Y41473D01*
X577662Y41153D01*
X576700Y40547D01*
X575955Y39701D01*
X575466Y38649D01*
X575304Y37437D01*
X575519Y36222D01*
X576038Y35212D01*
X576843Y34375D01*
X577841Y33809D01*
X578955Y33553D01*
X580174Y33640D01*
X581280Y34077D01*
X582165Y34776D01*
X582822Y35701D01*
X583194Y36795D01*
X583238Y37942D01*
X582934Y39097D01*
X582333Y40073D01*
X581460Y40847D01*
X580442Y41325D01*
X579296Y41498D01*
X578081Y41312D01*
X577054Y40818D01*
X576213Y40051D01*
X575602Y39033D01*
X575321Y37904D01*
X575378Y36751D01*
X575783Y35620D01*
X576478Y34695D01*
X577377Y34025D01*
X578465Y33624D01*
X579674Y33559D01*
X580804Y33842D01*
X581781Y34422D01*
X582580Y35293D01*
X583071Y36305D01*
X583261Y37526D01*
X583070Y38734D01*
X582581Y39744D01*
X581814Y40588D01*
X580839Y41180D01*
X579709Y41475D01*
X578504Y41421D01*
X577398Y41025D01*
X576500Y40364D01*
X575798Y39441D01*
X575402Y38402D01*
X575313Y37241D01*
X575592Y36025D01*
X576177Y35030D01*
X577031Y34237D01*
X578102Y33718D01*
X579252Y33540D01*
X580402Y33700D01*
X581470Y34195D01*
X582320Y34949D01*
X582944Y35962D01*
X583236Y37073D01*
G01X570014Y43930D02*
Y38588D01*
G01X570050Y24561D02*
Y18393D01*
G01X570750Y24561D02*
Y18393D01*
G01X571014Y44408D02*
Y36767D01*
G01X571264Y43930D02*
Y38588D01*
G01X571407Y34257D02*
Y40780D01*
G01X572289Y44408D02*
Y36569D01*
G01X572430Y44408D02*
Y37242D01*
G01X573002Y24561D02*
Y18393D01*
G01X573128Y37940D02*
Y44408D01*
G01X573156Y38069D02*
Y44408D01*
G01X573702Y24561D02*
Y18393D01*
G01X574439Y43339D02*
Y39178D01*
G01X574626Y31038D02*
Y26751D01*
G01X575626Y32261D02*
Y26751D01*
G01X575955Y24561D02*
Y18393D01*
G01X576655Y24561D02*
Y18393D01*
G01X578908Y24561D02*
Y18393D01*
G01X578984Y32261D02*
Y26751D01*
G01X579608Y24561D02*
Y18393D01*
G01X579984Y30777D02*
Y26751D01*
G01X580726Y12877D02*
Y19766D01*
G01X581726Y12877D02*
Y19766D01*
G01X581860Y24561D02*
Y18393D01*
G01X582560Y24561D02*
Y18393D01*
G01X582726Y19766D02*
Y12877D01*
G01X582937Y30777D02*
Y26751D01*
G01X583937Y31038D02*
Y26751D01*
G01X584124Y43339D02*
Y39178D01*
G01X584813Y24561D02*
Y18393D01*
G01X585360Y44408D02*
Y38069D01*
G01X585387Y44408D02*
Y37940D01*
G01X585513Y24561D02*
Y18393D01*
G01X586085Y44408D02*
Y37242D01*
G01X586226Y36569D02*
Y44408D01*
G01X587156Y40780D02*
Y34257D01*
G01X587299Y43930D02*
Y38588D01*
G01X587549Y44408D02*
Y36767D01*
G01X587766Y24561D02*
Y18393D01*
G01X588466Y24561D02*
Y18393D01*
G01X588549Y43930D02*
Y38588D01*
G01X589549Y38088D02*
X589539Y38173D01*
X589504Y38258D01*
X589446Y38341D01*
X589363Y38418D01*
X589257Y38484D01*
X589129Y38538D01*
X588981Y38574D01*
X588817Y38588D01*
G01X589518Y44408D02*
Y36767D01*
G01X589549Y43930D02*
Y38088D01*
G01X590719Y24561D02*
Y18393D01*
G01X591419Y24561D02*
Y18393D01*
G01X583236Y37073D02*
X582876Y36100D01*
X582292Y35281D01*
X581502Y34644D01*
X580583Y34257D01*
X579626Y34146D01*
X578698Y34303D01*
X577903Y34687D01*
G01X572092Y36767D02*
X571226Y35267D01*
G01X572289Y36569D02*
X573156Y38069D01*
G01X572092Y36767D02*
X573156Y38069D01*
G01X571226Y35267D02*
X572289Y36569D01*
G01X576987Y39675D02*
X577607Y40330D01*
X578427Y40802D01*
X579354Y41031D01*
X580335Y40994D01*
X581291Y40684D01*
X582130Y40130D01*
X582820Y39341D01*
G01X576108Y41985D02*
X573156Y39032D01*
G01X573128Y37940D02*
X571046Y35857D01*
G01X587156Y34257D02*
X582543Y29645D01*
G01X582937Y30777D02*
G03X582346Y31367I-591J-1D01*
G01X580575D02*
G03X579984Y30777I0J-591D01*
G01X574626Y26751D02*
G03X575626I500J0D01*
G01X578984D02*
G03X579984I500J0D01*
G01X582937D02*
G03X583937I500J0D01*
G01X583612Y37519D02*
G03I-4330J0D01*
G01X582431D02*
G03I-3149J0D01*
G01X576217Y32851D02*
G03X575626Y32261I0J-591D01*
G01X578984D02*
G03X578394Y32851I-590J0D01*
G01X584124Y39178D02*
G03X584715Y38588I591J1D01*
G01X573848D02*
G03X574439Y39178I1J590D01*
G01X589049Y37588D02*
G03X589549Y38088I0J500D01*
G01X587831Y6528D02*
X592752D01*
G01X587831Y9060D02*
X592752D01*
G01X601435Y45223D02*
X600435D01*
G01Y46475D02*
X601435D01*
G01Y47182D02*
X600435D01*
G01Y50541D02*
X601435D01*
G01X600435Y50638D02*
X601435D01*
G01X600435Y51142D02*
X601435D01*
G01X600435Y51171D02*
X601435D01*
G01Y51583D02*
X600435D01*
G01Y52568D02*
X601435D01*
G01X600435Y52975D02*
X601435D01*
G01X600435Y53005D02*
X601435D01*
G01X603123Y53499D02*
X601748D01*
G01X595748D02*
X596748D01*
G01X600435Y53512D02*
X601435D01*
G01Y53605D02*
X600435D01*
G01X601435Y54260D02*
X600435D01*
G01X601435Y54275D02*
X600435D01*
G01X596623Y54749D02*
X595873D01*
G01X601435Y56275D02*
X596915D01*
G01X596623Y59749D02*
X595873D01*
G01X596748Y60999D02*
X595748D01*
G01X603123Y63499D02*
X601748D01*
G01X596915Y66043D02*
X601435D01*
G01X604955Y68043D02*
X600435D01*
G01X595748Y53499D02*
X594748Y53749D01*
G01X595873Y54749D02*
X595373Y54873D01*
G01X597123Y59623D02*
X596623Y59749D01*
G01X597748Y60749D02*
X596748Y60999D01*
G01X595373Y54873D02*
X594748Y55249D01*
G01X597748Y59249D02*
X597123Y59623D01*
G01X594748Y53749D02*
X593998Y54249D01*
G01X598498Y60249D02*
X597748Y60749D01*
G01Y53749D02*
X596748Y53499D01*
G01X597123Y54873D02*
X596623Y54749D01*
G01X595873Y59749D02*
X595373Y59623D01*
G01X595748Y60999D02*
X594748Y60749D01*
G01X598498Y60249D02*
X598998Y59749D01*
G01D02*
X599498Y58999D01*
G01X594373Y55873D02*
X594748Y55249D01*
G01X597748Y59249D02*
X598123Y58623D01*
G01X594248Y56373D02*
X594373Y55873D01*
G01X598123Y58623D02*
X598248Y58123D01*
G01X599498Y58999D02*
X599748Y57999D01*
G01X594248Y58123D02*
Y56373D01*
G01X595915Y65043D02*
Y57275D01*
G01X597451Y66043D02*
Y86182D01*
G01X597788Y66043D02*
Y56275D01*
G01X598248Y58123D02*
Y56373D01*
G01X599435Y66043D02*
Y56275D01*
G01X599748Y56499D02*
Y57999D01*
G01X600230Y56275D02*
Y66043D01*
G01X601640Y77812D02*
Y68043D01*
G01X601748Y63499D02*
Y53499D01*
G01X602435Y68043D02*
Y77812D01*
G01X603123Y63499D02*
Y53499D01*
G01X594373Y58623D02*
X594248Y58123D01*
G01X598248Y56373D02*
X598123Y55873D01*
G01X599748Y56499D02*
X599498Y55499D01*
G01X594748Y59249D02*
X594373Y58623D01*
G01X598123Y55873D02*
X597748Y55249D01*
G01X599498Y55499D02*
X598998Y54749D01*
G01D02*
X598498Y54249D01*
G01X594748Y60749D02*
X593998Y60249D01*
G01X598498Y54249D02*
X597748Y53749D01*
G01X595373Y59623D02*
X594748Y59249D01*
G01X597748Y55249D02*
X597123Y54873D01*
G01X595915Y57275D02*
G03X596915Y56275I1000J0D01*
G01Y66043D02*
G03X595915Y65043I0J-1000D01*
G01X603372Y44408D02*
X641758D01*
G01X600435Y44516D02*
X601435D01*
G01X604563Y44759D02*
X600703D01*
G01X595409Y105171D02*
Y44408D01*
G01X596823Y105171D02*
Y44408D01*
G01X597451D02*
Y56275D01*
G01X598451Y44408D02*
Y105171D01*
G01X603372D02*
Y44408D01*
G01X576020Y45393D02*
X582543D01*
G01X584179Y45528D02*
X574337D01*
G01X584179Y46512D02*
X574337D01*
G01X570050Y48355D02*
X570750D01*
G01X578908D02*
X579608D01*
G01X587766D02*
X588466D01*
G01Y48571D02*
X587766D01*
G01X579608D02*
X578908D01*
G01X570750D02*
X570050D01*
G01X588466Y48667D02*
X587766D01*
G01X579608D02*
X578908D01*
G01X570750D02*
X570050D01*
G01X588466Y48729D02*
X587766D01*
G01X579608D02*
X578908D01*
G01X570750D02*
X570050D01*
G01X588466Y48827D02*
X587766D01*
G01X579608D02*
X578908D01*
G01X570750D02*
X570050D01*
G01X588466Y49812D02*
X587766D01*
G01X579608D02*
X578908D01*
G01X570750D02*
X570050D01*
G01X588466Y49910D02*
X587766D01*
G01X579608D02*
X578908D01*
G01X570750D02*
X570050D01*
G01X588466Y49973D02*
X587766D01*
G01X579608D02*
X578908D01*
G01X570750D02*
X570050D01*
G01X588466Y50068D02*
X587766D01*
G01X579608D02*
X578908D01*
G01X570750D02*
X570050D01*
G01Y50284D02*
X570750D01*
G01X578908D02*
X579608D01*
G01X587766D02*
X588466D01*
G01X573002Y51111D02*
X573702D01*
G01X581860D02*
X582560D01*
G01X590719D02*
X591419D01*
G01Y51327D02*
X590719D01*
G01X582560D02*
X581860D01*
G01X573702D02*
X573002D01*
G01X591419Y51423D02*
X590719D01*
G01X582560D02*
X581860D01*
G01X573702D02*
X573002D01*
G01X591419Y51485D02*
X590719D01*
G01X582560D02*
X581860D01*
G01X573702D02*
X573002D01*
G01X591419Y51583D02*
X590719D01*
G01X582560D02*
X581860D01*
G01X573702D02*
X573002D01*
G01X591419Y52568D02*
X590719D01*
G01X582561D02*
X581861D01*
G01X573702D02*
X573002D01*
G01X591419Y52666D02*
X590719D01*
G01X582560D02*
X581860D01*
G01X573702D02*
X573002D01*
G01X591419Y52729D02*
X590719D01*
G01X582560D02*
X581860D01*
G01X573702D02*
X573002D01*
G01X591419Y52823D02*
X590719D01*
G01X582560D02*
X581860D01*
G01X573702D02*
X573002D01*
G01Y53040D02*
X573702D01*
G01X581860D02*
X582560D01*
G01X590719D02*
X591419D01*
G01X590748Y53499D02*
X589373D01*
G01X586623D02*
X585248D01*
G01X582498D02*
X581123D01*
G01X585513Y53867D02*
X584813D01*
G01X576655D02*
X575955D01*
G01Y54083D02*
X576655D01*
G01X584813D02*
X585513D01*
G01X575955Y54179D02*
X576655D01*
G01X584813D02*
X585513D01*
G01X575955Y54241D02*
X576655D01*
G01X584813D02*
X585513D01*
G01Y54339D02*
X584813D01*
G01X576655D02*
X575955D01*
G01X585513Y55323D02*
X584813D01*
G01X576655D02*
X575955D01*
G01X585513Y55422D02*
X584813D01*
G01X576655D02*
X575955D01*
G01Y55484D02*
X576655D01*
G01X584813D02*
X585513D01*
G01X575955Y55579D02*
X576655D01*
G01X584813D02*
X585513D01*
G01Y55796D02*
X584813D01*
G01X576655D02*
X575955D01*
G01X582498Y60873D02*
X581123D01*
G01X588248Y60999D02*
X587748D01*
G01X584123D02*
X583623D01*
G01X570050Y63316D02*
X570750D01*
G01X578908D02*
X579608D01*
G01X587766D02*
X588466D01*
G01Y63532D02*
X587766D01*
G01X579608D02*
X578908D01*
G01X570750D02*
X570050D01*
G01X588466Y63627D02*
X587766D01*
G01X579608D02*
X578908D01*
G01X570750D02*
X570050D01*
G01X588466Y63690D02*
X587766D01*
G01X579608D02*
X578908D01*
G01X570750D02*
X570050D01*
G01X588466Y63788D02*
X587766D01*
G01X579608D02*
X578908D01*
G01X570750D02*
X570050D01*
G01X588466Y64772D02*
X587766D01*
G01X579608D02*
X578908D01*
G01X570750D02*
X570050D01*
G01X588466Y64871D02*
X587766D01*
G01X579608D02*
X578908D01*
G01X570750D02*
X570050D01*
G01X588466Y64933D02*
X587766D01*
G01X579608D02*
X578908D01*
G01X570750D02*
X570050D01*
G01X588466Y65028D02*
X587766D01*
G01X579608D02*
X578908D01*
G01X570750D02*
X570050D01*
G01Y65245D02*
X570750D01*
G01X578908D02*
X579608D01*
G01X587766D02*
X588466D01*
G01X573002Y66071D02*
X573702D01*
G01X581860D02*
X582560D01*
G01X590719D02*
X591419D01*
G01Y66288D02*
X590719D01*
G01X582560D02*
X581860D01*
G01X573702D02*
X573002D01*
G01X591419Y66383D02*
X590719D01*
G01X582560D02*
X581860D01*
G01X573702D02*
X573002D01*
G01X591419Y66445D02*
X590719D01*
G01X582560D02*
X581860D01*
G01X573702D02*
X573002D01*
G01X591419Y66544D02*
X590719D01*
G01X582560D02*
X581860D01*
G01X573702D02*
X573002D01*
G01X591419Y67528D02*
X590719D01*
G01X582561D02*
X581861D01*
G01X573702D02*
X573002D01*
G01X591419Y67627D02*
X590719D01*
G01X582560D02*
X581860D01*
G01X573702D02*
X573002D01*
G01X591419Y67689D02*
X590719D01*
G01X582560D02*
X581860D01*
G01X573702D02*
X573002D01*
G01X591419Y67784D02*
X590719D01*
G01X582560D02*
X581860D01*
G01X573702D02*
X573002D01*
G01Y68001D02*
X573702D01*
G01X581860D02*
X582560D01*
G01X590719D02*
X591419D01*
G01X585513Y68827D02*
X584813D01*
G01X576655D02*
X575955D01*
G01Y69044D02*
X576655D01*
G01X584813D02*
X585513D01*
G01X575955Y69139D02*
X576655D01*
G01X584813D02*
X585513D01*
G01X575955Y69201D02*
X576655D01*
G01X584813D02*
X585513D01*
G01Y69300D02*
X584813D01*
G01X576655D02*
X575955D01*
G01X585513Y70284D02*
X584813D01*
G01X576655D02*
X575955D01*
G01X585513Y70382D02*
X584813D01*
G01X576655D02*
X575955D01*
G01Y70445D02*
X576655D01*
G01X584813D02*
X585513D01*
G01Y70540D02*
X584813D01*
G01X576655D02*
X575955D01*
G01X585513Y70756D02*
X584813D01*
G01X576655D02*
X575955D01*
G01X584373Y59623D02*
X583748Y59749D01*
G01X588498Y59623D02*
X587873Y59749D01*
G01X584998Y60749D02*
X584123Y60999D01*
G01X589123Y60749D02*
X588248Y60999D01*
G01X585748Y60249D02*
X584998Y60749D01*
G01X589873Y60249D02*
X589123Y60749D01*
G01X587873Y59749D02*
X587373Y59623D01*
G01X583748Y59749D02*
X583248Y59623D01*
G01X584373D02*
X584748Y59249D01*
G01X585748Y60249D02*
X586248Y59749D01*
G01X588498Y59623D02*
X588873Y59249D01*
G01X593498Y54749D02*
X593998Y54249D01*
G01X589873Y60249D02*
X590248Y59749D01*
G01X592998Y55499D02*
X593498Y54749D01*
G01X584748Y59249D02*
X585123Y58623D01*
G01X588873Y59249D02*
X589248Y58623D01*
G01X590248Y59749D02*
X590623Y58999D01*
G01X585123Y58623D02*
X585248Y58123D01*
G01X589248Y58623D02*
X589373Y58123D01*
G01X592748Y56499D02*
X592998Y55499D01*
G01X570050Y48356D02*
Y50282D01*
G01Y63317D02*
Y65243D01*
G01X570750Y48357D02*
Y50283D01*
G01Y63318D02*
Y65243D01*
G01X573002Y51112D02*
Y53038D01*
G01Y66073D02*
Y67999D01*
G01X573702Y51113D02*
Y53039D01*
G01Y66073D02*
Y67999D01*
G01X575955Y53868D02*
Y55794D01*
G01Y68829D02*
Y70755D01*
G01X576655Y53869D02*
Y55795D01*
G01Y68829D02*
Y70755D01*
G01X578908Y48356D02*
Y50282D01*
G01Y63317D02*
Y65243D01*
G01X579608Y48357D02*
Y50283D01*
G01Y63318D02*
Y65243D01*
G01X581123Y60873D02*
Y53499D01*
G01X581860Y51112D02*
Y53038D01*
G01Y66073D02*
Y67999D01*
G01X582498Y58623D02*
Y53499D01*
G01Y60873D02*
Y60249D01*
G01X582560Y51113D02*
Y53039D01*
G01Y66073D02*
Y67999D01*
G01X584813Y53868D02*
Y55794D01*
G01Y68829D02*
Y70755D01*
G01X585248Y58123D02*
Y53499D01*
G01X585513Y53869D02*
Y55795D01*
G01Y68829D02*
Y70755D01*
G01X586623Y58623D02*
Y53499D01*
G01X587766Y48356D02*
Y50282D01*
G01Y63317D02*
Y65243D01*
G01X588466Y48357D02*
Y50283D01*
G01Y63318D02*
Y65243D01*
G01X589373Y58123D02*
Y53499D01*
G01X590623Y58999D02*
X590748Y57999D01*
G01X590719Y51112D02*
Y53038D01*
G01Y66073D02*
Y67999D01*
G01X590748Y57999D02*
Y53499D01*
G01X591419Y51113D02*
Y53039D01*
G01Y66073D02*
Y67999D01*
G01X592748Y57999D02*
Y56499D01*
G01X592998Y58999D02*
X592748Y57999D01*
G01X582748Y59249D02*
X582498Y58623D01*
G01X586873Y59249D02*
X586623Y58623D01*
G01Y60373D02*
X586248Y59749D01*
G01X593498D02*
X592998Y58999D01*
G01X582873Y60749D02*
X582498Y60249D01*
G01X593998D02*
X593498Y59749D01*
G01X583248Y59623D02*
X582748Y59249D01*
G01X587123Y60749D02*
X586623Y60373D01*
G01X587373Y59623D02*
X586873Y59249D01*
G01X587748Y60999D02*
X587123Y60749D01*
G01X583623Y60999D02*
X582873Y60749D01*
G01X589518Y41062D02*
X587549D01*
G01X582407Y41985D02*
X576108D01*
G01X617156Y43930D02*
X584715D01*
G01X582543Y45393D02*
X587156Y40780D01*
G01X574337Y46512D02*
Y44408D01*
G01X584179Y46512D02*
Y44408D01*
G01X576020Y45393D02*
X571407Y40780D01*
G01X584715Y43930D02*
G03X584124Y43339I0J-591D01*
G01X574439D02*
G03X573848Y43930I-591J0D01*
G01X600435Y85182D02*
X601435D01*
G01Y86182D02*
X596915D01*
G01X600703Y91636D02*
X604563D01*
G01X596915Y94578D02*
X601435D01*
G01X604955Y96578D02*
X600435D01*
G01X604563Y97542D02*
X600703D01*
G01X600435Y103048D02*
X601435D01*
G01Y103974D02*
X600435D01*
G01X601435Y104974D02*
X600435D01*
G01X600616Y105169D02*
X601207D01*
G01X594754Y105958D02*
Y106958D01*
G01X595915Y93578D02*
Y87182D01*
G01X597451Y94578D02*
Y105171D01*
G01X597788Y94578D02*
Y86182D01*
G01X599435Y94578D02*
Y86182D01*
G01X600230D02*
Y94578D01*
G01X600703Y91636D02*
Y97542D01*
G01X601640Y105171D02*
Y96578D01*
G01X602435Y91636D02*
Y105171D01*
G01X596915Y94578D02*
G03X595915Y93578I0J-1000D01*
G01Y87182D02*
G03X596915Y86182I1000J0D01*
G01X602435Y107942D02*
G03X600712Y106958I0J-2000D01*
G01X600435Y77812D02*
X604955D01*
G01X601435Y78812D02*
X600435D01*
G01X601435Y77580D02*
X603372Y75643D01*
G01X600435Y77628D02*
X598451Y75643D01*
G01X588466Y79733D02*
X587766D01*
G01X579608D02*
X578908D01*
G01X570750D02*
X570050D01*
G01X588466Y79831D02*
X587766D01*
G01X579608D02*
X578908D01*
G01X570750D02*
X570050D01*
G01X588466Y79894D02*
X587766D01*
G01X579608D02*
X578908D01*
G01X570750D02*
X570050D01*
G01X588466Y79989D02*
X587766D01*
G01X579608D02*
X578908D01*
G01X570750D02*
X570050D01*
G01Y80205D02*
X570750D01*
G01X578908D02*
X579608D01*
G01X587766D02*
X588466D01*
G01X573002Y81032D02*
X573702D01*
G01X581860D02*
X582560D01*
G01X590719D02*
X591419D01*
G01Y81249D02*
X590719D01*
G01X582560D02*
X581860D01*
G01X573702D02*
X573002D01*
G01X591419Y81344D02*
X590719D01*
G01X582560D02*
X581860D01*
G01X573702D02*
X573002D01*
G01X591419Y81406D02*
X590719D01*
G01X582560D02*
X581860D01*
G01X573702D02*
X573002D01*
G01X591419Y81505D02*
X590719D01*
G01X582560D02*
X581860D01*
G01X573702D02*
X573002D01*
G01X591419Y82489D02*
X590719D01*
G01X582561D02*
X581861D01*
G01X573702D02*
X573002D01*
G01X591419Y82587D02*
X590719D01*
G01X582560D02*
X581860D01*
G01X573702D02*
X573002D01*
G01X591419Y82650D02*
X590719D01*
G01X582560D02*
X581860D01*
G01X573702D02*
X573002D01*
G01X591419Y82745D02*
X590719D01*
G01X582560D02*
X581860D01*
G01X573702D02*
X573002D01*
G01Y82961D02*
X573702D01*
G01X581860D02*
X582560D01*
G01X590719D02*
X591419D01*
G01X585513Y83788D02*
X584813D01*
G01X576655D02*
X575955D01*
G01Y84005D02*
X576655D01*
G01X584813D02*
X585513D01*
G01X575955Y84100D02*
X576655D01*
G01X584813D02*
X585513D01*
G01X575955Y84162D02*
X576655D01*
G01X584813D02*
X585513D01*
G01Y84260D02*
X584813D01*
G01X576655D02*
X575955D01*
G01X585513Y85245D02*
X584813D01*
G01X576655D02*
X575955D01*
G01X585513Y85343D02*
X584813D01*
G01X576655D02*
X575955D01*
G01Y85406D02*
X576655D01*
G01X584813D02*
X585513D01*
G01Y85501D02*
X584813D01*
G01X576655D02*
X575955D01*
G01X585513Y85717D02*
X584813D01*
G01X576655D02*
X575955D01*
G01X570050Y93237D02*
X570750D01*
G01X578908D02*
X579608D01*
G01X587766D02*
X588466D01*
G01Y93453D02*
X587766D01*
G01X579608D02*
X578908D01*
G01X570750D02*
X570050D01*
G01X588466Y93549D02*
X587766D01*
G01X579608D02*
X578908D01*
G01X570750D02*
X570050D01*
G01X588466Y93611D02*
X587766D01*
G01X579608D02*
X578908D01*
G01X570750D02*
X570050D01*
G01X588466Y93709D02*
X587766D01*
G01X579608D02*
X578908D01*
G01X570750D02*
X570050D01*
G01X588466Y94693D02*
X587766D01*
G01X579608D02*
X578908D01*
G01X570750D02*
X570050D01*
G01X588466Y94792D02*
X587766D01*
G01X579608D02*
X578908D01*
G01X570750D02*
X570050D01*
G01X588466Y94855D02*
X587766D01*
G01X579608D02*
X578908D01*
G01X570750D02*
X570050D01*
G01X588466Y94949D02*
X587766D01*
G01X579608D02*
X578908D01*
G01X570750D02*
X570050D01*
G01Y95166D02*
X570750D01*
G01X578908D02*
X579608D01*
G01X587766D02*
X588466D01*
G01X573002Y95993D02*
X573702D01*
G01X581860D02*
X582560D01*
G01X590719D02*
X591419D01*
G01Y96209D02*
X590719D01*
G01X582560D02*
X581860D01*
G01X573702D02*
X573002D01*
G01X591419Y96305D02*
X590719D01*
G01X582560D02*
X581860D01*
G01X573702D02*
X573002D01*
G01X591419Y96367D02*
X590719D01*
G01X582560D02*
X581860D01*
G01X573702D02*
X573002D01*
G01X591419Y96465D02*
X590719D01*
G01X582560D02*
X581860D01*
G01X573702D02*
X573002D01*
G01X591419Y97449D02*
X590719D01*
G01X582561D02*
X581861D01*
G01X573702D02*
X573002D01*
G01X591419Y97548D02*
X590719D01*
G01X582560D02*
X581860D01*
G01X573702D02*
X573002D01*
G01X591419Y97610D02*
X590719D01*
G01X582560D02*
X581860D01*
G01X573702D02*
X573002D01*
G01X591419Y97705D02*
X590719D01*
G01X582560D02*
X581860D01*
G01X573702D02*
X573002D01*
G01Y97922D02*
X573702D01*
G01X581860D02*
X582560D01*
G01X590719D02*
X591419D01*
G01X585513Y98749D02*
X584813D01*
G01X576655D02*
X575955D01*
G01Y98965D02*
X576655D01*
G01X584813D02*
X585513D01*
G01X575955Y99060D02*
X576655D01*
G01X584813D02*
X585513D01*
G01X575955Y99123D02*
X576655D01*
G01X584813D02*
X585513D01*
G01Y99221D02*
X584813D01*
G01X576655D02*
X575955D01*
G01X585513Y100205D02*
X584813D01*
G01X576655D02*
X575955D01*
G01X585513Y100304D02*
X584813D01*
G01X576655D02*
X575955D01*
G01Y100366D02*
X576655D01*
G01X584813D02*
X585513D01*
G01Y100461D02*
X584813D01*
G01X576655D02*
X575955D01*
G01X585513Y100678D02*
X584813D01*
G01X576655D02*
X575955D01*
G01X569668Y106958D02*
Y105958D01*
G01X570050Y93238D02*
Y95164D01*
G01X570750Y93239D02*
Y95165D01*
G01X571011Y105958D02*
Y106958D01*
G01X571823D02*
Y105958D01*
G01X571915D02*
Y106958D01*
G01X572401Y105958D02*
Y106958D01*
G01X572453Y105958D02*
Y106958D01*
G01X572860Y105958D02*
Y106958D01*
G01X573002Y81034D02*
Y82960D01*
G01Y95994D02*
Y97920D01*
G01X573702Y81034D02*
Y82960D01*
G01Y95995D02*
Y97921D01*
G01X573844Y106958D02*
Y105958D01*
G01X574256D02*
Y106958D01*
G01X574307Y105958D02*
Y106958D01*
G01X574789Y105958D02*
Y106958D01*
G01X574886Y105958D02*
Y106958D01*
G01X575538Y105958D02*
Y106958D01*
G01X575955Y83790D02*
Y85716D01*
G01Y98750D02*
Y100676D01*
G01X576305Y102336D02*
Y105171D01*
G01Y105958D02*
Y106958D01*
G01X576655Y83790D02*
Y85716D01*
G01Y98751D02*
Y100677D01*
G01X577038Y105958D02*
Y106958D01*
G01X577683Y102336D02*
Y105171D01*
G01X578908Y93238D02*
Y95164D01*
G01X579608Y93239D02*
Y95165D01*
G01X581860Y81034D02*
Y82960D01*
G01Y95994D02*
Y97920D01*
G01X582211Y105958D02*
Y106958D01*
G01X582560Y81034D02*
Y82960D01*
G01Y95995D02*
Y97921D01*
G01X584813Y83790D02*
Y85716D01*
G01Y98750D02*
Y100676D01*
G01X585513Y83790D02*
Y85716D01*
G01Y98751D02*
Y100677D01*
G01X586738Y105171D02*
Y102336D01*
G01X587384Y106958D02*
Y105958D01*
G01X587766Y93238D02*
Y95164D01*
G01X588116Y105171D02*
Y102336D01*
G01X588466Y93239D02*
Y95165D01*
G01X588884Y105958D02*
Y106958D01*
G01X589539D02*
Y105958D01*
G01X589632D02*
Y106958D01*
G01X589892D02*
Y105958D01*
G01X589896Y105171D02*
Y106958D01*
G01X590118Y105958D02*
Y106958D01*
G01X590169Y105958D02*
Y106958D01*
G01X590577Y105958D02*
Y106958D01*
G01X590719Y81034D02*
Y82960D01*
G01Y95994D02*
Y97920D01*
G01X591419Y81034D02*
Y82960D01*
G01Y95995D02*
Y97921D01*
G01X591561Y106958D02*
Y105958D01*
G01X591892Y106958D02*
Y105958D01*
G01X591973D02*
Y106958D01*
G01X592024Y105958D02*
Y106958D01*
G01X592506Y105958D02*
Y106958D01*
G01X592603Y105958D02*
Y106958D01*
G01X592644Y105171D02*
Y102336D01*
G01X592892Y106958D02*
Y105958D01*
G01X593410Y106958D02*
Y105958D01*
G01X570050Y78276D02*
X570750D01*
G01X578908D02*
X579608D01*
G01X587766D02*
X588466D01*
G01Y78493D02*
X587766D01*
G01X579608D02*
X578908D01*
G01X570750D02*
X570050D01*
G01X588466Y78588D02*
X587766D01*
G01X579608D02*
X578908D01*
G01X570750D02*
X570050D01*
G01X588466Y78650D02*
X587766D01*
G01X579608D02*
X578908D01*
G01X570750D02*
X570050D01*
G01X588466Y78749D02*
X587766D01*
G01X579608D02*
X578908D01*
G01X570750D02*
X570050D01*
G01Y78278D02*
Y80204D01*
G01X570750Y78278D02*
Y80204D01*
G01X578908Y78278D02*
Y80204D01*
G01X579608Y78278D02*
Y80204D01*
G01X587766Y78278D02*
Y80204D01*
G01X588466Y78278D02*
Y80204D01*
G01X597175Y140307D02*
X610955D01*
G01X609478Y151364D02*
X597175Y140307D01*
G01X606356Y107942D02*
X602435D01*
G01X610955Y137794D02*
X593238D01*
G01X575030D02*
X572077D01*
G01D02*
Y148851D01*
G01X575030Y161416D02*
Y137794D01*
G01X593238D02*
Y140307D01*
G01D02*
X607018Y152872D01*
G01X601112Y158903D02*
X598652Y158401D01*
G01X598159Y160914D02*
X601604Y161416D01*
G01X603081Y158903D02*
X601112D01*
G01X601604Y161416D02*
X603573D01*
G01X605541Y158401D02*
X603081Y158903D01*
G01X597175Y157395D02*
X596191Y155888D01*
G01X594222Y157898D02*
X596191Y159908D01*
G01X598652Y158401D02*
X597175Y157395D01*
G01X596191Y159908D02*
X598159Y160914D01*
G01X596191Y155888D02*
X593730D01*
G01X572077Y161416D02*
X575030D01*
G01X588317Y154882D02*
X589301Y153375D01*
G01X572077Y151867D02*
Y161416D01*
G01X593730Y155888D02*
X594222Y157898D01*
G01X578967Y149856D02*
X588317Y154882D01*
G01X589301Y153375D02*
X582411Y149856D01*
G01D02*
X589301Y146338D01*
G01X588317Y144830D02*
X578967Y149856D01*
G01X589301Y146338D02*
X588317Y144830D01*
G01X594587Y883464D02*
Y892519D01*
G01X596752D02*
Y883464D01*
G01X597736D02*
Y892519D01*
G01X599902D02*
Y883464D01*
G01X600886D02*
Y892519D01*
G01X603051D02*
Y883464D01*
G01D02*
X600886D01*
G01X599902D02*
X597736D01*
G01X596752D02*
X594587D01*
G01X571555Y892519D02*
Y883464D01*
G01X572539D02*
Y892519D01*
G01X574705D02*
Y883464D01*
G01X575689D02*
Y892519D01*
G01X577854D02*
Y883464D01*
G01X578839D02*
Y892519D01*
G01X581004D02*
Y883464D01*
G01X581988D02*
Y892519D01*
G01X584154D02*
Y883464D01*
G01X585138D02*
Y892519D01*
G01X587303D02*
Y883464D01*
G01X588287D02*
Y892519D01*
G01X590453D02*
Y883464D01*
G01X591437D02*
Y892519D01*
G01X593602D02*
Y883464D01*
G01D02*
X591437D01*
G01X590453D02*
X588287D01*
G01X587303D02*
X585138D01*
G01X584154D02*
X581988D01*
G01X581004D02*
X578839D01*
G01X577854D02*
X575689D01*
G01X574705D02*
X572539D01*
G01X597736Y892519D02*
X599902D01*
G01X594587D02*
X596752D01*
G01X600886D02*
X603051D01*
G01X572539D02*
X574705D01*
G01X578839D02*
X581004D01*
G01X575689D02*
X577854D01*
G01X581988D02*
X584154D01*
G01X588287D02*
X590453D01*
G01X585138D02*
X587303D01*
G01X591437D02*
X593602D01*
G01X621665Y-1120610D02*
Y-1139623D01*
G01X625700Y-727083D02*
Y-636532D01*
G01Y-545981D02*
Y-636532D01*
G01X616317Y-654071D02*
X615595Y-653584D01*
X614874Y-652610D01*
Y-651635D01*
X615595Y-650661D01*
X616317Y-650174D01*
X617761D01*
X618483Y-650661D01*
G01X621370Y-641891D02*
X622813Y-642866D01*
X623535Y-643840D01*
Y-644814D01*
X622813Y-645789D01*
X622091Y-646276D01*
G01X619204Y-642866D02*
X620648Y-641891D01*
X621370D01*
G01X618483Y-650661D02*
X619926Y-652610D01*
X621370Y-653584D01*
X623535Y-654071D01*
Y-650174D01*
G01X615595Y-645789D02*
X614874Y-644814D01*
Y-643840D01*
X615595Y-642866D01*
X616317Y-642379D01*
X617039D01*
X617761Y-642866D01*
X618483Y-643840D01*
X619204Y-642866D01*
G01X618483Y-644814D02*
Y-643840D01*
G01X623535Y-636532D02*
Y-637019D01*
X622813D01*
X623535Y-636532D01*
G01Y-620942D02*
X622813Y-621916D01*
X622091Y-622403D01*
X620648Y-622890D01*
X617761D01*
X616317Y-622403D01*
X615595Y-621916D01*
X614874Y-620942D01*
X615595Y-619967D01*
X616317Y-619480D01*
X617761Y-618993D01*
X620648D01*
X622091Y-619480D01*
X622813Y-619967D01*
X623535Y-620942D01*
G01Y-628737D02*
X622813Y-629711D01*
X622091Y-630198D01*
X620648Y-630686D01*
X617761D01*
X616317Y-630198D01*
X615595Y-629711D01*
X614874Y-628737D01*
X615595Y-627762D01*
X616317Y-627275D01*
X617761Y-626788D01*
X620648D01*
X622091Y-627275D01*
X622813Y-627762D01*
X623535Y-628737D01*
G01X635692Y-98447D02*
X634717Y-97725D01*
X634230Y-97003D01*
X633743Y-95560D01*
Y-92672D01*
X634230Y-91229D01*
X634717Y-90507D01*
X635692Y-89785D01*
X636666Y-90507D01*
X637154Y-91229D01*
X637641Y-92672D01*
Y-95560D01*
X637154Y-97003D01*
X636666Y-97725D01*
X635692Y-98447D01*
G01X620101Y-89785D02*
Y-98447D01*
G01X612306D02*
X611331Y-97725D01*
X610844Y-97003D01*
X610357Y-95560D01*
Y-92672D01*
X610844Y-91229D01*
X611331Y-90507D01*
X612306Y-89785D01*
X613280Y-90507D01*
X613768Y-91229D01*
X614255Y-92672D01*
Y-95560D01*
X613768Y-97003D01*
X613280Y-97725D01*
X612306Y-98447D01*
G01X625948Y-95560D02*
X626435Y-94116D01*
X627896Y-93394D01*
X629358Y-94116D01*
X629845Y-95560D01*
X629358Y-97003D01*
X628871Y-97725D01*
X627896Y-98447D01*
X626922Y-97725D01*
X626435Y-97003D01*
X625948Y-95560D01*
Y-92672D01*
X626435Y-91229D01*
X626922Y-90507D01*
X627896Y-89785D01*
X628871Y-90507D01*
X629358Y-91229D01*
G01X641177Y-31255D02*
X633009Y-31261D01*
G01X658981Y-42635D02*
X629503D01*
G01X658381Y-41435D02*
X630104D01*
G01X641177Y-33775D02*
X632994D01*
G01X641177Y-33102D02*
X633008D01*
G01Y-32967D02*
X641177D01*
G01X633008Y-30829D02*
X641177D01*
G01Y-30744D02*
X633008D01*
G01X628381Y-41928D02*
X628796Y-42342D01*
G01X631522Y-33775D02*
X631516Y-33744D01*
X631512Y-33713D01*
X631509Y-33682D01*
G01Y-33663D02*
X631512Y-33701D01*
X631516Y-33738D01*
X631522Y-33775D01*
G01X631509Y-33682D02*
X631508Y-33647D01*
G01Y-33621D02*
X631509Y-33663D01*
G01X627589Y-41832D02*
Y-40398D01*
G01X627904Y-32749D02*
Y-34319D01*
G01X631509Y-33663D02*
Y-33682D01*
G01X631508Y-17548D02*
Y-33647D01*
G01X633008D02*
Y-17548D01*
G01X633007Y-33663D02*
Y-33682D01*
G01X636609Y-38879D02*
Y-33339D01*
G01X633007Y-33663D02*
X633008Y-33621D01*
G01Y-33647D02*
X633007Y-33682D01*
G01D02*
X633004Y-33713D01*
X633000Y-33744D01*
X632994Y-33775D01*
G01D02*
X633000Y-33738D01*
X633004Y-33701D01*
X633007Y-33663D01*
G01X628796Y-42342D02*
G03X629503Y-42635I707J707D01*
G01X628381Y-41928D02*
G03X627674Y-41635I-707J-707D01*
G01X629144Y-40670D02*
G03X630104Y-41435I959J219D01*
G01X629144Y-40670D02*
G03X627589Y-40845I-768J-175D01*
G01X636609Y-38879D02*
G03X637199Y-39469I590J0D01*
G01X636609Y-38564D02*
G03X637199Y-39154I590J0D01*
G01X631522Y-33775D02*
G03X632258Y-34378I734J145D01*
G01D02*
G03X632994Y-33775I2J748D01*
G01X637199Y-32749D02*
G03X636609Y-33339I0J-590D01*
G01X637199Y-33249D02*
G03X636609Y-33839I0J-590D01*
G01X632258Y-32016D02*
G03X633008Y-31261I2J748D01*
G01X631508D02*
G03X632258Y-32016I748J-7D01*
G01X627589Y-41835D02*
X617589D01*
G01X627674Y-41635D02*
X617503D01*
G01X627589Y-41461D02*
X617589D01*
G01Y-41403D02*
X627589D01*
G01X617589Y-41135D02*
X627589D01*
G01Y-41107D02*
X617589D01*
G01X608175Y-39469D02*
X604341D01*
G01X618255Y-39467D02*
X626922D01*
G01X626589Y-39440D02*
X618589D01*
G01X607978Y-39154D02*
X604341D01*
G01X603508Y-34338D02*
X603442D01*
G01X617274Y-34319D02*
X627904D01*
G01X631522Y-33775D02*
X623324D01*
G01X621853D02*
X613655D01*
G01X612183D02*
X604000D01*
G01X608175Y-33249D02*
X604341D01*
G01X631508Y-33102D02*
X623339D01*
G01X621839D02*
X613669D01*
G01X612169D02*
X604000D01*
G01Y-32967D02*
X612169D01*
G01X613669D02*
X621839D01*
G01X623339D02*
X631508D01*
G01X631507Y-31261D02*
X623339D01*
G01X621838D02*
X613670D01*
G01X604000Y-30829D02*
X612169D01*
G01X613669D02*
X621839D01*
G01X623339D02*
X631508D01*
G01Y-30744D02*
X623339D01*
G01X621839D02*
X613669D01*
G01X612169D02*
X604000D01*
G01X612169Y-31261D02*
X604000Y-31255D01*
G01X612183Y-33775D02*
X612178Y-33744D01*
X612173Y-33713D01*
X612170Y-33682D01*
G01Y-33663D02*
X612173Y-33701D01*
X612178Y-33738D01*
X612183Y-33775D01*
G01X621840Y-33663D02*
X621843Y-33701D01*
X621847Y-33738D01*
X621853Y-33775D01*
G01D02*
X621847Y-33744D01*
X621843Y-33713D01*
X621840Y-33682D01*
G01X612170D02*
X612169Y-33647D01*
G01X621840Y-33682D02*
X621839Y-33647D01*
G01X612169Y-33621D02*
X612170Y-33663D01*
G01X621839Y-33621D02*
X621840Y-33663D01*
G01X603750Y-38879D02*
Y-33339D01*
G01X604000Y-33845D02*
Y-17548D01*
G01X604972Y-35399D02*
Y-37336D01*
G01X608569Y-33339D02*
Y-38564D01*
G01X608766Y-33839D02*
Y-38879D01*
G01X612170Y-33682D02*
Y-33663D01*
G01X612169Y-17548D02*
Y-33647D01*
G01X613669D02*
Y-17548D01*
G01Y-33663D02*
Y-33682D01*
G01X617274Y-34319D02*
Y-32749D01*
G01X617589Y-41832D02*
Y-40398D01*
G01X619705Y-34319D02*
Y-32749D01*
G01X620324D02*
Y-34319D01*
G01X621840Y-33682D02*
Y-33663D01*
G01X621839Y-17548D02*
Y-33647D01*
G01X623339D02*
Y-17548D01*
G01X623338Y-33663D02*
Y-33682D01*
G01X624853Y-34319D02*
Y-32749D01*
G01X625473D02*
Y-34319D01*
G01X613669Y-33663D02*
Y-33621D01*
G01X623338Y-33663D02*
X623339Y-33621D01*
G01X613669Y-33647D02*
Y-33682D01*
G01X623339Y-33647D02*
X623338Y-33682D01*
G01X613669D02*
X613666Y-33713D01*
X613661Y-33744D01*
X613655Y-33775D01*
G01X623338Y-33682D02*
X623335Y-33713D01*
X623331Y-33744D01*
X623324Y-33775D01*
G01X613655D02*
X613661Y-33738D01*
X613666Y-33701D01*
X613669Y-33663D01*
G01X623324Y-33775D02*
X623331Y-33738D01*
X623335Y-33701D01*
X623338Y-33663D01*
G01X616796Y-41928D02*
X616381Y-42342D01*
G01X603972Y-38336D02*
G03X604972Y-37336I0J1000D01*
G01X608175Y-39469D02*
G03X608766Y-38879I0J591D01*
G01X603750D02*
G03X604341Y-39469I591J1D01*
G01X603750Y-38564D02*
G03X604341Y-39154I591J1D01*
G01X607978D02*
G03X608569Y-38564I1J590D01*
G01X604972Y-35399D02*
G03X603972Y-34399I-1000J0D01*
G01X608569Y-33339D02*
G03X607978Y-32749I-590J0D01*
G01X604341D02*
G03X603750Y-33339I0J-591D01*
G01X604341Y-33249D02*
G03X603750Y-33839I0J-591D01*
G01X608766D02*
G03X608175Y-33249I-591J-1D01*
G01X608569Y-33839D02*
G03X607978Y-33249I-590J0D01*
G01X603508Y-34338D02*
G03X604000Y-33845I0J492D01*
G01X603500Y-32016D02*
G03X604000Y-31524I8J492D01*
G01X617503Y-41635D02*
G03X616796Y-41928I0J-1000D01*
G01X615674Y-42635D02*
G03X616381Y-42342I0J1000D01*
G01X618589Y-39440D02*
G03X617589Y-40440I0J-1000D01*
G01X615074Y-41435D02*
G03X616031Y-40679I0J984D01*
G01X618255Y-39467D02*
G03X617589Y-40398I318J-931D01*
G01Y-40845D02*
G03X616031Y-40679I-788J0D01*
G01X627589Y-40440D02*
G03X626589Y-39440I-1000J0D01*
G01X627589Y-40398D02*
G03X626922Y-39467I-984J-1D01*
G01X612183Y-33775D02*
G03X612919Y-34378I734J145D01*
G01D02*
G03X613655Y-33775I2J748D01*
G01X621853D02*
G03X622589Y-34378I734J145D01*
G01D02*
G03X623324Y-33775I1J748D01*
G01X622589Y-32016D02*
G03X623339Y-31261I2J748D01*
G01X621839D02*
G03X622589Y-32016I748J-7D01*
G01X612919D02*
G03X613669Y-31261I2J748D01*
G01X612170D02*
G03X612919Y-32016I748J-7D01*
G01X633795Y-16798D02*
X633643Y-16813D01*
X633495Y-16857D01*
X633360Y-16929D01*
X633239Y-17028D01*
X633141Y-17146D01*
X633069Y-17281D01*
X633024Y-17427D01*
X633008Y-17582D01*
G01X636103Y-16904D02*
X635944Y-16918D01*
X635793Y-16958D01*
X635654Y-17023D01*
X635531Y-17112D01*
X635433Y-17218D01*
X635363Y-17341D01*
G01X639381Y-18862D02*
X634804D01*
G01Y-18845D02*
X639381D01*
G01X641177Y-18516D02*
X633008D01*
G01Y-18481D02*
X641177D01*
G01Y-18138D02*
X633008D01*
G01Y-18104D02*
X641177D01*
G01X635217Y-17890D02*
X638969D01*
G01Y-17679D02*
X635217D01*
G01X636059Y-17318D02*
X631138D01*
G01X636103Y-17116D02*
X638083D01*
G01Y-16904D02*
X636103D01*
G01X633795Y-16798D02*
X640390D01*
G01Y-16764D02*
X633795D01*
G01X636059Y-14786D02*
X631138D01*
G01Y-14307D02*
X636059D01*
G01Y-9699D02*
X631138D01*
G01Y-9220D02*
X636059D01*
G01X631138Y-6688D02*
X636059D01*
G01Y-1570D02*
X631138D01*
G01X636059Y962D02*
X631138D01*
G01Y1441D02*
X636059D01*
G01Y6049D02*
X631138D01*
G01X630720Y-17116D02*
X630874Y-17128D01*
X631021Y-17166D01*
X631156Y-17227D01*
X631278Y-17310D01*
X631375Y-17410D01*
X631448Y-17525D01*
X631493Y-17649D01*
X631508Y-17780D01*
G01X630720Y-16764D02*
X630874Y-16779D01*
X631021Y-16823D01*
X631156Y-16895D01*
X631278Y-16994D01*
X631375Y-17112D01*
X631448Y-17247D01*
X631493Y-17393D01*
X631508Y-17548D01*
G01Y-17582D02*
X631493Y-17430D01*
X631449Y-17284D01*
X631376Y-17149D01*
X631278Y-17028D01*
X631159Y-16931D01*
X631023Y-16858D01*
X630876Y-16814D01*
X630720Y-16798D01*
G01X631508Y-17568D02*
X631493Y-17439D01*
X631449Y-17315D01*
X631376Y-17201D01*
X631278Y-17099D01*
X631159Y-17016D01*
X631023Y-16955D01*
X630876Y-16917D01*
X630720Y-16904D01*
G01Y-16764D02*
Y-16798D01*
G01Y-17116D02*
Y-16904D01*
G01X631138Y9060D02*
Y-1570D01*
G01Y-6688D02*
Y-17318D01*
G01X633795Y-16798D02*
Y-16764D01*
G01X634804Y-18862D02*
Y-18845D01*
G01X635217Y-17679D02*
Y-17890D01*
G01X635363Y-17553D02*
Y-17341D01*
G01X636059Y-17318D02*
Y-6688D01*
G01Y-1570D02*
Y9060D01*
G01X636103Y-16904D02*
Y-17116D01*
G01X633008Y-17548D02*
X633023Y-17396D01*
X633067Y-17249D01*
X633140Y-17114D01*
X633239Y-16994D01*
X633357Y-16896D01*
X633493Y-16824D01*
X633640Y-16779D01*
X633795Y-16764D01*
G01X635217Y-17679D02*
X635080Y-18044D01*
X634942Y-18437D01*
X634804Y-18845D01*
G01Y-18862D02*
X634942Y-18522D01*
X635080Y-18195D01*
X635217Y-17890D01*
G01X635363Y-17341D02*
X635217Y-17679D01*
G01Y-17890D02*
X635363Y-17553D01*
G01D02*
X635432Y-17432D01*
X635529Y-17325D01*
X635649Y-17237D01*
X635790Y-17170D01*
X635942Y-17130D01*
X636103Y-17116D01*
G01X633008Y-24077D02*
X641177D01*
G01Y-23942D02*
X633008D01*
G01X641150Y-23756D02*
X633035D01*
G01Y-23671D02*
X641150D01*
G01X633170Y-23348D02*
X641015D01*
G01Y-23331D02*
X633170D01*
G01X633008Y-23097D02*
X641177D01*
G01Y-23063D02*
X633008D01*
G01X633035Y-23756D02*
Y-23671D01*
G01X633056Y-23615D02*
Y-23689D01*
G01X633170Y-23331D02*
Y-23339D01*
G01D02*
Y-23348D01*
G01X633008Y-23958D02*
X633009Y-23925D01*
X633011Y-23891D01*
X633015Y-23858D01*
X633020Y-23824D01*
X633027Y-23790D01*
X633035Y-23756D01*
G01Y-23671D02*
X633028Y-23702D01*
X633020Y-23736D01*
X633015Y-23768D01*
X633011Y-23803D01*
X633009Y-23838D01*
X633008Y-23872D01*
G01X633035Y-23756D02*
X633042Y-23734D01*
X633048Y-23711D01*
X633056Y-23689D01*
G01D02*
X633170Y-23348D01*
G01X634804Y-18845D02*
X633170Y-23331D01*
G01Y-23348D02*
X634804Y-18862D01*
G01X633056Y-23615D02*
X633048Y-23633D01*
X633042Y-23652D01*
X633035Y-23671D01*
G01X633170Y-23331D02*
X633056Y-23615D01*
G01X624126Y-16798D02*
X623973Y-16813D01*
X623826Y-16857D01*
X623691Y-16929D01*
X623569Y-17028D01*
X623472Y-17146D01*
X623399Y-17281D01*
X623354Y-17427D01*
X623339Y-17582D01*
G01X614457Y-16798D02*
X614304Y-16813D01*
X614157Y-16857D01*
X614021Y-16929D01*
X613900Y-17028D01*
X613802Y-17146D01*
X613730Y-17281D01*
X613685Y-17427D01*
X613669Y-17582D01*
G01X604787Y-16798D02*
X604635Y-16813D01*
X604487Y-16857D01*
X604352Y-16929D01*
X604231Y-17028D01*
X604133Y-17146D01*
X604061Y-17281D01*
X604016Y-17427D01*
X604000Y-17582D01*
G01X607095Y-16904D02*
X606937Y-16918D01*
X606785Y-16958D01*
X606646Y-17023D01*
X606523Y-17112D01*
X606426Y-17218D01*
X606355Y-17341D01*
G01X624126Y-16904D02*
X623973Y-16917D01*
X623826Y-16954D01*
X623691Y-17015D01*
X623569Y-17099D01*
X623472Y-17199D01*
X623399Y-17313D01*
X623354Y-17437D01*
X623339Y-17568D01*
G01X614457Y-16904D02*
X614304Y-16917D01*
X614157Y-16954D01*
X614021Y-17015D01*
X613900Y-17099D01*
X613802Y-17199D01*
X613730Y-17313D01*
X613685Y-17437D01*
X613669Y-17568D01*
G01X631508Y-18862D02*
X623339D01*
G01X621839D02*
X613669D01*
G01X610373D02*
X605796D01*
G01Y-18845D02*
X610373D01*
G01X613669D02*
X621839D01*
G01X623339D02*
X631508D01*
G01X612169Y-18516D02*
X604000D01*
G01X631508D02*
X623339D01*
G01X621839D02*
X613669D01*
G01X604000Y-18481D02*
X612169D01*
G01X613669D02*
X621839D01*
G01X623339D02*
X631508D01*
G01Y-18138D02*
X623339D01*
G01X621839D02*
X613669D01*
G01X612169D02*
X604000D01*
G01Y-18104D02*
X612169D01*
G01X613669D02*
X621839D01*
G01X623339D02*
X631508D01*
G01X606209Y-17890D02*
X609961D01*
G01X613669D02*
X621839D01*
G01X623339D02*
X631508D01*
G01Y-17679D02*
X623339D01*
G01X621839D02*
X613669D01*
G01X609961D02*
X606209D01*
G01X614039Y-17318D02*
X609118D01*
G01X607095Y-17116D02*
X609075D01*
G01X614457D02*
X621051D01*
G01X624126D02*
X630720D01*
G01Y-16904D02*
X624126D01*
G01X621051D02*
X614457D01*
G01X609075D02*
X607095D01*
G01X604787Y-16798D02*
X611382D01*
G01X614457D02*
X621051D01*
G01X624126D02*
X630720D01*
G01Y-16764D02*
X624126D01*
G01X621051D02*
X614457D01*
G01X611382D02*
X604787D01*
G01X614039Y-14786D02*
X609118D01*
G01Y-14307D02*
X614039D01*
G01Y-9699D02*
X609118D01*
G01Y-9220D02*
X614039D01*
G01X609118Y-6688D02*
X614039D01*
G01Y-1570D02*
X609118D01*
G01X614039Y962D02*
X609118D01*
G01Y1441D02*
X614039D01*
G01Y6049D02*
X609118D01*
G01X621051Y-17116D02*
X621204Y-17128D01*
X621352Y-17166D01*
X621487Y-17227D01*
X621608Y-17310D01*
X621706Y-17410D01*
X621778Y-17525D01*
X621823Y-17649D01*
X621839Y-17780D01*
G01X609075Y-17116D02*
X609233Y-17129D01*
X609385Y-17170D01*
X609524Y-17234D01*
X609647Y-17323D01*
X609744Y-17430D01*
X609815Y-17553D01*
G01X611382Y-16764D02*
X611535Y-16779D01*
X611682Y-16823D01*
X611818Y-16895D01*
X611939Y-16994D01*
X612036Y-17112D01*
X612109Y-17247D01*
X612154Y-17393D01*
X612169Y-17548D01*
G01X621051Y-16764D02*
X621204Y-16779D01*
X621352Y-16823D01*
X621487Y-16895D01*
X621608Y-16994D01*
X621706Y-17112D01*
X621778Y-17247D01*
X621823Y-17393D01*
X621839Y-17548D01*
G01X609815Y-17341D02*
X609745Y-17220D01*
X609649Y-17114D01*
X609529Y-17025D01*
X609387Y-16959D01*
X609236Y-16918D01*
X609075Y-16904D01*
G01X609961Y-17890D02*
X610098Y-18195D01*
X610235Y-18522D01*
X610373Y-18862D01*
G01X609815Y-17553D02*
X609961Y-17890D01*
G01Y-17679D02*
X609815Y-17341D01*
G01X610373Y-18845D02*
X610235Y-18437D01*
X610098Y-18044D01*
X609961Y-17679D01*
G01X612169Y-17582D02*
X612154Y-17430D01*
X612110Y-17284D01*
X612038Y-17149D01*
X611939Y-17028D01*
X611820Y-16931D01*
X611685Y-16858D01*
X611538Y-16814D01*
X611382Y-16798D01*
G01X621839Y-17582D02*
X621824Y-17430D01*
X621780Y-17284D01*
X621707Y-17149D01*
X621608Y-17028D01*
X621489Y-16931D01*
X621354Y-16858D01*
X621207Y-16814D01*
X621051Y-16798D01*
G01X621839Y-17568D02*
X621824Y-17439D01*
X621780Y-17315D01*
X621707Y-17201D01*
X621608Y-17099D01*
X621489Y-17016D01*
X621354Y-16955D01*
X621207Y-16917D01*
X621051Y-16904D01*
G01X604787Y-16798D02*
Y-16764D01*
G01X605563Y-12273D02*
Y-16178D01*
G01X605796Y-18862D02*
Y-18845D01*
G01X605876Y-9725D02*
Y-13990D01*
G01X606209Y-17679D02*
Y-17890D01*
G01X606355Y-17553D02*
Y-17341D01*
G01X606947Y-9060D02*
Y-14934D01*
G01X607095Y-16904D02*
Y-17116D01*
G01X609075D02*
Y-16904D01*
G01X609118Y9060D02*
Y-1570D01*
G01Y-6688D02*
Y-17318D01*
G01X609815Y-17341D02*
Y-17553D01*
G01X609961Y-17890D02*
Y-17679D01*
G01X610373Y-18845D02*
Y-18862D01*
G01X611382Y-16764D02*
Y-16798D01*
G01X614039Y-17318D02*
Y-6688D01*
G01Y-1570D02*
Y9060D01*
G01X614457Y-16904D02*
Y-17116D01*
G01Y-16798D02*
Y-16764D01*
G01X621051D02*
Y-16798D01*
G01Y-17116D02*
Y-16904D01*
G01X624126D02*
Y-17116D01*
G01Y-16798D02*
Y-16764D01*
G01X604000Y-17548D02*
X604015Y-17396D01*
X604059Y-17249D01*
X604132Y-17114D01*
X604231Y-16994D01*
X604350Y-16896D01*
X604485Y-16824D01*
X604632Y-16779D01*
X604787Y-16764D01*
G01X613669Y-17548D02*
X613685Y-17396D01*
X613729Y-17249D01*
X613801Y-17114D01*
X613900Y-16994D01*
X614019Y-16896D01*
X614154Y-16824D01*
X614301Y-16779D01*
X614457Y-16764D01*
G01X623339Y-17548D02*
X623354Y-17396D01*
X623398Y-17249D01*
X623470Y-17114D01*
X623569Y-16994D01*
X623688Y-16896D01*
X623824Y-16824D01*
X623970Y-16779D01*
X624126Y-16764D01*
G01X613669Y-17780D02*
X613685Y-17651D01*
X613729Y-17527D01*
X613801Y-17412D01*
X613900Y-17310D01*
X614019Y-17228D01*
X614154Y-17167D01*
X614301Y-17129D01*
X614457Y-17116D01*
G01X623339Y-17780D02*
X623354Y-17651D01*
X623398Y-17527D01*
X623470Y-17412D01*
X623569Y-17310D01*
X623688Y-17228D01*
X623824Y-17167D01*
X623970Y-17129D01*
X624126Y-17116D01*
G01X606209Y-17679D02*
X606072Y-18044D01*
X605934Y-18437D01*
X605796Y-18845D01*
G01Y-18862D02*
X605934Y-18522D01*
X606072Y-18195D01*
X606209Y-17890D01*
G01X606355Y-17341D02*
X606209Y-17679D01*
G01Y-17890D02*
X606355Y-17553D01*
G01D02*
X606424Y-17432D01*
X606521Y-17325D01*
X606641Y-17237D01*
X606782Y-17170D01*
X606934Y-17130D01*
X607095Y-17116D01*
G01X605563Y-12273D02*
G03X604563Y-11273I-1000J0D01*
G01Y-17178D02*
G03X605563Y-16178I0J1000D01*
G01X605947Y-15934D02*
G03X606947Y-14934I0J1000D01*
G01Y-9060D02*
G03X605947Y-8060I-1000J0D01*
G01X605817Y-14327D02*
G03X605876Y-13990I-925J336D01*
G01Y-9725D02*
G03X604892Y-8741I-984J0D01*
G01X604000Y-24077D02*
X612169D01*
G01X613669D02*
X621839D01*
G01X623339D02*
X631508D01*
G01Y-23942D02*
X623339D01*
G01X621839D02*
X613669D01*
G01X612169D02*
X604000D01*
G01X631508Y-23756D02*
X623339D01*
G01X621839D02*
X613669D01*
G01X612142D02*
X604028D01*
G01Y-23671D02*
X612142D01*
G01X613669D02*
X621839D01*
G01X623339D02*
X631508D01*
G01X604162Y-23348D02*
X612007D01*
G01X613669D02*
X621839D01*
G01X623339D02*
X631508D01*
G01Y-23331D02*
X623339D01*
G01X621839D02*
X613669D01*
G01X612007D02*
X604162D01*
G01X604000Y-23097D02*
X612169D01*
G01X613669D02*
X621839D01*
G01X623339D02*
X631508D01*
G01Y-23063D02*
X623339D01*
G01X621839D02*
X613669D01*
G01X612169D02*
X604000D01*
G01X612122Y-23615D02*
X612007Y-23331D01*
G01X610373Y-18862D02*
X612007Y-23348D01*
G01Y-23331D02*
X610373Y-18845D01*
G01X612007Y-23348D02*
X612122Y-23689D01*
G01D02*
X612129Y-23711D01*
X612136Y-23734D01*
X612142Y-23756D01*
G01Y-23671D02*
X612136Y-23652D01*
X612129Y-23633D01*
X612122Y-23615D01*
G01X612142Y-23756D02*
X612150Y-23787D01*
X612157Y-23821D01*
X612162Y-23853D01*
X612166Y-23888D01*
X612169Y-23923D01*
Y-23958D01*
G01Y-23872D02*
Y-23840D01*
X612167Y-23805D01*
X612163Y-23773D01*
X612157Y-23739D01*
X612150Y-23705D01*
X612142Y-23671D01*
G01X604028Y-23756D02*
Y-23671D01*
G01X604048Y-23615D02*
Y-23689D01*
G01X604162Y-23331D02*
Y-23339D01*
G01D02*
Y-23348D01*
G01X612122Y-23689D02*
Y-23615D01*
G01X612142Y-23671D02*
Y-23756D01*
G01X612007Y-23348D02*
Y-23331D01*
G01X604000Y-23958D02*
X604001Y-23925D01*
X604003Y-23891D01*
X604007Y-23858D01*
X604012Y-23824D01*
X604019Y-23790D01*
X604028Y-23756D01*
G01Y-23671D02*
X604020Y-23702D01*
X604013Y-23736D01*
X604007Y-23768D01*
X604004Y-23803D01*
X604001Y-23838D01*
X604000Y-23872D01*
G01X604028Y-23756D02*
X604034Y-23734D01*
X604041Y-23711D01*
X604048Y-23689D01*
G01D02*
X604162Y-23348D01*
G01X605796Y-18845D02*
X604162Y-23331D01*
G01Y-23348D02*
X605796Y-18862D01*
G01X604048Y-23615D02*
X604041Y-23633D01*
X604034Y-23652D01*
X604028Y-23671D01*
G01X604162Y-23331D02*
X604048Y-23615D01*
G01X628120Y18393D02*
X628820D01*
G01X631073D02*
X631773D01*
G01X634026D02*
X634726D01*
G01X631773Y21371D02*
X631073D01*
G01X634726D02*
X634026D01*
G01X628820D02*
X628120D01*
G01X631773Y24336D02*
X631073D01*
G01X634726D02*
X634026D01*
G01X628820D02*
X628120D01*
G01X631773Y24561D02*
X631073D01*
G01X634726D02*
X634026D01*
G01X628820D02*
X628120D01*
G01X640183Y36767D02*
X629730D01*
G01X632356Y37588D02*
X630463D01*
G01X628022Y38588D02*
X632490D01*
G01X628694Y39032D02*
X628667D01*
G01X632825Y39392D02*
X630856D01*
G01X632490Y38588D02*
X632623Y38552D01*
X632742Y38447D01*
X632825Y38288D01*
X632856Y38088D01*
G01X628694Y37940D02*
X630776Y35857D01*
G01X629533Y36569D02*
X630596Y35267D01*
G01X628667Y38069D02*
X629730Y36767D01*
G01X628667Y38069D02*
X629533Y36569D01*
G01X630596Y35267D02*
X629730Y36767D01*
G01X632856Y38088D02*
X632846Y38173D01*
X632811Y38258D01*
X632753Y38341D01*
X632670Y38418D01*
X632565Y38484D01*
X632436Y38538D01*
X632288Y38574D01*
X632124Y38588D01*
G01X628120Y24561D02*
Y18393D01*
G01X628667Y44408D02*
Y38069D01*
G01X628694Y44408D02*
Y37940D01*
G01X628820Y24561D02*
Y18393D01*
G01X629392Y44408D02*
Y37242D01*
G01X629533Y36569D02*
Y44408D01*
G01X630463Y40780D02*
Y34257D01*
G01X630606Y43930D02*
Y38588D01*
G01X630856Y44408D02*
Y36767D01*
G01X631073Y24561D02*
Y18393D01*
G01X631773Y24561D02*
Y18393D01*
G01X631856Y43930D02*
Y38588D01*
G01X632825Y44408D02*
Y36767D01*
G01X632856Y43930D02*
Y38088D01*
G01X634026Y24561D02*
Y18393D01*
G01X634726Y24561D02*
Y18393D01*
G01X632356Y37588D02*
G03X632856Y38088I0J500D01*
G01X631138Y6528D02*
X636059D01*
G01X631138Y9060D02*
X636059D01*
G01X640183Y12019D02*
X604947D01*
G01X624033Y12877D02*
X626033D01*
G01X624033Y14058D02*
X625033D01*
G01X638018Y14955D02*
X607112D01*
G01X610404Y18393D02*
X611104D01*
G01X613357D02*
X614057D01*
G01X616309D02*
X617009D01*
G01X619262D02*
X619962D01*
G01X622215D02*
X622915D01*
G01X625167D02*
X625867D01*
G01X625033Y18585D02*
X624033D01*
G01X626033Y19766D02*
X624033D01*
G01X622915Y21371D02*
X622215D01*
G01X625867D02*
X625167D01*
G01X619962D02*
X619262D01*
G01X614057D02*
X613357D01*
G01X617009D02*
X616309D01*
G01X611104D02*
X610404D01*
G01X622915Y24336D02*
X622215D01*
G01X625867D02*
X625167D01*
G01X619962D02*
X619262D01*
G01X614057D02*
X613357D01*
G01X617009D02*
X616309D01*
G01X611104D02*
X610404D01*
G01X625867Y24561D02*
X625167D01*
G01X622915D02*
X622215D01*
G01X619962D02*
X619262D01*
G01X617009D02*
X616309D01*
G01X614057D02*
X613357D01*
G01X611104D02*
X610404D01*
G01X626244Y27251D02*
X623291D01*
G01X622291D02*
X618933D01*
G01X613054Y38588D02*
X612773Y38547D01*
X612540Y38441D01*
X612378Y38279D01*
X612321Y38088D01*
G01X626244Y28251D02*
X623291D01*
G01X622291D02*
X618933D01*
G01X626244Y29251D02*
X623291D01*
G01X622291D02*
X618933D01*
G01X626244Y29501D02*
X623291D01*
G01X622291D02*
X618933D01*
G01X625850Y29645D02*
X619327D01*
G01X623882Y31367D02*
X625654D01*
G01X621701Y32851D02*
X619524D01*
G01X607112Y34353D02*
X638018D01*
G01Y35141D02*
X607112D01*
G01X640183Y35267D02*
X604947D01*
G01X630776Y35857D02*
X614353D01*
G01X615399Y36767D02*
X604947D01*
G01X614715Y37588D02*
X612821D01*
G01X612687Y38588D02*
X617156D01*
G01X616463Y39032D02*
X616435D01*
G01X614321Y39392D02*
X612352D01*
G01X621210Y34687D02*
X622040Y34292D01*
X622972Y34145D01*
X623902Y34260D01*
X624788Y34632D01*
X625567Y35247D01*
X626163Y36062D01*
X626543Y37073D01*
G01X621210Y34686D02*
X622020Y34298D01*
X622943Y34147D01*
X623875Y34252D01*
X624770Y34621D01*
X625558Y35238D01*
X626160Y36057D01*
X626543Y37073D01*
G01X614715Y34257D02*
X619327Y29645D01*
G01X625715Y41985D02*
X628667Y39032D01*
G01X626126Y39341D02*
X625454Y40116D01*
X624628Y40669D01*
X623680Y40987D01*
X622693Y41034D01*
X621757Y40811D01*
X620924Y40337D01*
X620293Y39675D01*
G01X626126Y39341D02*
X625469Y40265D01*
X624570Y40969D01*
X623471Y41398D01*
X622313Y41489D01*
X621175Y41238D01*
X620173Y40682D01*
X619363Y39846D01*
X618828Y38822D01*
X618613Y37666D01*
X618741Y36502D01*
X619190Y35448D01*
X619943Y34547D01*
X620935Y33899D01*
X622074Y33574D01*
X623239Y33592D01*
X624349Y33950D01*
X625308Y34614D01*
X626044Y35547D01*
X626475Y36666D01*
X626553Y37866D01*
X626256Y39065D01*
X625648Y40063D01*
X624791Y40833D01*
X623698Y41340D01*
X622533Y41497D01*
X621391Y41313D01*
X620323Y40790D01*
X619481Y40005D01*
X618898Y39005D01*
X618624Y37852D01*
X618692Y36714D01*
X619085Y35630D01*
X619782Y34697D01*
X620733Y33999D01*
X621833Y33612D01*
X622985Y33560D01*
X624101Y33837D01*
X625042Y34385D01*
X625819Y35195D01*
X626357Y36241D01*
X626565Y37379D01*
X626432Y38551D01*
X625977Y39606D01*
X625223Y40501D01*
X624245Y41136D01*
X623099Y41464D01*
X621971Y41451D01*
X620858Y41101D01*
X619906Y40458D01*
X619158Y39533D01*
X618705Y38387D01*
X618623Y37197D01*
X618878Y36081D01*
X619444Y35079D01*
X620285Y34274D01*
X621346Y33738D01*
X622520Y33540D01*
X623715Y33702D01*
X624767Y34188D01*
X625638Y34961D01*
X626248Y35956D01*
X626544Y37089D01*
X626501Y38249D01*
X626126Y39341D01*
G01X626544Y38246D02*
X626163Y39363D01*
X625474Y40321D01*
X624534Y41039D01*
X623428Y41452D01*
X622250Y41526D01*
X621094Y41253D01*
X620082Y40664D01*
X619271Y39792D01*
X618754Y38731D01*
X618567Y37567D01*
X618728Y36392D01*
X619216Y35327D01*
X620008Y34434D01*
X621015Y33817D01*
X622154Y33520D01*
X623335Y33566D01*
X624449Y33953D01*
X625409Y34651D01*
X626122Y35597D01*
X626527Y36703D01*
X626594Y37880D01*
X626316Y39030D01*
X625716Y40048D01*
X624842Y40850D01*
X623778Y41361D01*
X622612Y41540D01*
X621442Y41373D01*
X620374Y40876D01*
X619490Y40083D01*
X618879Y39072D01*
X618588Y37928D01*
X618641Y36749D01*
X619034Y35636D01*
X619734Y34685D01*
X620681Y33978D01*
X621791Y33577D01*
X622971Y33515D01*
X624118Y33799D01*
X625131Y34402D01*
X625926Y35274D01*
X626434Y36340D01*
X626611Y37508D01*
X626441Y38676D01*
X625938Y39745D01*
X625153Y40618D01*
X624143Y41228D01*
X622998Y41519D01*
X621819Y41466D01*
X620702Y41070D01*
X619763Y40380D01*
X619055Y39439D01*
X618650Y38330D01*
X618583Y37152D01*
X618865Y35999D01*
X619456Y34995D01*
X620320Y34197D01*
X621383Y33682D01*
X622548Y33497D01*
X623717Y33658D01*
X624786Y34150D01*
X625663Y34925D01*
X626284Y35930D01*
X626586Y37069D01*
X626544Y38246D01*
G01X626593Y37855D02*
X626451Y38627D01*
X626126Y39341D01*
G01X626543Y37073D02*
X626501Y38248D01*
X626107Y39377D01*
X625424Y40312D01*
X624487Y41015D01*
X623349Y41425D01*
X622148Y41473D01*
X620969Y41153D01*
X620007Y40547D01*
X619262Y39701D01*
X618773Y38649D01*
X618611Y37437D01*
X618826Y36222D01*
X619345Y35212D01*
X620150Y34375D01*
X621148Y33809D01*
X622262Y33553D01*
X623481Y33640D01*
X624587Y34077D01*
X625472Y34776D01*
X626129Y35701D01*
X626502Y36795D01*
X626545Y37942D01*
X626241Y39097D01*
X625640Y40073D01*
X624767Y40847D01*
X623749Y41325D01*
X622604Y41498D01*
X621388Y41312D01*
X620361Y40818D01*
X619520Y40051D01*
X618909Y39033D01*
X618628Y37904D01*
X618685Y36751D01*
X619090Y35620D01*
X619785Y34695D01*
X620684Y34025D01*
X621772Y33624D01*
X622981Y33559D01*
X624111Y33842D01*
X625088Y34422D01*
X625887Y35293D01*
X626378Y36305D01*
X626568Y37526D01*
X626378Y38734D01*
X625889Y39744D01*
X625121Y40588D01*
X624146Y41180D01*
X623016Y41475D01*
X621811Y41421D01*
X620705Y41025D01*
X619807Y40364D01*
X619105Y39441D01*
X618709Y38402D01*
X618620Y37241D01*
X618899Y36025D01*
X619484Y35030D01*
X620339Y34237D01*
X621409Y33718D01*
X622559Y33540D01*
X623709Y33700D01*
X624778Y34195D01*
X625628Y34949D01*
X626251Y35962D01*
X626543Y37073D01*
G01X605563Y43759D02*
Y39853D01*
G01X606947Y19242D02*
Y25116D01*
G01X607112Y35141D02*
Y14955D01*
G01X610404Y24561D02*
Y18393D01*
G01X611104Y24561D02*
Y18393D01*
G01X612321Y43930D02*
Y38088D01*
G01X612352Y44408D02*
Y36767D01*
G01X613321Y43930D02*
Y38588D01*
G01X613357Y24561D02*
Y18393D01*
G01X614057Y24561D02*
Y18393D01*
G01X614321Y44408D02*
Y36767D01*
G01X614571Y43930D02*
Y38588D01*
G01X614715Y34257D02*
Y40780D01*
G01X615596Y44408D02*
Y36569D01*
G01X615737Y44408D02*
Y37242D01*
G01X616309Y24561D02*
Y18393D01*
G01X616435Y37940D02*
Y44408D01*
G01X616463Y38069D02*
Y44408D01*
G01X617009Y24561D02*
Y18393D01*
G01X617746Y43339D02*
Y39178D01*
G01X617933Y31038D02*
Y26751D01*
G01X618933Y32261D02*
Y26751D01*
G01X619262Y24561D02*
Y18393D01*
G01X619962Y24561D02*
Y18393D01*
G01X622215Y24561D02*
Y18393D01*
G01X622291Y32261D02*
Y26751D01*
G01X622915Y24561D02*
Y18393D01*
G01X623291Y30777D02*
Y26751D01*
G01X624033Y12877D02*
Y19766D01*
G01X625033Y12877D02*
Y19766D01*
G01X625167Y24561D02*
Y18393D01*
G01X625867Y24561D02*
Y18393D01*
G01X626033Y19766D02*
Y12877D01*
G01X626244Y30777D02*
Y26751D01*
G01X627244Y31038D02*
Y26751D01*
G01X627431Y43339D02*
Y39178D01*
G01X626543Y37073D02*
X626593Y37855D01*
X626451Y38627D01*
G01X612321Y38088D02*
X612352Y38288D01*
X612435Y38447D01*
X612555Y38552D01*
X612687Y38588D01*
G01X615399Y36767D02*
X614533Y35267D01*
G01X615596Y36569D02*
X616463Y38069D01*
G01X615399Y36767D02*
X616463Y38069D01*
G01X614533Y35267D02*
X615596Y36569D01*
G01X620294Y39675D02*
X620914Y40330D01*
X621734Y40802D01*
X622661Y41031D01*
X623643Y40994D01*
X624598Y40684D01*
X625437Y40130D01*
X626127Y39341D01*
G01X619415Y41985D02*
X616463Y39032D01*
G01X616435Y37940D02*
X614353Y35857D01*
G01X630463Y34257D02*
X625850Y29645D01*
G01X605947Y18242D02*
G03X606947Y19242I0J1000D01*
G01Y25116D02*
G03X605947Y26116I-1000J0D01*
G01X626244Y30777D02*
G03X625654Y31367I-591J-1D01*
G01X623882D02*
G03X623291Y30777I0J-591D01*
G01X626244Y26751D02*
G03X627244I500J0D01*
G01X617933D02*
G03X618933I500J0D01*
G01X622291D02*
G03X623291I500J0D01*
G01X604563Y38853D02*
G03X605563Y39853I0J1000D01*
G01X626919Y37519D02*
G03I-4330J0D01*
G01X625738D02*
G03I-3149J0D01*
G01X619524Y32851D02*
G03X618933Y32261I0J-591D01*
G01X622291D02*
G03X621701Y32851I-590J0D01*
G01X627431Y39178D02*
G03X628022Y38588I591J1D01*
G01X617156D02*
G03X617746Y39178I0J590D01*
G01X612321Y38088D02*
G03X612821Y37588I500J0D01*
G01X609118Y6528D02*
X614039D01*
G01X609118Y9060D02*
X614039D01*
G01X604947Y11019D02*
X640183D01*
G01X604947Y44408D02*
Y11019D01*
G01X607112Y14955D02*
X605931Y11019D01*
G01X607112Y14955D02*
X605931Y11019D01*
G01X631073Y48355D02*
X631773D01*
G01Y48571D02*
X631073D01*
G01X631773Y48667D02*
X631073D01*
G01X631773Y48729D02*
X631073D01*
G01X631773Y48827D02*
X631073D01*
G01X631773Y49812D02*
X631073D01*
G01X631773Y49910D02*
X631073D01*
G01X631773Y49973D02*
X631073D01*
G01X631773Y50068D02*
X631073D01*
G01Y50284D02*
X631773D01*
G01X634026Y51111D02*
X634726D01*
G01Y51327D02*
X634026D01*
G01X634726Y51423D02*
X634026D01*
G01X634726Y51485D02*
X634026D01*
G01X634726Y51583D02*
X634026D01*
G01X634726Y52568D02*
X634026D01*
G01X634726Y52666D02*
X634026D01*
G01X634726Y52729D02*
X634026D01*
G01X634726Y52823D02*
X634026D01*
G01Y53040D02*
X634726D01*
G01X628820Y53867D02*
X628120D01*
G01Y54083D02*
X628820D01*
G01X628120Y54179D02*
X628820D01*
G01X628120Y54241D02*
X628820D01*
G01Y54339D02*
X628120D01*
G01X628820Y55323D02*
X628120D01*
G01X628820Y55422D02*
X628120D01*
G01Y55484D02*
X628820D01*
G01X628120Y55579D02*
X628820D01*
G01Y55796D02*
X628120D01*
G01X631073Y63316D02*
X631773D01*
G01Y63532D02*
X631073D01*
G01X631773Y63627D02*
X631073D01*
G01X631773Y63690D02*
X631073D01*
G01X631773Y63788D02*
X631073D01*
G01X631773Y64772D02*
X631073D01*
G01X631773Y64871D02*
X631073D01*
G01X631773Y64933D02*
X631073D01*
G01X631773Y65028D02*
X631073D01*
G01Y65245D02*
X631773D01*
G01X634026Y66071D02*
X634726D01*
G01Y66288D02*
X634026D01*
G01X634726Y66383D02*
X634026D01*
G01X634726Y66445D02*
X634026D01*
G01X634726Y66544D02*
X634026D01*
G01X634726Y67528D02*
X634026D01*
G01X634726Y67627D02*
X634026D01*
G01X634726Y67689D02*
X634026D01*
G01X634726Y67784D02*
X634026D01*
G01Y68001D02*
X634726D01*
G01X628820Y68827D02*
X628120D01*
G01Y69044D02*
X628820D01*
G01X628120Y69139D02*
X628820D01*
G01X628120Y69201D02*
X628820D01*
G01Y69300D02*
X628120D01*
G01X628820Y70284D02*
X628120D01*
G01X628820Y70382D02*
X628120D01*
G01Y70445D02*
X628820D01*
G01Y70540D02*
X628120D01*
G01X628820Y70756D02*
X628120D01*
G01Y53868D02*
Y55794D01*
G01Y68829D02*
Y70755D01*
G01X628820Y53869D02*
Y55795D01*
G01Y68829D02*
Y70755D01*
G01X631073Y48356D02*
Y50282D01*
G01Y63317D02*
Y65243D01*
G01X631773Y48357D02*
Y50283D01*
G01Y63318D02*
Y65243D01*
G01X634026Y51112D02*
Y53038D01*
G01Y66073D02*
Y67999D01*
G01X634726Y51113D02*
Y53039D01*
G01Y66073D02*
Y67999D01*
G01X632825Y41062D02*
X630856D01*
G01X660463Y43930D02*
X628022D01*
G01X610909Y54492D02*
X610844Y54478D01*
G01X610660Y55095D02*
X610726Y55108D01*
G01X619327Y45393D02*
X625850D01*
G01X627486Y45528D02*
X617644D01*
G01X627486Y46512D02*
X617644D01*
G01X613357Y48355D02*
X614057D01*
G01X622215D02*
X622915D01*
G01Y48571D02*
X622215D01*
G01X614057D02*
X613357D01*
G01X622915Y48667D02*
X622215D01*
G01X614057D02*
X613357D01*
G01X622915Y48729D02*
X622215D01*
G01X614057D02*
X613357D01*
G01X622915Y48827D02*
X622215D01*
G01X614057D02*
X613357D01*
G01X622915Y49812D02*
X622215D01*
G01X614057D02*
X613357D01*
G01X622915Y49910D02*
X622215D01*
G01X614057D02*
X613357D01*
G01X622915Y49973D02*
X622215D01*
G01X614057D02*
X613357D01*
G01X622915Y50068D02*
X622215D01*
G01X614057D02*
X613357D01*
G01Y50284D02*
X614057D01*
G01X622215D02*
X622915D01*
G01X616309Y51111D02*
X617009D01*
G01X625167D02*
X625867D01*
G01Y51327D02*
X625167D01*
G01X617009D02*
X616309D01*
G01X625867Y51423D02*
X625167D01*
G01X617009D02*
X616309D01*
G01X625867Y51485D02*
X625167D01*
G01X617009D02*
X616309D01*
G01X625867Y51583D02*
X625167D01*
G01X617009D02*
X616309D01*
G01X625867Y52568D02*
X625167D01*
G01X617009D02*
X616309D01*
G01X625867Y52666D02*
X625167D01*
G01X617009D02*
X616309D01*
G01X625867Y52729D02*
X625167D01*
G01X617009D02*
X616309D01*
G01X625867Y52823D02*
X625167D01*
G01X617009D02*
X616309D01*
G01Y53040D02*
X617009D01*
G01X625167D02*
X625867D01*
G01X609123Y53499D02*
X608123D01*
G01X614123D02*
X615748D01*
G01X619498D02*
X621123D01*
G01X619962Y53867D02*
X619262D01*
G01X611104D02*
X610404D01*
G01Y54083D02*
X611104D01*
G01X619262D02*
X619962D01*
G01X610404Y54179D02*
X611104D01*
G01X619262D02*
X619962D01*
G01X610404Y54241D02*
X611104D01*
G01X619262D02*
X619962D01*
G01Y54339D02*
X619262D01*
G01X611104D02*
X610404D01*
G01X610844Y54478D02*
X610726D01*
G01X611211D02*
X611132D01*
G01X611657D02*
X611578D01*
G01X611920D02*
X611841D01*
G01X610726Y54558D02*
X610844D01*
G01X611526Y54639D02*
X611263D01*
G01X610948D02*
X611027D01*
G01X611513Y54693D02*
X611277D01*
G01X608998Y54749D02*
X608248D01*
G01X611027Y54947D02*
X610948D01*
G01X610844Y55028D02*
X610726D01*
G01Y55108D02*
X610844D01*
G01X611342D02*
X611447D01*
G01X611841D02*
X611920D01*
G01X619962Y55323D02*
X619262D01*
G01X611104D02*
X610404D01*
G01X619962Y55422D02*
X619262D01*
G01X611104D02*
X610404D01*
G01Y55484D02*
X611104D01*
G01X619262D02*
X619962D01*
G01X610404Y55579D02*
X611104D01*
G01X619262D02*
X619962D01*
G01Y55796D02*
X619262D01*
G01X611104D02*
X610404D01*
G01X611998Y55999D02*
X610623D01*
G01X612123Y56999D02*
X606623D01*
G01X610623Y57999D02*
X606623D01*
G01X608998Y59749D02*
X608248D01*
G01X620748Y60999D02*
X619123D01*
G01X616123D02*
X614498D01*
G01X609123D02*
X608123D01*
G01X613357Y63316D02*
X614057D01*
G01X622215D02*
X622915D01*
G01Y63532D02*
X622215D01*
G01X614057D02*
X613357D01*
G01X622915Y63627D02*
X622215D01*
G01X614057D02*
X613357D01*
G01X622915Y63690D02*
X622215D01*
G01X614057D02*
X613357D01*
G01X622915Y63788D02*
X622215D01*
G01X614057D02*
X613357D01*
G01X622915Y64772D02*
X622215D01*
G01X614057D02*
X613357D01*
G01X622915Y64871D02*
X622215D01*
G01X614057D02*
X613357D01*
G01X622915Y64933D02*
X622215D01*
G01X614057D02*
X613357D01*
G01X622915Y65028D02*
X622215D01*
G01X614057D02*
X613357D01*
G01Y65245D02*
X614057D01*
G01X622215D02*
X622915D01*
G01X616309Y66071D02*
X617009D01*
G01X625167D02*
X625867D01*
G01Y66288D02*
X625167D01*
G01X617009D02*
X616309D01*
G01X625867Y66383D02*
X625167D01*
G01X617009D02*
X616309D01*
G01X625867Y66445D02*
X625167D01*
G01X617009D02*
X616309D01*
G01X625867Y66544D02*
X625167D01*
G01X617009D02*
X616309D01*
G01X625867Y67528D02*
X625167D01*
G01X617009D02*
X616309D01*
G01X625867Y67627D02*
X625167D01*
G01X617009D02*
X616309D01*
G01X625867Y67689D02*
X625167D01*
G01X617009D02*
X616309D01*
G01X625867Y67784D02*
X625167D01*
G01X617009D02*
X616309D01*
G01Y68001D02*
X617009D01*
G01X625167D02*
X625867D01*
G01X619962Y68827D02*
X619262D01*
G01X611104D02*
X610404D01*
G01Y69044D02*
X611104D01*
G01X619262D02*
X619962D01*
G01X610404Y69139D02*
X611104D01*
G01X619262D02*
X619962D01*
G01X610404Y69201D02*
X611104D01*
G01X619262D02*
X619962D01*
G01Y69300D02*
X619262D01*
G01X611104D02*
X610404D01*
G01X619962Y70284D02*
X619262D01*
G01X611104D02*
X610404D01*
G01X619962Y70382D02*
X619262D01*
G01X611104D02*
X610404D01*
G01Y70445D02*
X611104D01*
G01X619262D02*
X619962D01*
G01Y70540D02*
X619262D01*
G01X611104D02*
X610404D01*
G01X619962Y70756D02*
X619262D01*
G01X611104D02*
X610404D01*
G01X610726Y54478D02*
X610660Y54492D01*
G01X610844Y55108D02*
X610909Y55095D01*
G01X608123Y53499D02*
X607123Y53749D01*
G01X608248Y54749D02*
X607748Y54873D01*
G01X609498Y59623D02*
X608998Y59749D01*
G01X610123Y60749D02*
X609123Y60999D01*
G01X610673Y54572D02*
X610726Y54558D01*
G01X610896Y55014D02*
X610844Y55028D01*
G01X610660Y54492D02*
X610607Y54518D01*
G01X610909Y55095D02*
X610962Y55068D01*
G01X607748Y54873D02*
X607123Y55249D01*
G01X610123Y59249D02*
X609498Y59623D01*
G01X607123Y53749D02*
X606373Y54249D01*
G01X610873Y60249D02*
X610123Y60749D01*
G01X610633Y54599D02*
X610673Y54572D01*
G01X610935Y54988D02*
X610896Y55014D01*
G01X610844Y54558D02*
X610896Y54572D01*
G01X610726Y55028D02*
X610673Y55014D01*
G01X610123Y53749D02*
X609123Y53499D01*
G01X609498Y54873D02*
X608998Y54749D01*
G01X608248Y59749D02*
X607748Y59623D01*
G01X608123Y60999D02*
X607123Y60749D01*
G01X605873Y54749D02*
X606373Y54249D01*
G01X610873Y60249D02*
X611373Y59749D01*
G01X610607Y54518D02*
X610555Y54572D01*
G01X610962Y55068D02*
X611014Y55014D01*
G01X605373Y55499D02*
X605873Y54749D01*
G01X617623Y56249D02*
X619498Y53499D01*
G01X611373Y59749D02*
X611873Y58999D01*
G01X616123Y60999D02*
X617623Y58749D01*
G01X618498Y57499D02*
X621123Y53499D01*
G01X610607Y54639D02*
X610633Y54599D01*
G01X614498Y60999D02*
X616748Y57499D01*
G01X606748Y55873D02*
X607123Y55249D01*
G01X610123Y59249D02*
X610498Y58623D01*
G01X610555Y54572D02*
X610529Y54626D01*
G01X611447Y55108D02*
X611657Y54478D01*
G01X610948Y54947D02*
X610935Y54988D01*
G01X611578Y54478D02*
X611526Y54639D01*
G01X611395Y55055D02*
X611513Y54693D01*
G01X605123Y56499D02*
X605373Y55499D01*
G01X606623Y56373D02*
X606748Y55873D01*
G01X611873Y58999D02*
X612123Y57999D01*
G01X610594Y54693D02*
X610607Y54639D01*
G01X610498Y58623D02*
X610623Y57999D01*
G01X610529Y54626D02*
X610515Y54693D01*
G01X611014Y55014D02*
X611027Y54947D01*
G01X604034Y68043D02*
Y77812D01*
G01X605123Y57999D02*
Y56499D01*
G01X605955Y76812D02*
Y69043D01*
G01X606623Y58123D02*
Y57999D01*
G01Y56999D02*
Y56373D01*
G01X610404Y53868D02*
Y55794D01*
G01Y68829D02*
Y70755D01*
G01X610515Y54693D02*
Y54893D01*
G01X610594D02*
Y54693D01*
G01X611104Y53869D02*
Y55795D01*
G01Y68829D02*
Y70755D01*
G01X611762Y54907D02*
Y55014D01*
G01X611841Y54478D02*
Y55001D01*
G01X611920Y55108D02*
Y54478D01*
G01X612123Y57999D02*
Y56999D01*
G01X613357Y48356D02*
Y50282D01*
G01Y63317D02*
Y65243D01*
G01X614057Y48357D02*
Y50283D01*
G01Y63318D02*
Y65243D01*
G01X616309Y51112D02*
Y53038D01*
G01Y66073D02*
Y67999D01*
G01X617009Y51113D02*
Y53039D01*
G01Y66073D02*
Y67999D01*
G01X619262Y53868D02*
Y55794D01*
G01Y68829D02*
Y70755D01*
G01X619962Y53869D02*
Y55795D01*
G01Y68829D02*
Y70755D01*
G01X622215Y48356D02*
Y50282D01*
G01Y63317D02*
Y65243D01*
G01X622915Y48357D02*
Y50283D01*
G01Y63318D02*
Y65243D01*
G01X625167Y51112D02*
Y53038D01*
G01Y66073D02*
Y67999D01*
G01X625867Y51113D02*
Y53039D01*
G01Y66073D02*
Y67999D01*
G01X610515Y54893D02*
X610529Y54961D01*
G01X611027Y54639D02*
X611014Y54572D01*
G01X610607Y54947D02*
X610594Y54893D01*
G01X605373Y58999D02*
X605123Y57999D01*
G01X606748Y58623D02*
X606623Y58123D01*
G01X611998Y55999D02*
X611873Y55499D01*
G01X610935Y54599D02*
X610948Y54639D01*
G01X611277Y54693D02*
X611395Y55055D01*
G01X611263Y54639D02*
X611211Y54478D01*
G01X611132D02*
X611342Y55108D01*
G01X610529Y54961D02*
X610555Y55014D01*
G01X607123Y59249D02*
X606748Y58623D01*
G01X620748Y60999D02*
X618498Y57499D01*
G01X610633Y54988D02*
X610607Y54947D01*
G01X616748Y57499D02*
X614123Y53499D01*
G01X605873Y59749D02*
X605373Y58999D01*
G01X610623Y55999D02*
X610123Y55249D01*
G01X611873Y55499D02*
X611373Y54749D01*
G01X619123Y60999D02*
X617623Y58749D01*
G01Y56249D02*
X615748Y53499D01*
G01X611762Y55014D02*
X611841Y55108D01*
G01Y55001D02*
X611762Y54907D01*
G01X610555Y55014D02*
X610607Y55068D01*
G01X611014Y54572D02*
X610962Y54518D01*
G01X606373Y60249D02*
X605873Y59749D01*
G01X611373Y54749D02*
X610873Y54249D01*
G01X610673Y55014D02*
X610633Y54988D01*
G01X610896Y54572D02*
X610935Y54599D01*
G01X607123Y60749D02*
X606373Y60249D01*
G01X610873Y54249D02*
X610123Y53749D01*
G01X607748Y59623D02*
X607123Y59249D01*
G01X610123Y55249D02*
X609498Y54873D01*
G01X610607Y55068D02*
X610660Y55095D01*
G01X610962Y54518D02*
X610909Y54492D01*
G01X604955Y68043D02*
G03X605955Y69043I0J1000D01*
G01X614321Y41062D02*
X612352D01*
G01X625715Y41985D02*
X619415D01*
G01X625850Y45393D02*
X630463Y40780D01*
G01X604372Y44408D02*
Y68043D01*
G01X605000Y105171D02*
Y44408D01*
G01X606413Y105171D02*
Y44408D01*
G01X617644Y46512D02*
Y44408D01*
G01X627486Y46512D02*
Y44408D01*
G01X619327Y45393D02*
X614715Y40780D01*
G01X605563Y43759D02*
G03X604563Y44759I-1000J0D01*
G01X628022Y43930D02*
G03X627431Y43339I0J-591D01*
G01X617746D02*
G03X617156Y43930I-591J0D01*
G01X631773Y79733D02*
X631073D01*
G01X631773Y79831D02*
X631073D01*
G01X631773Y79894D02*
X631073D01*
G01X631773Y79989D02*
X631073D01*
G01Y80205D02*
X631773D01*
G01X634026Y81032D02*
X634726D01*
G01Y81249D02*
X634026D01*
G01X634726Y81344D02*
X634026D01*
G01X634726Y81406D02*
X634026D01*
G01X634726Y81505D02*
X634026D01*
G01X634726Y82489D02*
X634026D01*
G01X634726Y82587D02*
X634026D01*
G01X634726Y82650D02*
X634026D01*
G01X634726Y82745D02*
X634026D01*
G01Y82961D02*
X634726D01*
G01X628820Y83788D02*
X628120D01*
G01Y84005D02*
X628820D01*
G01X628120Y84100D02*
X628820D01*
G01X628120Y84162D02*
X628820D01*
G01Y84260D02*
X628120D01*
G01X628820Y85245D02*
X628120D01*
G01X628820Y85343D02*
X628120D01*
G01Y85406D02*
X628820D01*
G01Y85501D02*
X628120D01*
G01X628820Y85717D02*
X628120D01*
G01X631073Y93237D02*
X631773D01*
G01Y93453D02*
X631073D01*
G01X631773Y93549D02*
X631073D01*
G01X631773Y93611D02*
X631073D01*
G01X631773Y93709D02*
X631073D01*
G01X631773Y94693D02*
X631073D01*
G01X631773Y94792D02*
X631073D01*
G01X631773Y94855D02*
X631073D01*
G01X631773Y94949D02*
X631073D01*
G01Y95166D02*
X631773D01*
G01X634026Y95993D02*
X634726D01*
G01Y96209D02*
X634026D01*
G01X634726Y96305D02*
X634026D01*
G01X634726Y96367D02*
X634026D01*
G01X634726Y96465D02*
X634026D01*
G01X634726Y97449D02*
X634026D01*
G01X634726Y97548D02*
X634026D01*
G01X634726Y97610D02*
X634026D01*
G01X634726Y97705D02*
X634026D01*
G01Y97922D02*
X634726D01*
G01X628820Y98749D02*
X628120D01*
G01Y98965D02*
X628820D01*
G01X628120Y99060D02*
X628820D01*
G01X628120Y99123D02*
X628820D01*
G01Y99221D02*
X628120D01*
G01X628820Y100205D02*
X628120D01*
G01X628820Y100304D02*
X628120D01*
G01Y100366D02*
X628820D01*
G01Y100461D02*
X628120D01*
G01X628820Y100678D02*
X628120D01*
G01Y83790D02*
Y85716D01*
G01Y98750D02*
Y100676D01*
G01X628820Y83790D02*
Y85716D01*
G01Y98751D02*
Y100677D01*
G01X630045Y105171D02*
Y102336D01*
G01X630691Y106958D02*
Y105958D01*
G01X631073Y93238D02*
Y95164D01*
G01X631423Y105171D02*
Y102336D01*
G01X631773Y93239D02*
Y95165D01*
G01X632191Y105958D02*
Y106958D01*
G01X632846D02*
Y105958D01*
G01X632939D02*
Y106958D01*
G01X633199D02*
Y105958D01*
G01X633203Y105171D02*
Y106958D01*
G01X633425Y105958D02*
Y106958D01*
G01X633476Y105958D02*
Y106958D01*
G01X633884Y105958D02*
Y106958D01*
G01X634026Y81034D02*
Y82960D01*
G01Y95994D02*
Y97920D01*
G01X634726Y81034D02*
Y82960D01*
G01Y95995D02*
Y97921D01*
G01X634868Y106958D02*
Y105958D01*
G01X635199Y106958D02*
Y105958D01*
G01X635280D02*
Y106958D01*
G01X635331Y105958D02*
Y106958D01*
G01X635813Y105958D02*
Y106958D01*
G01X635910Y105958D02*
Y106958D01*
G01X635951Y105171D02*
Y102336D01*
G01X636199Y106958D02*
Y105958D01*
G01X636717Y106958D02*
Y105958D01*
G01X631073Y78276D02*
X631773D01*
G01Y78493D02*
X631073D01*
G01X631773Y78588D02*
X631073D01*
G01X631773Y78650D02*
X631073D01*
G01X631773Y78749D02*
X631073D01*
G01Y78278D02*
Y80204D01*
G01X631773Y78278D02*
Y80204D01*
G01X622915Y79733D02*
X622215D01*
G01X614057D02*
X613357D01*
G01X622915Y79831D02*
X622215D01*
G01X614057D02*
X613357D01*
G01X622915Y79894D02*
X622215D01*
G01X614057D02*
X613357D01*
G01X622915Y79989D02*
X622215D01*
G01X614057D02*
X613357D01*
G01Y80205D02*
X614057D01*
G01X622215D02*
X622915D01*
G01X616309Y81032D02*
X617009D01*
G01X625167D02*
X625867D01*
G01Y81249D02*
X625167D01*
G01X617009D02*
X616309D01*
G01X625867Y81344D02*
X625167D01*
G01X617009D02*
X616309D01*
G01X625867Y81406D02*
X625167D01*
G01X617009D02*
X616309D01*
G01X625867Y81505D02*
X625167D01*
G01X617009D02*
X616309D01*
G01X625867Y82489D02*
X625167D01*
G01X617009D02*
X616309D01*
G01X625867Y82587D02*
X625167D01*
G01X617009D02*
X616309D01*
G01X625867Y82650D02*
X625167D01*
G01X617009D02*
X616309D01*
G01X625867Y82745D02*
X625167D01*
G01X617009D02*
X616309D01*
G01Y82961D02*
X617009D01*
G01X625167D02*
X625867D01*
G01X619962Y83788D02*
X619262D01*
G01X611104D02*
X610404D01*
G01Y84005D02*
X611104D01*
G01X619262D02*
X619962D01*
G01X610404Y84100D02*
X611104D01*
G01X619262D02*
X619962D01*
G01X610404Y84162D02*
X611104D01*
G01X619262D02*
X619962D01*
G01Y84260D02*
X619262D01*
G01X611104D02*
X610404D01*
G01X619962Y85245D02*
X619262D01*
G01X611104D02*
X610404D01*
G01X619962Y85343D02*
X619262D01*
G01X611104D02*
X610404D01*
G01Y85406D02*
X611104D01*
G01X619262D02*
X619962D01*
G01Y85501D02*
X619262D01*
G01X611104D02*
X610404D01*
G01X619962Y85717D02*
X619262D01*
G01X611104D02*
X610404D01*
G01X613357Y93237D02*
X614057D01*
G01X622215D02*
X622915D01*
G01Y93453D02*
X622215D01*
G01X614057D02*
X613357D01*
G01X622915Y93549D02*
X622215D01*
G01X614057D02*
X613357D01*
G01X622915Y93611D02*
X622215D01*
G01X614057D02*
X613357D01*
G01X622915Y93709D02*
X622215D01*
G01X614057D02*
X613357D01*
G01X622915Y94693D02*
X622215D01*
G01X614057D02*
X613357D01*
G01X622915Y94792D02*
X622215D01*
G01X614057D02*
X613357D01*
G01X622915Y94855D02*
X622215D01*
G01X614057D02*
X613357D01*
G01X622915Y94949D02*
X622215D01*
G01X614057D02*
X613357D01*
G01Y95166D02*
X614057D01*
G01X622215D02*
X622915D01*
G01X616309Y95993D02*
X617009D01*
G01X625167D02*
X625867D01*
G01Y96209D02*
X625167D01*
G01X617009D02*
X616309D01*
G01X625867Y96305D02*
X625167D01*
G01X617009D02*
X616309D01*
G01X625867Y96367D02*
X625167D01*
G01X617009D02*
X616309D01*
G01X625867Y96465D02*
X625167D01*
G01X617009D02*
X616309D01*
G01X625867Y97449D02*
X625167D01*
G01X617009D02*
X616309D01*
G01X625867Y97548D02*
X625167D01*
G01X617009D02*
X616309D01*
G01X625867Y97610D02*
X625167D01*
G01X617009D02*
X616309D01*
G01X625867Y97705D02*
X625167D01*
G01X617009D02*
X616309D01*
G01Y97922D02*
X617009D01*
G01X625167D02*
X625867D01*
G01X619962Y98749D02*
X619262D01*
G01X611104D02*
X610404D01*
G01Y98965D02*
X611104D01*
G01X619262D02*
X619962D01*
G01X610404Y99060D02*
X611104D01*
G01X619262D02*
X619962D01*
G01X610404Y99123D02*
X611104D01*
G01X619262D02*
X619962D01*
G01Y99221D02*
X619262D01*
G01X611104D02*
X610404D01*
G01X619962Y100205D02*
X619262D01*
G01X611104D02*
X610404D01*
G01X619962Y100304D02*
X619262D01*
G01X611104D02*
X610404D01*
G01Y100366D02*
X611104D01*
G01X619262D02*
X619962D01*
G01Y100461D02*
X619262D01*
G01X611104D02*
X610404D01*
G01X619962Y100678D02*
X619262D01*
G01X611104D02*
X610404D01*
G01X609179Y102336D02*
X635951D01*
G01X604034Y96578D02*
Y105171D01*
G01X605356Y107942D02*
Y106958D01*
G01X605563Y92636D02*
Y96542D01*
G01X605955Y104171D02*
Y97578D01*
G01X606356Y107942D02*
Y106958D01*
G01X608959Y105958D02*
Y106958D01*
G01X609179Y105171D02*
Y102336D01*
G01X609959Y106958D02*
Y105958D01*
G01X610404Y83790D02*
Y85716D01*
G01Y98750D02*
Y100676D01*
G01X611104Y83790D02*
Y85716D01*
G01Y98751D02*
Y100677D01*
G01X611955Y106958D02*
Y105958D01*
G01X611959Y105171D02*
Y106958D01*
G01X612975D02*
Y105958D01*
G01X613357Y93238D02*
Y95164D01*
G01X614057Y93239D02*
Y95165D01*
G01X614318Y105958D02*
Y106958D01*
G01X615130D02*
Y105958D01*
G01X615222D02*
Y106958D01*
G01X615708Y105958D02*
Y106958D01*
G01X615760Y105958D02*
Y106958D01*
G01X616167Y105958D02*
Y106958D01*
G01X616309Y81034D02*
Y82960D01*
G01Y95994D02*
Y97920D01*
G01X617009Y81034D02*
Y82960D01*
G01Y95995D02*
Y97921D01*
G01X617152Y106958D02*
Y105958D01*
G01X617563D02*
Y106958D01*
G01X617615Y105958D02*
Y106958D01*
G01X618096Y105958D02*
Y106958D01*
G01X618193Y105958D02*
Y106958D01*
G01X618845Y105958D02*
Y106958D01*
G01X619262Y83790D02*
Y85716D01*
G01Y98750D02*
Y100676D01*
G01X619612Y102336D02*
Y105171D01*
G01Y105958D02*
Y106958D01*
G01X619962Y83790D02*
Y85716D01*
G01Y98751D02*
Y100677D01*
G01X620345Y105958D02*
Y106958D01*
G01X620990Y102336D02*
Y105171D01*
G01X622215Y93238D02*
Y95164D01*
G01X622915Y93239D02*
Y95165D01*
G01X625167Y81034D02*
Y82960D01*
G01Y95994D02*
Y97920D01*
G01X625518Y105958D02*
Y106958D01*
G01X625867Y81034D02*
Y82960D01*
G01Y95995D02*
Y97921D01*
G01X605563Y96542D02*
G03X604563Y97542I-1000J0D01*
G01Y91636D02*
G03X605563Y92636I0J1000D01*
G01X604955Y96578D02*
G03X605955Y97578I0J1000D01*
G01Y104171D02*
G03X604955Y105171I-1000J0D01*
G01X613357Y78276D02*
X614057D01*
G01X622215D02*
X622915D01*
G01Y78493D02*
X622215D01*
G01X614057D02*
X613357D01*
G01X622915Y78588D02*
X622215D01*
G01X614057D02*
X613357D01*
G01X622915Y78650D02*
X622215D01*
G01X614057D02*
X613357D01*
G01X622915Y78749D02*
X622215D01*
G01X614057D02*
X613357D01*
G01X604372Y77812D02*
Y96578D01*
G01X613357Y78278D02*
Y80204D01*
G01X614057Y78278D02*
Y80204D01*
G01X622215Y78278D02*
Y80204D01*
G01X622915Y78278D02*
Y80204D01*
G01X605955Y76812D02*
G03X604955Y77812I-1000J0D01*
G01X636053Y138297D02*
X638514Y137794D01*
G01X637037Y140810D02*
X639006Y140307D01*
G01X635069Y141815D02*
X637037Y140810D01*
G01X633593Y139805D02*
X636053Y138297D01*
G01X632116Y141312D02*
X633593Y139805D01*
G01X631132Y143825D02*
X632116Y141312D01*
G01X627195Y137794D02*
X624734D01*
G01X620797D02*
X617844D01*
G01X624734Y140307D02*
X627195D01*
G01X610955D02*
Y137794D01*
G01X617844D02*
Y157395D01*
G01X620797Y161416D02*
Y137794D01*
G01X624734D02*
Y140307D01*
G01X627195D02*
Y137794D01*
G01X639006Y148851D02*
X637037Y148349D01*
G01X639006Y158903D02*
X637037Y158401D01*
G01X639006Y161416D02*
X636545Y160914D01*
G01X637037Y151364D02*
X639006Y150862D01*
G01X634085Y150359D02*
X635069Y149856D01*
G01Y152872D02*
X637037Y151364D01*
G01X632608Y151867D02*
X634085Y150359D01*
G01Y154380D02*
X635069Y152872D01*
G01X631624Y153877D02*
X632608Y151867D01*
G01X631624Y155385D02*
Y153877D01*
G01X634085Y155385D02*
Y154380D01*
G01X632608Y157898D02*
X631624Y155385D01*
G01X635069Y156893D02*
X634085Y155385D01*
G01Y159406D02*
X632608Y157898D01*
G01X637037Y158401D02*
X635069Y156893D01*
G01X634085Y149354D02*
X632116Y147846D01*
G01X636545Y160914D02*
X634085Y159406D01*
G01X635069Y149856D02*
X634085Y149354D01*
G01X637037Y148349D02*
X635069Y147343D01*
G01X633593Y143825D02*
X635069Y141815D01*
G01X631132Y145333D02*
Y143825D01*
G01X633593Y145333D02*
Y143825D01*
G01X632116Y147846D02*
X631132Y145333D01*
G01X635069Y147343D02*
X633593Y145333D01*
G01X617844Y161416D02*
X620797D01*
G01X603573D02*
X606526Y160914D01*
G01D02*
X608494Y159908D01*
G01X607018Y157395D02*
X605541Y158401D01*
G01X608494Y159908D02*
X610463Y157898D01*
G01X608002Y155888D02*
X607018Y157395D01*
G01X610463Y157898D02*
X610955Y155888D01*
G01X608002Y154882D02*
Y155888D01*
G01X610955D02*
Y154882D01*
G01X614892Y153877D02*
Y157898D01*
G01X610955Y154882D02*
X610463Y152872D01*
G01X607018D02*
X608002Y154882D01*
G01X610463Y152872D02*
X609478Y151364D01*
G01X614892Y157898D02*
X617844Y161416D01*
G01Y157395D02*
X614892Y153877D01*
G01X618119Y474684D02*
Y514054D01*
G01X623040Y493112D02*
Y474684D01*
G01D02*
X618119D01*
G01X623040Y514054D02*
Y498138D01*
G01X646006Y493112D02*
X623040D01*
G01Y498138D02*
X646006D01*
G01X618119Y514054D02*
X623040D01*
G01X628248Y892519D02*
Y883464D01*
G01X629232D02*
Y892519D01*
G01X631398D02*
Y883464D01*
G01X632382D02*
Y892519D01*
G01X634547D02*
Y883464D01*
G01X635000Y864408D02*
Y876219D01*
G01X635531Y883464D02*
Y892519D01*
G01X636476Y876219D02*
Y871445D01*
G01Y869937D02*
Y864408D01*
G01D02*
X635000D01*
G01X643366Y869937D02*
X636476D01*
G01Y871445D02*
X643366D01*
G01X635000Y876219D02*
X636476D01*
G01X637697Y883464D02*
X635531D01*
G01X634547D02*
X632382D01*
G01X631398D02*
X629232D01*
G01X604035D02*
Y892519D01*
G01X606201D02*
Y883464D01*
G01X607185D02*
Y892519D01*
G01X609350D02*
Y883464D01*
G01X610335D02*
Y892519D01*
G01X612500D02*
Y883464D01*
G01X613484D02*
Y892519D01*
G01X615650D02*
Y883464D01*
G01X616634D02*
Y892519D01*
G01X618799D02*
Y883464D01*
G01X619783D02*
Y892519D01*
G01X621949D02*
Y883464D01*
G01X622933D02*
Y892519D01*
G01X625098D02*
Y883464D01*
G01X626083D02*
Y892519D01*
G01X628248Y883464D02*
X626083D01*
G01X625098D02*
X622933D01*
G01X621949D02*
X619783D01*
G01X618799D02*
X616634D01*
G01X615650D02*
X613484D01*
G01X612500D02*
X610335D01*
G01X609350D02*
X607185D01*
G01X606201D02*
X604035D01*
G01X629232Y892519D02*
X631398D01*
G01X632382D02*
X634547D01*
G01X635531D02*
X637697D01*
G01X604035D02*
X606201D01*
G01X610335D02*
X612500D01*
G01X607185D02*
X609350D01*
G01X613484D02*
X615650D01*
G01X619783D02*
X621949D01*
G01X616634D02*
X618799D01*
G01X622933D02*
X625098D01*
G01X626083D02*
X628248D01*
G01X634612Y939377D02*
X633638Y940099D01*
X633151Y940821D01*
X632663Y942265D01*
Y945152D01*
X633151Y946595D01*
X633638Y947317D01*
X634612Y948039D01*
X635587Y947317D01*
X636074Y946595D01*
X636561Y945152D01*
Y942265D01*
X636074Y940821D01*
X635587Y940099D01*
X634612Y939377D01*
G01X709449Y937212D02*
X607329D01*
G01D02*
X713780D01*
G01X609278Y946595D02*
X609765Y947317D01*
X610739Y948039D01*
X611714D01*
X612688Y947317D01*
X613175Y946595D01*
Y945152D01*
X612688Y944430D01*
X610739Y942986D01*
G01D02*
X609765Y941543D01*
X609278Y939377D01*
X613175D01*
G01X624868Y946595D02*
X625356Y947317D01*
X626330Y948039D01*
X627304D01*
X628279Y947317D01*
X628766Y946595D01*
Y945152D01*
X628279Y944430D01*
X626330Y942986D01*
G01D02*
X625356Y941543D01*
X624868Y939377D01*
X628766D01*
G01X619022D02*
X618535D01*
Y940099D01*
X619022Y939377D01*
G01X621665Y2171102D02*
Y2152090D01*
G01X659711Y-727083D02*
Y-616847D01*
G01Y-506611D02*
Y-616847D01*
G01X655380Y-627078D02*
X654659D01*
G01D02*
X653215Y-626104D01*
X652493Y-625129D01*
Y-624155D01*
X653215Y-623181D01*
G01D02*
X654659Y-622206D01*
X655380D01*
X656102Y-622694D01*
X656824Y-623181D01*
X657546Y-624155D01*
Y-625129D01*
G01Y-616847D02*
Y-617334D01*
X656824D01*
X657546Y-616847D01*
G01Y-601257D02*
X656824Y-602231D01*
X656102Y-602718D01*
X654659Y-603205D01*
X651772D01*
X650328Y-602718D01*
X649606Y-602231D01*
X648884Y-601257D01*
X649606Y-600282D01*
X650328Y-599795D01*
X651772Y-599308D01*
X654659D01*
X656102Y-599795D01*
X656824Y-600282D01*
X657546Y-601257D01*
G01Y-609052D02*
X656824Y-610026D01*
X656102Y-610513D01*
X654659Y-611001D01*
X651772D01*
X650328Y-610513D01*
X649606Y-610026D01*
X648884Y-609052D01*
X649606Y-608077D01*
X650328Y-607590D01*
X651772Y-607103D01*
X654659D01*
X656102Y-607590D01*
X656824Y-608077D01*
X657546Y-609052D01*
G01X652493Y-625129D02*
X651772Y-626104D01*
X651050Y-626591D01*
X650328D01*
X649606Y-626104D01*
X648884Y-625129D01*
Y-624155D01*
X649606Y-623181D01*
X650328Y-622694D01*
X651050D01*
X651772Y-623181D01*
X652493Y-624155D01*
G01X657546Y-625129D02*
X656824Y-626104D01*
X655380Y-627078D01*
G01X650328Y-634386D02*
X649606Y-633899D01*
X648884Y-632925D01*
Y-631950D01*
X649606Y-630976D01*
X650328Y-630489D01*
X651772D01*
X652493Y-630976D01*
G01D02*
X653937Y-632925D01*
X655380Y-633899D01*
X657546Y-634386D01*
Y-630489D01*
G01X651282Y-89785D02*
Y-98447D01*
G01X641538Y-95560D02*
X642026Y-94116D01*
X643487Y-93394D01*
X644949Y-94116D01*
X645436Y-95560D01*
X644949Y-97003D01*
X644461Y-97725D01*
X643487Y-98447D01*
X642513Y-97725D01*
X642026Y-97003D01*
X641538Y-95560D01*
Y-92672D01*
X642026Y-91229D01*
X642513Y-90507D01*
X643487Y-89785D01*
X644461Y-90507D01*
X644949Y-91229D01*
G01X657129Y-95560D02*
X657616Y-94116D01*
X659078Y-93394D01*
X660539Y-94116D01*
X661026Y-95560D01*
X660539Y-97003D01*
X660052Y-97725D01*
X659078Y-98447D01*
X658103Y-97725D01*
X657616Y-97003D01*
X657129Y-95560D01*
Y-92672D01*
X657616Y-91229D01*
X658103Y-90507D01*
X659078Y-89785D01*
X660052Y-90507D01*
X660539Y-91229D01*
G01X670230Y-39467D02*
X661562D01*
G01X669896Y-39440D02*
X661896D01*
G01X674829Y-33775D02*
X666631D01*
G01X674815Y-33102D02*
X666646D01*
G01Y-32967D02*
X674815D01*
G01Y-31261D02*
X666646D01*
G01Y-30829D02*
X674815D01*
G01Y-30744D02*
X666646D01*
G01X665160Y-33775D02*
X665154Y-33744D01*
X665150Y-33713D01*
X665147Y-33682D01*
G01Y-33663D02*
X665150Y-33701D01*
X665154Y-33738D01*
X665160Y-33775D01*
G01X665147Y-33682D02*
X665146Y-33647D01*
G01Y-33621D02*
X665147Y-33663D01*
G01X663012Y-34319D02*
Y-32749D01*
G01X663631D02*
Y-34319D01*
G01X665147Y-33682D02*
Y-33663D01*
G01X665146Y-17548D02*
Y-33647D01*
G01X666646D02*
Y-17548D01*
G01X666645Y-33663D02*
Y-33682D01*
G01X668160Y-34319D02*
Y-32749D01*
G01X668780D02*
Y-34319D01*
G01X666645Y-33663D02*
X666646Y-33621D01*
G01Y-33647D02*
X666645Y-33682D01*
G01D02*
X666642Y-33713D01*
X666638Y-33744D01*
X666631Y-33775D01*
G01D02*
X666638Y-33738D01*
X666642Y-33701D01*
X666645Y-33663D01*
G01X670896Y-40440D02*
G03X669896Y-39440I-1000J0D01*
G01X670896Y-40398D02*
G03X670230Y-39467I-984J0D01*
G01X665160Y-33775D02*
G03X665896Y-34378I734J145D01*
G01D02*
G03X666631Y-33775I1J748D01*
G01X665896Y-32016D02*
G03X666646Y-31261I2J748D01*
G01X665146D02*
G03X665896Y-32016I748J-7D01*
G01X670896Y-41835D02*
X660896D01*
G01X670981Y-41635D02*
X660810D01*
G01X670896Y-41461D02*
X660896D01*
G01Y-41403D02*
X670896D01*
G01X660896Y-41135D02*
X670896D01*
G01Y-41107D02*
X660896D01*
G01X651482Y-39469D02*
X647648D01*
G01X640837D02*
X637199D01*
G01X651285Y-39154D02*
X647648D01*
G01X640640D02*
X637199D01*
G01X647279Y-38336D02*
X644008D01*
G01Y-34399D02*
X647279D01*
G01X646815Y-34338D02*
X646749D01*
G01X641735D02*
X641669D01*
G01X660581Y-34319D02*
X671211D01*
G01X665160Y-33775D02*
X656962D01*
G01X655491D02*
X647307D01*
G01X651482Y-33249D02*
X647648D01*
G01X640837D02*
X637199D01*
G01X665146Y-33102D02*
X656976D01*
G01X655476D02*
X647307D01*
G01Y-32967D02*
X655476D01*
G01X656976D02*
X665146D01*
G01X687049Y-32749D02*
X644742D01*
G01X643227Y-32023D02*
X645257D01*
G01X665145Y-31261D02*
X656977D01*
G01X647307Y-30829D02*
X655476D01*
G01X656976D02*
X665146D01*
G01Y-30744D02*
X656976D01*
G01X655476D02*
X647307D01*
G01X655476Y-31261D02*
X647307Y-31255D01*
G01X644742Y-28812D02*
X687049D01*
G01X655491Y-33775D02*
X655485Y-33744D01*
X655480Y-33713D01*
X655478Y-33682D01*
G01Y-33663D02*
X655480Y-33701D01*
X655485Y-33738D01*
X655491Y-33775D01*
G01X655478Y-33682D02*
X655476Y-33647D01*
G01Y-33621D02*
X655478Y-33663D01*
G01X644742Y-32749D02*
X644747Y-42635D01*
G01X641177Y-17548D02*
Y-33845D01*
G01X641230Y-33339D02*
Y-38564D01*
G01X641427Y-33839D02*
Y-38879D01*
G01X642177Y-22238D02*
Y-31524D01*
G01X642227Y-33023D02*
Y-33845D01*
G01X643742Y-32749D02*
Y-42635D01*
G01Y-28812D02*
Y105958D01*
G01X644008Y-34399D02*
Y-38336D01*
G01X644742Y-42635D02*
Y-32749D01*
G01Y-28812D02*
Y105958D01*
G01X645742Y-38336D02*
Y-34399D01*
G01X646257Y-33023D02*
Y-33845D01*
G01X646307Y-22238D02*
Y-31524D01*
G01X647057Y-38879D02*
Y-33339D01*
G01X647307Y-17548D02*
Y-33845D01*
G01X644749Y-14225D02*
X644742Y-28812D01*
G01X648279Y-35399D02*
Y-37336D01*
G01X651876Y-33339D02*
Y-38564D01*
G01X652073Y-33839D02*
Y-38879D01*
G01X655478Y-33682D02*
Y-33663D01*
G01X655476Y-17548D02*
Y-33647D01*
G01X656976D02*
Y-17548D01*
G01Y-33663D02*
Y-33682D01*
G01X660581Y-34319D02*
Y-32749D01*
G01X660896Y-41835D02*
Y-40398D01*
G01X656976Y-33663D02*
Y-33621D01*
G01Y-33647D02*
Y-33682D01*
G01D02*
X656973Y-33713D01*
X656969Y-33744D01*
X656962Y-33775D01*
G01D02*
X656969Y-33738D01*
X656973Y-33701D01*
X656976Y-33663D01*
G01X660103Y-41928D02*
X659689Y-42342D01*
G01X647279Y-38336D02*
G03X648279Y-37336I0J1000D01*
G01X651285Y-39154D02*
G03X651876Y-38564I1J590D01*
G01X651482Y-39469D02*
G03X652073Y-38879I0J591D01*
G01X647057D02*
G03X647648Y-39469I591J1D01*
G01X647057Y-38564D02*
G03X647648Y-39154I591J1D01*
G01X640640D02*
G03X641230Y-38564I0J590D01*
G01X640837Y-39469D02*
G03X641427Y-38879I0J590D01*
G01Y-33839D02*
G03X640837Y-33249I-590J0D01*
G01X641230Y-33339D02*
G03X640640Y-32749I-590J0D01*
G01X641230Y-33839D02*
G03X640640Y-33249I-590J0D01*
G01X641177Y-33845D02*
G03X641669Y-34338I492J-1D01*
G01X641735D02*
G03X642227Y-33845I0J492D01*
G01X641677Y-32016D02*
G03X642177Y-31524I8J492D01*
G01X641177D02*
G03X641677Y-32016I492J0D01*
G01X648279Y-35399D02*
G03X647279Y-34399I-1000J0D01*
G01X651876Y-33339D02*
G03X651285Y-32749I-590J0D01*
G01X647648D02*
G03X647057Y-33339I0J-591D01*
G01X647648Y-33249D02*
G03X647057Y-33839I0J-591D01*
G01X651876D02*
G03X651285Y-33249I-590J0D01*
G01X652073Y-33839D02*
G03X651482Y-33249I-591J-1D01*
G01X646257Y-33845D02*
G03X646749Y-34338I492J-1D01*
G01X646815D02*
G03X647307Y-33845I0J492D01*
G01X643227Y-32023D02*
G03X642227Y-33023I0J-1000D01*
G01X646257D02*
G03X645257Y-32023I-1000J0D01*
G01X646807Y-32016D02*
G03X647307Y-31524I8J492D01*
G01X646307D02*
G03X646807Y-32016I492J0D01*
G01X660810Y-41635D02*
G03X660103Y-41928I0J-1000D01*
G01X658981Y-42635D02*
G03X659689Y-42342I1J1000D01*
G01X661896Y-39440D02*
G03X660896Y-40440I0J-1000D01*
G01X658381Y-41435D02*
G03X659339Y-40679I0J984D01*
G01X661562Y-39467D02*
G03X660896Y-40398I318J-931D01*
G01Y-40845D02*
G03X659339Y-40679I-787J0D01*
G01X655491Y-33775D02*
G03X656226Y-34378I734J145D01*
G01D02*
G03X656962Y-33775I2J748D01*
G01X656226Y-32016D02*
G03X656976Y-31261I2J748D01*
G01X655477D02*
G03X656226Y-32016I748J-7D01*
G01X667433Y-16798D02*
X667280Y-16813D01*
X667133Y-16857D01*
X666998Y-16929D01*
X666876Y-17028D01*
X666779Y-17146D01*
X666706Y-17281D01*
X666661Y-17427D01*
X666646Y-17582D01*
G01X667433Y-16904D02*
X667280Y-16917D01*
X667133Y-16954D01*
X666998Y-17015D01*
X666876Y-17099D01*
X666779Y-17199D01*
X666706Y-17313D01*
X666661Y-17437D01*
X666646Y-17568D01*
G01X674815Y-18862D02*
X666646D01*
G01Y-18845D02*
X674815D01*
G01Y-18516D02*
X666646D01*
G01Y-18481D02*
X674815D01*
G01Y-18138D02*
X666646D01*
G01Y-18104D02*
X674815D01*
G01X666646Y-17890D02*
X674815D01*
G01Y-17679D02*
X666646D01*
G01X667433Y-17116D02*
X674028D01*
G01Y-16904D02*
X667433D01*
G01Y-16798D02*
X674028D01*
G01Y-16764D02*
X667433D01*
G01X664358Y-17116D02*
X664511Y-17128D01*
X664659Y-17166D01*
X664794Y-17227D01*
X664915Y-17310D01*
X665013Y-17410D01*
X665085Y-17525D01*
X665130Y-17649D01*
X665146Y-17780D01*
G01X664358Y-16764D02*
X664511Y-16779D01*
X664659Y-16823D01*
X664794Y-16895D01*
X664915Y-16994D01*
X665013Y-17112D01*
X665085Y-17247D01*
X665130Y-17393D01*
X665146Y-17548D01*
G01Y-17582D02*
X665131Y-17430D01*
X665087Y-17284D01*
X665014Y-17149D01*
X664915Y-17028D01*
X664796Y-16931D01*
X664661Y-16858D01*
X664514Y-16814D01*
X664358Y-16798D01*
G01X665146Y-17568D02*
X665131Y-17439D01*
X665087Y-17315D01*
X665014Y-17201D01*
X664915Y-17099D01*
X664796Y-17016D01*
X664661Y-16955D01*
X664514Y-16917D01*
X664358Y-16904D01*
G01Y-16764D02*
Y-16798D01*
G01Y-17116D02*
Y-16904D01*
G01X667433D02*
Y-17116D01*
G01Y-16798D02*
Y-16764D01*
G01X666646Y-17548D02*
X666661Y-17396D01*
X666705Y-17249D01*
X666778Y-17114D01*
X666876Y-16994D01*
X666995Y-16896D01*
X667131Y-16824D01*
X667278Y-16779D01*
X667433Y-16764D01*
G01X666646Y-17780D02*
X666661Y-17651D01*
X666705Y-17527D01*
X666778Y-17412D01*
X666876Y-17310D01*
X666995Y-17228D01*
X667131Y-17167D01*
X667278Y-17129D01*
X667433Y-17116D01*
G01X666646Y-24077D02*
X674815D01*
G01Y-23942D02*
X666646D01*
G01X674815Y-23756D02*
X666646D01*
G01Y-23671D02*
X674815D01*
G01X666646Y-23348D02*
X674815D01*
G01Y-23331D02*
X666646D01*
G01Y-23097D02*
X674815D01*
G01Y-23063D02*
X666646D01*
G01X657764Y-16798D02*
X657611Y-16813D01*
X657464Y-16857D01*
X657328Y-16929D01*
X657207Y-17028D01*
X657109Y-17146D01*
X657037Y-17281D01*
X656992Y-17427D01*
X656976Y-17582D01*
G01X648094Y-16798D02*
X647942Y-16813D01*
X647794Y-16857D01*
X647659Y-16929D01*
X647538Y-17028D01*
X647440Y-17146D01*
X647368Y-17281D01*
X647323Y-17427D01*
X647307Y-17582D01*
G01X650402Y-16904D02*
X650244Y-16918D01*
X650092Y-16958D01*
X649953Y-17023D01*
X649830Y-17112D01*
X649733Y-17218D01*
X649662Y-17341D01*
G01X657764Y-16904D02*
X657611Y-16917D01*
X657464Y-16954D01*
X657328Y-17015D01*
X657207Y-17099D01*
X657109Y-17199D01*
X657037Y-17313D01*
X656992Y-17437D01*
X656976Y-17568D01*
G01X665146Y-18862D02*
X656976D01*
G01X653680D02*
X649104D01*
G01Y-18845D02*
X653680D01*
G01X656976D02*
X665146D01*
G01X655476Y-18516D02*
X647307D01*
G01X665146D02*
X656976D01*
G01X647307Y-18481D02*
X655476D01*
G01X656976D02*
X665146D01*
G01Y-18138D02*
X656976D01*
G01X655476D02*
X647307D01*
G01Y-18104D02*
X655476D01*
G01X656976D02*
X665146D01*
G01X649516Y-17890D02*
X653268D01*
G01X656976D02*
X665146D01*
G01Y-17679D02*
X656976D01*
G01X653268D02*
X649516D01*
G01X657346Y-17318D02*
X652425D01*
G01X644010Y-17178D02*
X647870D01*
G01X650402Y-17116D02*
X652382D01*
G01X657764D02*
X664358D01*
G01Y-16904D02*
X657764D01*
G01X652382D02*
X650402D01*
G01X648094Y-16798D02*
X654689D01*
G01X657764D02*
X664358D01*
G01Y-16764D02*
X657764D01*
G01X654689D02*
X648094D01*
G01X644010Y-15934D02*
X649254D01*
G01X657346Y-14786D02*
X652425D01*
G01Y-14307D02*
X657346D01*
G01X647870Y-11273D02*
X644010D01*
G01X657346Y-9699D02*
X652425D01*
G01Y-9220D02*
X657346D01*
G01X648199Y-8741D02*
X640286D01*
G01X649254Y-8060D02*
X644010D01*
G01X652425Y-6688D02*
X657346D01*
G01X644742Y-2525D02*
X643742D01*
G01Y-1874D02*
X644742D01*
G01X643742Y-1777D02*
X644742D01*
G01X657346Y-1570D02*
X652425D01*
G01X643742Y-1273D02*
X644742D01*
G01X643742Y-1244D02*
X644742D01*
G01Y-832D02*
X643742D01*
G01Y153D02*
X644742D01*
G01X643742Y560D02*
X644742D01*
G01X643742Y590D02*
X644742D01*
G01X657346Y962D02*
X652425D01*
G01X643742Y1097D02*
X644742D01*
G01Y1190D02*
X643742D01*
G01X652425Y1441D02*
X657346D01*
G01X644742Y1845D02*
X643742D01*
G01X644742Y3845D02*
X643742D01*
G01X644742Y4436D02*
X643742D01*
G01X657346Y6049D02*
X652425D01*
G01X638083Y-17116D02*
X638241Y-17129D01*
X638393Y-17170D01*
X638532Y-17234D01*
X638655Y-17323D01*
X638752Y-17430D01*
X638822Y-17553D01*
G01X652382Y-17116D02*
X652540Y-17129D01*
X652692Y-17170D01*
X652831Y-17234D01*
X652954Y-17323D01*
X653051Y-17430D01*
X653122Y-17553D01*
G01X640390Y-16764D02*
X640543Y-16779D01*
X640690Y-16823D01*
X640826Y-16895D01*
X640947Y-16994D01*
X641044Y-17112D01*
X641117Y-17247D01*
X641162Y-17393D01*
X641177Y-17548D01*
G01X654689Y-16764D02*
X654842Y-16779D01*
X654989Y-16823D01*
X655125Y-16895D01*
X655246Y-16994D01*
X655343Y-17112D01*
X655416Y-17247D01*
X655461Y-17393D01*
X655476Y-17548D01*
G01X638822Y-17341D02*
X638753Y-17220D01*
X638657Y-17114D01*
X638537Y-17025D01*
X638395Y-16959D01*
X638244Y-16918D01*
X638083Y-16904D01*
G01X653122Y-17341D02*
X653052Y-17220D01*
X652956Y-17114D01*
X652836Y-17025D01*
X652694Y-16959D01*
X652543Y-16918D01*
X652382Y-16904D01*
G01X638969Y-17890D02*
X639106Y-18195D01*
X639243Y-18522D01*
X639381Y-18862D01*
G01X638822Y-17553D02*
X638969Y-17890D01*
G01Y-17679D02*
X638822Y-17341D01*
G01X653268Y-17890D02*
X653405Y-18195D01*
X653543Y-18522D01*
X653680Y-18862D01*
G01X653122Y-17553D02*
X653268Y-17890D01*
G01Y-17679D02*
X653122Y-17341D01*
G01X639361Y-14327D02*
X642118Y-21902D01*
G01X639381Y-18845D02*
X639243Y-18437D01*
X639106Y-18044D01*
X638969Y-17679D01*
G01X653680Y-18845D02*
X653543Y-18437D01*
X653405Y-18044D01*
X653268Y-17679D01*
G01X641177Y-17582D02*
X641162Y-17430D01*
X641118Y-17284D01*
X641046Y-17149D01*
X640947Y-17028D01*
X640828Y-16931D01*
X640693Y-16858D01*
X640546Y-16814D01*
X640390Y-16798D01*
G01X655476Y-17582D02*
X655461Y-17430D01*
X655417Y-17284D01*
X655345Y-17149D01*
X655246Y-17028D01*
X655127Y-16931D01*
X654992Y-16858D01*
X654845Y-16814D01*
X654689Y-16798D01*
G01X638083Y-17116D02*
Y-16904D01*
G01X638822Y-17341D02*
Y-17553D01*
G01X638969Y-17890D02*
Y-17679D01*
G01X639302Y-9725D02*
Y-13990D01*
G01X639381Y-18845D02*
Y-18862D01*
G01X640390Y-16764D02*
Y-16798D01*
G01X644010Y-8060D02*
Y-17178D01*
G01X644747Y31917D02*
X644749Y-6351D01*
G01X644760Y-14225D02*
Y-6351D01*
G01X645742Y-15934D02*
Y-8060D01*
G01X645746Y-11273D02*
Y-17178D01*
G01X648094Y-16798D02*
Y-16764D01*
G01X648870Y-12273D02*
Y-16178D01*
G01X649104Y-18862D02*
Y-18845D01*
G01X649183Y-9725D02*
Y-13990D01*
G01X649516Y-17679D02*
Y-17890D01*
G01X649662Y-17553D02*
Y-17341D01*
G01X650254Y-9060D02*
Y-14934D01*
G01X650402Y-16904D02*
Y-17116D01*
G01X652382D02*
Y-16904D01*
G01X652425Y9060D02*
Y-1570D01*
G01Y-6688D02*
Y-17318D01*
G01X653122Y-17341D02*
Y-17553D01*
G01X653268Y-17890D02*
Y-17679D01*
G01X653680Y-18845D02*
Y-18862D01*
G01X654689Y-16764D02*
Y-16798D01*
G01X657346Y-17318D02*
Y-6688D01*
G01Y-1570D02*
Y9060D01*
G01X657764Y-16904D02*
Y-17116D01*
G01Y-16798D02*
Y-16764D01*
G01X647307Y-17548D02*
X647322Y-17396D01*
X647367Y-17249D01*
X647439Y-17114D01*
X647538Y-16994D01*
X647657Y-16896D01*
X647792Y-16824D01*
X647939Y-16779D01*
X648094Y-16764D01*
G01X656976Y-17548D02*
X656992Y-17396D01*
X657036Y-17249D01*
X657108Y-17114D01*
X657207Y-16994D01*
X657326Y-16896D01*
X657461Y-16824D01*
X657608Y-16779D01*
X657764Y-16764D01*
G01X656976Y-17780D02*
X656992Y-17651D01*
X657036Y-17527D01*
X657108Y-17412D01*
X657207Y-17310D01*
X657326Y-17228D01*
X657461Y-17167D01*
X657608Y-17129D01*
X657764Y-17116D01*
G01X649124Y-14327D02*
X646367Y-21902D01*
G01X649516Y-17679D02*
X649379Y-18044D01*
X649241Y-18437D01*
X649104Y-18845D01*
G01Y-18862D02*
X649241Y-18522D01*
X649379Y-18195D01*
X649516Y-17890D01*
G01X649662Y-17341D02*
X649516Y-17679D01*
G01Y-17890D02*
X649662Y-17553D01*
G01D02*
X649731Y-17432D01*
X649828Y-17325D01*
X649948Y-17237D01*
X650089Y-17170D01*
X650241Y-17130D01*
X650402Y-17116D01*
G01X648870Y-12273D02*
G03X647870Y-11273I-1000J0D01*
G01Y-17178D02*
G03X648870Y-16178I0J1000D01*
G01X649254Y-15934D02*
G03X650254Y-14934I0J1000D01*
G01Y-9060D02*
G03X649254Y-8060I-1000J0D01*
G01X646367Y-21902D02*
G03X646307Y-22238I924J-338D01*
G01X649124Y-14327D02*
G03X649183Y-13990I-925J336D01*
G01Y-9725D02*
G03X648199Y-8741I-984J0D01*
G01X640286D02*
G03X639302Y-9725I0J-984D01*
G01Y-13990D02*
G03X639361Y-14327I984J-1D01*
G01X642177Y-22238D02*
G03X642118Y-21902I-984J0D01*
G01X647307Y-24077D02*
X655476D01*
G01X656976D02*
X665146D01*
G01Y-23942D02*
X656976D01*
G01X655476D02*
X647307D01*
G01X665146Y-23756D02*
X656976D01*
G01X655449D02*
X647335D01*
G01Y-23671D02*
X655449D01*
G01X656976D02*
X665146D01*
G01X647469Y-23348D02*
X655315D01*
G01X656976D02*
X665146D01*
G01Y-23331D02*
X656976D01*
G01X655315D02*
X647469D01*
G01X647307Y-23097D02*
X655476D01*
G01X656976D02*
X665146D01*
G01X644742Y-23095D02*
X687049D01*
G01X665146Y-23063D02*
X656976D01*
G01X655476D02*
X647307D01*
G01X687049Y-22468D02*
X644742D01*
G01X641130Y-23615D02*
X641015Y-23331D01*
G01X655429Y-23615D02*
X655315Y-23331D01*
G01X639381Y-18862D02*
X641015Y-23348D01*
G01Y-23331D02*
X639381Y-18845D01*
G01X653680Y-18862D02*
X655315Y-23348D01*
G01Y-23331D02*
X653680Y-18845D01*
G01X641015Y-23348D02*
X641130Y-23689D01*
G01X655315Y-23348D02*
X655429Y-23689D01*
G01X641130D02*
X641137Y-23711D01*
X641144Y-23734D01*
X641150Y-23756D01*
G01X655429Y-23689D02*
X655436Y-23711D01*
X655443Y-23734D01*
X655449Y-23756D01*
G01X641150Y-23671D02*
X641144Y-23652D01*
X641137Y-23633D01*
X641130Y-23615D01*
G01X655449Y-23671D02*
X655443Y-23652D01*
X655436Y-23633D01*
X655429Y-23615D01*
G01X641150Y-23756D02*
X641158Y-23787D01*
X641165Y-23821D01*
X641170Y-23853D01*
X641174Y-23888D01*
X641176Y-23923D01*
X641177Y-23958D01*
G01X655449Y-23756D02*
X655457Y-23787D01*
X655464Y-23821D01*
X655469Y-23853D01*
X655473Y-23888D01*
X655476Y-23923D01*
Y-23958D01*
G01X641177Y-23872D02*
Y-23840D01*
X641174Y-23805D01*
X641171Y-23773D01*
X641165Y-23739D01*
X641158Y-23705D01*
X641150Y-23671D01*
G01X655476Y-23872D02*
Y-23840D01*
X655474Y-23805D01*
X655470Y-23773D01*
X655465Y-23739D01*
X655457Y-23705D01*
X655449Y-23671D01*
G01X641130Y-23689D02*
Y-23615D01*
G01X641150Y-23671D02*
Y-23756D01*
G01X647335D02*
Y-23671D01*
G01X647355Y-23615D02*
Y-23689D01*
G01X647469Y-23331D02*
Y-23339D01*
G01D02*
Y-23348D01*
G01X641015D02*
Y-23331D01*
G01X655429Y-23689D02*
Y-23615D01*
G01X655449Y-23671D02*
Y-23756D01*
G01X655315Y-23348D02*
Y-23331D01*
G01X647307Y-23958D02*
X647308Y-23925D01*
X647310Y-23891D01*
X647314Y-23858D01*
X647319Y-23824D01*
X647326Y-23790D01*
X647335Y-23756D01*
G01Y-23671D02*
X647327Y-23702D01*
X647320Y-23736D01*
X647315Y-23768D01*
X647311Y-23803D01*
X647308Y-23838D01*
X647307Y-23872D01*
G01X647335Y-23756D02*
X647341Y-23734D01*
X647348Y-23711D01*
X647355Y-23689D01*
G01D02*
X647469Y-23348D01*
G01X649104Y-18845D02*
X647469Y-23331D01*
G01Y-23348D02*
X649104Y-18862D01*
G01X647355Y-23615D02*
X647348Y-23633D01*
X647341Y-23652D01*
X647335Y-23671D01*
G01X647469Y-23331D02*
X647355Y-23615D01*
G01X669341Y12877D02*
X667341D01*
G01Y14058D02*
X668341D01*
G01X662569Y18393D02*
X663269D01*
G01X665522D02*
X666222D01*
G01X668474D02*
X669174D01*
G01X668341Y18585D02*
X667341D01*
G01X669341Y19766D02*
X667341D01*
G01X669174Y21371D02*
X668474D01*
G01X666222D02*
X665522D01*
G01X663269D02*
X662569D01*
G01X669174Y24336D02*
X668474D01*
G01X666222D02*
X665522D01*
G01X663269D02*
X662569D01*
G01X669174Y24561D02*
X668474D01*
G01X666222D02*
X665522D01*
G01X663269D02*
X662569D01*
G01X669551Y27251D02*
X666598D01*
G01X665598D02*
X662241D01*
G01X669551Y28251D02*
X666598D01*
G01X665598D02*
X662241D01*
G01X669551Y29251D02*
X666598D01*
G01X665598D02*
X662241D01*
G01X669551Y29501D02*
X666598D01*
G01X665598D02*
X662241D01*
G01X669157Y29645D02*
X662634D01*
G01X667189Y31367D02*
X668961D01*
G01X665008Y32851D02*
X662831D01*
G01X664517Y34687D02*
X665347Y34292D01*
X666279Y34145D01*
X667209Y34260D01*
X668095Y34632D01*
X668874Y35247D01*
X669470Y36062D01*
X669850Y37073D01*
G01X664517Y34686D02*
X665328Y34298D01*
X666250Y34147D01*
X667182Y34252D01*
X668077Y34621D01*
X668865Y35238D01*
X669467Y36057D01*
X669850Y37073D01*
G01X669022Y41985D02*
X671974Y39032D01*
G01X669434Y39341D02*
X668741Y40133D01*
X667902Y40686D01*
X666950Y40994D01*
X665973Y41031D01*
X665049Y40806D01*
X664228Y40333D01*
X663600Y39674D01*
G01X669433Y39341D02*
X668776Y40265D01*
X667878Y40969D01*
X666778Y41398D01*
X665620Y41489D01*
X664482Y41238D01*
X663480Y40682D01*
X662670Y39846D01*
X662135Y38822D01*
X661920Y37666D01*
X662048Y36502D01*
X662497Y35448D01*
X663250Y34547D01*
X664243Y33899D01*
X665381Y33574D01*
X666546Y33592D01*
X667656Y33950D01*
X668615Y34614D01*
X669352Y35547D01*
X669782Y36666D01*
X669860Y37866D01*
X669563Y39065D01*
X668955Y40063D01*
X668098Y40833D01*
X667005Y41340D01*
X665840Y41497D01*
X664698Y41313D01*
X663630Y40790D01*
X662788Y40005D01*
X662205Y39005D01*
X661931Y37852D01*
X661999Y36714D01*
X662393Y35630D01*
X663089Y34697D01*
X664041Y33999D01*
X665140Y33612D01*
X666292Y33560D01*
X667408Y33837D01*
X668349Y34385D01*
X669126Y35195D01*
X669664Y36241D01*
X669872Y37379D01*
X669739Y38551D01*
X669284Y39606D01*
X668530Y40501D01*
X667552Y41136D01*
X666406Y41464D01*
X665278Y41451D01*
X664165Y41101D01*
X663213Y40458D01*
X662465Y39533D01*
X662012Y38387D01*
X661930Y37197D01*
X662185Y36081D01*
X662752Y35079D01*
X663593Y34274D01*
X664653Y33738D01*
X665827Y33540D01*
X667022Y33702D01*
X668074Y34188D01*
X668945Y34961D01*
X669555Y35956D01*
X669851Y37089D01*
X669808Y38249D01*
X669433Y39341D01*
G01D02*
X669758Y38627D01*
X669900Y37855D01*
G01X669852Y38246D02*
X669470Y39363D01*
X668781Y40321D01*
X667841Y41039D01*
X666735Y41452D01*
X665557Y41526D01*
X664401Y41253D01*
X663389Y40664D01*
X662578Y39792D01*
X662061Y38731D01*
X661874Y37567D01*
X662035Y36392D01*
X662523Y35327D01*
X663315Y34434D01*
X664322Y33817D01*
X665461Y33520D01*
X666642Y33566D01*
X667756Y33953D01*
X668717Y34651D01*
X669429Y35597D01*
X669834Y36703D01*
X669902Y37880D01*
X669623Y39030D01*
X669023Y40048D01*
X668149Y40850D01*
X667085Y41361D01*
X665919Y41540D01*
X664749Y41373D01*
X663681Y40876D01*
X662797Y40083D01*
X662186Y39072D01*
X661895Y37928D01*
X661948Y36749D01*
X662341Y35636D01*
X663041Y34685D01*
X663988Y33978D01*
X665098Y33577D01*
X666278Y33515D01*
X667425Y33799D01*
X668438Y34402D01*
X669233Y35274D01*
X669741Y36340D01*
X669918Y37508D01*
X669748Y38676D01*
X669245Y39745D01*
X668460Y40618D01*
X667450Y41228D01*
X666306Y41519D01*
X665126Y41466D01*
X664009Y41070D01*
X663070Y40380D01*
X662362Y39439D01*
X661957Y38330D01*
X661891Y37152D01*
X662172Y35999D01*
X662763Y34995D01*
X663628Y34197D01*
X664690Y33682D01*
X665855Y33497D01*
X667024Y33658D01*
X668093Y34150D01*
X668970Y34925D01*
X669591Y35930D01*
X669893Y37069D01*
X669852Y38246D01*
G01X669850Y37073D02*
X669808Y38248D01*
X669414Y39377D01*
X668731Y40312D01*
X667794Y41015D01*
X666656Y41425D01*
X665455Y41473D01*
X664276Y41153D01*
X663314Y40547D01*
X662569Y39701D01*
X662080Y38649D01*
X661918Y37437D01*
X662133Y36222D01*
X662652Y35212D01*
X663457Y34375D01*
X664455Y33809D01*
X665569Y33553D01*
X666788Y33640D01*
X667894Y34077D01*
X668779Y34776D01*
X669436Y35701D01*
X669809Y36795D01*
X669852Y37942D01*
X669548Y39097D01*
X668947Y40073D01*
X668074Y40847D01*
X667056Y41325D01*
X665911Y41498D01*
X664695Y41312D01*
X663669Y40818D01*
X662827Y40051D01*
X662216Y39033D01*
X661935Y37904D01*
X661992Y36751D01*
X662397Y35620D01*
X663093Y34695D01*
X663991Y34025D01*
X665080Y33624D01*
X666288Y33559D01*
X667419Y33842D01*
X668395Y34422D01*
X669194Y35293D01*
X669685Y36305D01*
X669875Y37526D01*
X669685Y38734D01*
X669196Y39744D01*
X668428Y40588D01*
X667454Y41180D01*
X666323Y41475D01*
X665118Y41421D01*
X664012Y41025D01*
X663114Y40364D01*
X662412Y39441D01*
X662016Y38402D01*
X661927Y37241D01*
X662206Y36025D01*
X662791Y35030D01*
X663646Y34237D01*
X664716Y33718D01*
X665866Y33540D01*
X667017Y33700D01*
X668085Y34195D01*
X668935Y34949D01*
X669558Y35962D01*
X669850Y37073D01*
G01X662241Y32261D02*
Y26751D01*
G01X662569Y24561D02*
Y18393D01*
G01X663269Y24561D02*
Y18393D01*
G01X665522Y24561D02*
Y18393D01*
G01X665598Y32261D02*
Y26751D01*
G01X666222Y24561D02*
Y18393D01*
G01X666598Y30777D02*
Y26751D01*
G01X667341Y19766D02*
Y12877D01*
G01X668341Y19766D02*
Y12877D01*
G01X668474Y24561D02*
Y18393D01*
G01X669174Y24561D02*
Y18393D01*
G01X669341Y19766D02*
Y12877D01*
G01X669551Y30777D02*
Y26751D01*
G01X670551Y31038D02*
Y26751D01*
G01X670739Y43339D02*
Y39178D01*
G01X669850Y37073D02*
X669900Y37855D01*
X669758Y38627D01*
G01X673770Y34257D02*
X669157Y29645D01*
G01X664227Y40332D02*
X665040Y40802D01*
X665950Y41029D01*
X666913Y41001D01*
X667865Y40703D01*
X668719Y40152D01*
X669433Y39341D01*
G01X669551Y30777D02*
G03X668961Y31367I-590J0D01*
G01X667189D02*
G03X666598Y30777I0J-591D01*
G01X665598Y26751D02*
G03X666598I500J0D01*
G01X669551D02*
G03X670551I500J0D01*
G01X670226Y37519D02*
G03I-4330J0D01*
G01X669045D02*
G03I-3149J0D01*
G01X662831Y32851D02*
G03X662241Y32261I0J-590D01*
G01X665598D02*
G03X665008Y32851I-590J0D01*
G01X670739Y39178D02*
G03X671329Y38588I590J0D01*
G01X683490Y12019D02*
X648254D01*
G01X681325Y14955D02*
X650419D01*
G01X649254Y18242D02*
X644010D01*
G01X653711Y18393D02*
X654411D01*
G01X656664D02*
X657364D01*
G01X659616D02*
X660316D01*
G01Y21371D02*
X659616D01*
G01X657364D02*
X656664D01*
G01X654411D02*
X653711D01*
G01X660316Y24336D02*
X659616D01*
G01X657364D02*
X656664D01*
G01X654411D02*
X653711D01*
G01X660316Y24561D02*
X659616D01*
G01X657364D02*
X656664D01*
G01X654411D02*
X653711D01*
G01X644010Y26116D02*
X649254D01*
G01X656361Y38588D02*
X656080Y38547D01*
X655847Y38441D01*
X655685Y38279D01*
X655628Y38088D01*
G01X644935Y31917D02*
X644742D01*
G01X650419Y34353D02*
X681325D01*
G01Y35141D02*
X650419D01*
G01X683490Y35267D02*
X648254D01*
G01X674083Y35857D02*
X657660D01*
G01X658706Y36767D02*
X648254D01*
G01X658022Y37588D02*
X656128D01*
G01X655994Y38588D02*
X660463D01*
G01X644010Y38853D02*
X647870D01*
G01X659770Y39032D02*
X659743D01*
G01X657628Y39392D02*
X655659D01*
G01X644742Y39791D02*
X644935D01*
G01X658022Y34257D02*
X662634Y29645D01*
G01X638018Y35141D02*
Y14955D01*
G01X644010Y26116D02*
Y18242D01*
G01Y38853D02*
Y44759D01*
G01X644935Y31917D02*
Y39791D01*
G01X645742Y44759D02*
Y38853D01*
G01Y18242D02*
Y26116D01*
G01X648870Y43759D02*
Y39853D01*
G01X650254Y19242D02*
Y25116D01*
G01X650419Y35141D02*
Y14955D01*
G01X653711Y24561D02*
Y18393D01*
G01X654411Y24561D02*
Y18393D01*
G01X655628Y43930D02*
Y38088D01*
G01X655659Y44408D02*
Y36767D01*
G01X656628Y43930D02*
Y38588D01*
G01X656664Y24561D02*
Y18393D01*
G01X657364Y24561D02*
Y18393D01*
G01X657628Y44408D02*
Y36767D01*
G01X657878Y43930D02*
Y38588D01*
G01X658022Y34257D02*
Y40780D01*
G01X658904Y44408D02*
Y36569D01*
G01X659044Y44408D02*
Y37242D01*
G01X659616Y24561D02*
Y18393D01*
G01X659743Y37940D02*
Y44408D01*
G01X659770Y38069D02*
Y44408D01*
G01X660316Y24561D02*
Y18393D01*
G01X661053Y43339D02*
Y39178D01*
G01X661241Y31038D02*
Y26751D01*
G01X655628Y38088D02*
X655659Y38288D01*
X655743Y38447D01*
X655862Y38552D01*
X655994Y38588D01*
G01X658706Y36767D02*
X657840Y35267D01*
G01X658904Y36569D02*
X659770Y38069D01*
G01X658706Y36767D02*
X659770Y38069D01*
G01X657840Y35267D02*
X658904Y36569D01*
G01X662722Y41985D02*
X659770Y39032D01*
G01X659743Y37940D02*
X657660Y35857D01*
G01X649254Y18242D02*
G03X650254Y19242I0J1000D01*
G01Y25116D02*
G03X649254Y26116I-1000J0D01*
G01X661241Y26751D02*
G03X662241I500J0D01*
G01X647870Y38853D02*
G03X648870Y39853I0J1000D01*
G01X660463Y38588D02*
G03X661053Y39178I0J590D01*
G01X655628Y38088D02*
G03X656128Y37588I500J0D01*
G01X652425Y6528D02*
X657346D01*
G01X643742Y6877D02*
X644742D01*
G01Y7468D02*
X643742D01*
G01X652425Y9060D02*
X657346D01*
G01X648254Y11019D02*
X683490D01*
G01X638018Y14955D02*
X639199Y11019D01*
G01X638018Y14955D02*
X639199Y11019D01*
G01X640183D02*
Y44408D01*
G01X648254D02*
Y11019D01*
G01X650419Y14955D02*
X649238Y11019D01*
G01X650419Y14955D02*
X649238Y11019D01*
G01X662634Y45393D02*
X669157D01*
G01X665522Y48355D02*
X666222D01*
G01Y48571D02*
X665522D01*
G01X666222Y48667D02*
X665522D01*
G01X666222Y48729D02*
X665522D01*
G01X666222Y48827D02*
X665522D01*
G01X666222Y49812D02*
X665522D01*
G01X666222Y49910D02*
X665522D01*
G01X666222Y49973D02*
X665522D01*
G01X666222Y50068D02*
X665522D01*
G01Y50284D02*
X666222D01*
G01X668474Y51111D02*
X669174D01*
G01Y51327D02*
X668474D01*
G01X669174Y51423D02*
X668474D01*
G01X669174Y51485D02*
X668474D01*
G01X669174Y51583D02*
X668474D01*
G01X669174Y52568D02*
X668474D01*
G01X669174Y52666D02*
X668474D01*
G01X669174Y52729D02*
X668474D01*
G01X669174Y52823D02*
X668474D01*
G01Y53040D02*
X669174D01*
G01X663269Y53867D02*
X662569D01*
G01Y54083D02*
X663269D01*
G01X662569Y54179D02*
X663269D01*
G01X662569Y54241D02*
X663269D01*
G01Y54339D02*
X662569D01*
G01X663269Y55323D02*
X662569D01*
G01X663269Y55422D02*
X662569D01*
G01Y55484D02*
X663269D01*
G01X662569Y55579D02*
X663269D01*
G01Y55796D02*
X662569D01*
G01X665522Y63316D02*
X666222D01*
G01Y63532D02*
X665522D01*
G01X666222Y63627D02*
X665522D01*
G01X666222Y63690D02*
X665522D01*
G01X666222Y63788D02*
X665522D01*
G01X666222Y64772D02*
X665522D01*
G01X666222Y64871D02*
X665522D01*
G01X666222Y64933D02*
X665522D01*
G01X666222Y65028D02*
X665522D01*
G01Y65245D02*
X666222D01*
G01X668474Y66071D02*
X669174D01*
G01Y66288D02*
X668474D01*
G01X669174Y66383D02*
X668474D01*
G01X669174Y66445D02*
X668474D01*
G01X669174Y66544D02*
X668474D01*
G01X669174Y67528D02*
X668474D01*
G01X669174Y67627D02*
X668474D01*
G01X669174Y67689D02*
X668474D01*
G01X669174Y67784D02*
X668474D01*
G01Y68001D02*
X669174D01*
G01X663269Y68827D02*
X662569D01*
G01Y69044D02*
X663269D01*
G01X662569Y69139D02*
X663269D01*
G01X662569Y69201D02*
X663269D01*
G01Y69300D02*
X662569D01*
G01X663269Y70284D02*
X662569D01*
G01X663269Y70382D02*
X662569D01*
G01Y70445D02*
X663269D01*
G01Y70540D02*
X662569D01*
G01X663269Y70756D02*
X662569D01*
G01Y53868D02*
Y55794D01*
G01Y68829D02*
Y70755D01*
G01X663269Y53869D02*
Y55795D01*
G01Y68829D02*
Y70755D01*
G01X665522Y48356D02*
Y50282D01*
G01Y63317D02*
Y65243D01*
G01X666222Y48357D02*
Y50283D01*
G01Y63318D02*
Y65243D01*
G01X668474Y51112D02*
Y53038D01*
G01Y66073D02*
Y67999D01*
G01X669174Y51113D02*
Y53039D01*
G01Y66073D02*
Y67999D01*
G01X669022Y41985D02*
X662722D01*
G01X669157Y45393D02*
X673770Y40780D01*
G01X670793Y46512D02*
Y44408D01*
G01X671329Y43930D02*
G03X670739Y43339I0J-590D01*
G01X654225Y54572D02*
X654172Y54558D01*
G01X654238Y54492D02*
X654172Y54478D01*
G01X644742Y45223D02*
X643742D01*
G01X670793Y45528D02*
X660951D01*
G01X643742Y46475D02*
X644742D01*
G01X670793Y46512D02*
X660951D01*
G01X644742Y47182D02*
X643742D01*
G01X656664Y48355D02*
X657364D01*
G01Y48571D02*
X656664D01*
G01X657364Y48667D02*
X656664D01*
G01X657364Y48729D02*
X656664D01*
G01X657364Y48827D02*
X656664D01*
G01X657364Y49812D02*
X656664D01*
G01X657364Y49910D02*
X656664D01*
G01X657364Y49973D02*
X656664D01*
G01X657364Y50068D02*
X656664D01*
G01Y50284D02*
X657364D01*
G01X643742Y50541D02*
X644742D01*
G01X643742Y50638D02*
X644742D01*
G01X659616Y51111D02*
X660316D01*
G01X643742Y51142D02*
X644742D01*
G01X643742Y51171D02*
X644742D01*
G01X660316Y51327D02*
X659616D01*
G01X660316Y51423D02*
X659616D01*
G01X660316Y51485D02*
X659616D01*
G01X660316Y51583D02*
X659616D01*
G01X644742D02*
X643742D01*
G01X660316Y52568D02*
X659616D01*
G01X643742D02*
X644742D01*
G01X660316Y52666D02*
X659616D01*
G01X660316Y52729D02*
X659616D01*
G01X660316Y52823D02*
X659616D01*
G01X643742Y52975D02*
X644742D01*
G01X643742Y53005D02*
X644742D01*
G01X659616Y53040D02*
X660316D01*
G01X643742Y53512D02*
X644742D01*
G01Y53605D02*
X643742D01*
G01X654411Y53867D02*
X653711D01*
G01Y54083D02*
X654411D01*
G01X653711Y54179D02*
X654411D01*
G01X653711Y54241D02*
X654411D01*
G01X644742Y54260D02*
X643742D01*
G01X644742Y54275D02*
X643742D01*
G01X654411Y54339D02*
X653711D01*
G01X654566Y54478D02*
X654487D01*
G01X655012D02*
X654933D01*
G01X655275D02*
X655196D01*
G01X654172D02*
X653857D01*
G01X654172Y54558D02*
X653936D01*
G01X654881Y54639D02*
X654619D01*
G01X654868Y54693D02*
X654631D01*
G01X653936Y55028D02*
X654172D01*
G01X653857Y55108D02*
X654172D01*
G01X654697D02*
X654802D01*
G01X655196D02*
X655275D01*
G01X654411Y55323D02*
X653711D01*
G01X654411Y55422D02*
X653711D01*
G01Y55484D02*
X654411D01*
G01X653711Y55579D02*
X654411D01*
G01Y55796D02*
X653711D01*
G01X644742Y56275D02*
X640222D01*
G01X656664Y63316D02*
X657364D01*
G01Y63532D02*
X656664D01*
G01X657364Y63627D02*
X656664D01*
G01X657364Y63690D02*
X656664D01*
G01X657364Y63788D02*
X656664D01*
G01X657364Y64772D02*
X656664D01*
G01X657364Y64871D02*
X656664D01*
G01X657364Y64933D02*
X656664D01*
G01X657364Y65028D02*
X656664D01*
G01Y65245D02*
X657364D01*
G01X640222Y66043D02*
X644742D01*
G01X659616Y66071D02*
X660316D01*
G01Y66288D02*
X659616D01*
G01X660316Y66383D02*
X659616D01*
G01X660316Y66445D02*
X659616D01*
G01X660316Y66544D02*
X659616D01*
G01X660316Y67528D02*
X659616D01*
G01X660316Y67627D02*
X659616D01*
G01X660316Y67689D02*
X659616D01*
G01X660316Y67784D02*
X659616D01*
G01Y68001D02*
X660316D01*
G01X648262Y68043D02*
X643742D01*
G01X654411Y68827D02*
X653711D01*
G01Y69044D02*
X654411D01*
G01X653711Y69139D02*
X654411D01*
G01X653711Y69201D02*
X654411D01*
G01Y69300D02*
X653711D01*
G01X654411Y70284D02*
X653711D01*
G01X654411Y70382D02*
X653711D01*
G01Y70445D02*
X654411D01*
G01Y70540D02*
X653711D01*
G01X654411Y70756D02*
X653711D01*
G01X654172Y55108D02*
X654238Y55095D01*
G01X654172Y55028D02*
X654225Y55014D01*
G01X654238Y55095D02*
X654291Y55068D01*
G01X654225Y55014D02*
X654264Y54988D01*
G01X654291Y55068D02*
X654343Y55014D01*
G01X654264Y54988D02*
X654291Y54947D01*
G01X654343Y55014D02*
X654369Y54961D01*
G01X654802Y55108D02*
X655012Y54478D01*
G01X654933D02*
X654881Y54639D01*
G01X654750Y55055D02*
X654868Y54693D01*
G01X654291Y54947D02*
X654304Y54893D01*
G01X654369Y54961D02*
X654382Y54893D01*
G01X639222Y65043D02*
Y57275D01*
G01X640758Y66043D02*
Y86182D01*
G01X641095Y66043D02*
Y56275D01*
G01X642742Y66043D02*
Y56275D01*
G01X643537D02*
Y66043D01*
G01X644947Y77812D02*
Y68043D01*
G01X645742D02*
Y77812D01*
G01X647341Y68043D02*
Y77812D01*
G01X649262Y76812D02*
Y69043D01*
G01X653711Y53868D02*
Y55794D01*
G01Y68829D02*
Y70755D01*
G01X653857Y54478D02*
Y55108D01*
G01X653936Y54558D02*
Y55028D01*
G01X654304Y54893D02*
Y54693D01*
G01X654382Y54893D02*
Y54693D01*
G01X654411Y53869D02*
Y55795D01*
G01Y68829D02*
Y70755D01*
G01X655117Y54907D02*
Y55014D01*
G01X655196Y54478D02*
Y55001D01*
G01X655275Y55108D02*
Y54478D01*
G01X656664Y48356D02*
Y50282D01*
G01Y63317D02*
Y65243D01*
G01X657364Y48357D02*
Y50283D01*
G01Y63318D02*
Y65243D01*
G01X659616Y51112D02*
Y53038D01*
G01Y66073D02*
Y67999D01*
G01X660316Y51113D02*
Y53039D01*
G01Y66073D02*
Y67999D01*
G01X654382Y54693D02*
X654369Y54626D01*
G01X654304Y54693D02*
X654291Y54639D01*
G01X654631Y54693D02*
X654750Y55055D01*
G01X654619Y54639D02*
X654566Y54478D01*
G01X654487D02*
X654697Y55108D01*
G01X654369Y54626D02*
X654343Y54572D01*
G01X654291Y54639D02*
X654264Y54599D01*
G01X655117Y55014D02*
X655196Y55108D01*
G01Y55001D02*
X655117Y54907D01*
G01X654343Y54572D02*
X654291Y54518D01*
G01X654264Y54599D02*
X654225Y54572D01*
G01X654291Y54518D02*
X654238Y54492D01*
G01X639222Y57275D02*
G03X640222Y56275I1000J0D01*
G01Y66043D02*
G03X639222Y65043I0J-1000D01*
G01X648262Y68043D02*
G03X649262Y69043I0J1000D01*
G01X657628Y41062D02*
X655659D01*
G01X646679Y44408D02*
X685065D01*
G01X643742Y44516D02*
X644742D01*
G01X647870Y44759D02*
X644010D01*
G01X638717Y105171D02*
Y44408D01*
G01X640130Y105171D02*
Y44408D01*
G01X640758D02*
Y56275D01*
G01X641758Y44408D02*
Y105171D01*
G01X646679D02*
Y44408D01*
G01X647679D02*
Y68043D01*
G01X648307Y105171D02*
Y44408D01*
G01X649720Y105171D02*
Y44408D01*
G01X660951Y46512D02*
Y44408D01*
G01X662634Y45393D02*
X658022Y40780D01*
G01X648870Y43759D02*
G03X647870Y44759I-1000J0D01*
G01X661053Y43339D02*
G03X660463Y43930I-591J0D01*
G01X666222Y79733D02*
X665522D01*
G01X666222Y79831D02*
X665522D01*
G01X666222Y79894D02*
X665522D01*
G01X666222Y79989D02*
X665522D01*
G01Y80205D02*
X666222D01*
G01X668474Y81032D02*
X669174D01*
G01Y81249D02*
X668474D01*
G01X669174Y81344D02*
X668474D01*
G01X669174Y81406D02*
X668474D01*
G01X669174Y81505D02*
X668474D01*
G01X669174Y82489D02*
X668474D01*
G01X669174Y82587D02*
X668474D01*
G01X669174Y82650D02*
X668474D01*
G01X669174Y82745D02*
X668474D01*
G01Y82961D02*
X669174D01*
G01X663269Y83788D02*
X662569D01*
G01Y84005D02*
X663269D01*
G01X662569Y84100D02*
X663269D01*
G01X662569Y84162D02*
X663269D01*
G01Y84260D02*
X662569D01*
G01X663269Y85245D02*
X662569D01*
G01X663269Y85343D02*
X662569D01*
G01Y85406D02*
X663269D01*
G01Y85501D02*
X662569D01*
G01X663269Y85717D02*
X662569D01*
G01X665522Y93237D02*
X666222D01*
G01Y93453D02*
X665522D01*
G01X666222Y93549D02*
X665522D01*
G01X666222Y93611D02*
X665522D01*
G01X666222Y93709D02*
X665522D01*
G01X666222Y94693D02*
X665522D01*
G01X666222Y94792D02*
X665522D01*
G01X666222Y94855D02*
X665522D01*
G01X666222Y94949D02*
X665522D01*
G01Y95166D02*
X666222D01*
G01X668474Y95993D02*
X669174D01*
G01Y96209D02*
X668474D01*
G01X669174Y96305D02*
X668474D01*
G01X669174Y96367D02*
X668474D01*
G01X669174Y96465D02*
X668474D01*
G01X669174Y97449D02*
X668474D01*
G01X669174Y97548D02*
X668474D01*
G01X669174Y97610D02*
X668474D01*
G01X669174Y97705D02*
X668474D01*
G01Y97922D02*
X669174D01*
G01X663269Y98749D02*
X662569D01*
G01Y98965D02*
X663269D01*
G01X662569Y99060D02*
X663269D01*
G01X662569Y99123D02*
X663269D01*
G01Y99221D02*
X662569D01*
G01X663269Y100205D02*
X662569D01*
G01X663269Y100304D02*
X662569D01*
G01Y100366D02*
X663269D01*
G01Y100461D02*
X662569D01*
G01X663269Y100678D02*
X662569D01*
G01X661404Y105958D02*
Y106958D01*
G01X661500Y105958D02*
Y106958D01*
G01X662152Y105958D02*
Y106958D01*
G01X662569Y83790D02*
Y85716D01*
G01Y98750D02*
Y100676D01*
G01X662919Y105958D02*
Y106958D01*
G01Y102336D02*
Y105171D01*
G01X663269Y83790D02*
Y85716D01*
G01Y98751D02*
Y100677D01*
G01X663652Y105958D02*
Y106958D01*
G01X664297Y102336D02*
Y105171D01*
G01X665522Y93238D02*
Y95164D01*
G01X666222Y93239D02*
Y95165D01*
G01X668474Y81034D02*
Y82960D01*
G01Y95994D02*
Y97920D01*
G01X668825Y105958D02*
Y106958D01*
G01X669174Y81034D02*
Y82960D01*
G01Y95995D02*
Y97921D01*
G01X665522Y78276D02*
X666222D01*
G01Y78493D02*
X665522D01*
G01X666222Y78588D02*
X665522D01*
G01X666222Y78650D02*
X665522D01*
G01X666222Y78749D02*
X665522D01*
G01Y78278D02*
Y80204D01*
G01X666222Y78278D02*
Y80204D01*
G01X657364Y79733D02*
X656664D01*
G01X657364Y79831D02*
X656664D01*
G01X657364Y79894D02*
X656664D01*
G01X657364Y79989D02*
X656664D01*
G01Y80205D02*
X657364D01*
G01X659616Y81032D02*
X660316D01*
G01Y81249D02*
X659616D01*
G01X660316Y81344D02*
X659616D01*
G01X660316Y81406D02*
X659616D01*
G01X660316Y81505D02*
X659616D01*
G01X660316Y82489D02*
X659616D01*
G01X660316Y82587D02*
X659616D01*
G01X660316Y82650D02*
X659616D01*
G01X660316Y82745D02*
X659616D01*
G01Y82961D02*
X660316D01*
G01X654411Y83788D02*
X653711D01*
G01Y84005D02*
X654411D01*
G01X653711Y84100D02*
X654411D01*
G01X653711Y84162D02*
X654411D01*
G01Y84260D02*
X653711D01*
G01X643742Y85182D02*
X644742D01*
G01X654411Y85245D02*
X653711D01*
G01X654411Y85343D02*
X653711D01*
G01Y85406D02*
X654411D01*
G01Y85501D02*
X653711D01*
G01X654411Y85717D02*
X653711D01*
G01X644742Y86182D02*
X640222D01*
G01X644010Y91636D02*
X647870D01*
G01X656664Y93237D02*
X657364D01*
G01Y93453D02*
X656664D01*
G01X657364Y93549D02*
X656664D01*
G01X657364Y93611D02*
X656664D01*
G01X657364Y93709D02*
X656664D01*
G01X640222Y94578D02*
X644742D01*
G01X657364Y94693D02*
X656664D01*
G01X657364Y94792D02*
X656664D01*
G01X657364Y94855D02*
X656664D01*
G01X657364Y94949D02*
X656664D01*
G01Y95166D02*
X657364D01*
G01X659616Y95993D02*
X660316D01*
G01Y96209D02*
X659616D01*
G01X660316Y96305D02*
X659616D01*
G01X660316Y96367D02*
X659616D01*
G01X660316Y96465D02*
X659616D01*
G01X648262Y96578D02*
X643742D01*
G01X660316Y97449D02*
X659616D01*
G01X647870Y97542D02*
X644010D01*
G01X660316Y97548D02*
X659616D01*
G01X660316Y97610D02*
X659616D01*
G01X660316Y97705D02*
X659616D01*
G01Y97922D02*
X660316D01*
G01X654411Y98749D02*
X653711D01*
G01Y98965D02*
X654411D01*
G01X653711Y99060D02*
X654411D01*
G01X653711Y99123D02*
X654411D01*
G01Y99221D02*
X653711D01*
G01X654411Y100205D02*
X653711D01*
G01X654411Y100304D02*
X653711D01*
G01Y100366D02*
X654411D01*
G01Y100461D02*
X653711D01*
G01X654411Y100678D02*
X653711D01*
G01X652486Y102336D02*
X679258D01*
G01X643742Y103048D02*
X644742D01*
G01Y103974D02*
X643742D01*
G01X644742Y104974D02*
X643742D01*
G01X643923Y105169D02*
X644514D01*
G01X638061Y105958D02*
Y106958D01*
G01X639222Y93578D02*
Y87182D01*
G01X640758Y94578D02*
Y105171D01*
G01X641095Y94578D02*
Y86182D01*
G01X642742Y94578D02*
Y86182D01*
G01X643537D02*
Y94578D01*
G01X644010Y91636D02*
Y97542D01*
G01X644947Y105171D02*
Y96578D01*
G01X645742Y91636D02*
Y105171D01*
G01X647341Y96578D02*
Y105171D01*
G01X648663Y107942D02*
Y106958D01*
G01X648870Y92636D02*
Y96542D01*
G01X649262Y104171D02*
Y97578D01*
G01X649663Y107942D02*
Y106958D01*
G01X652266Y105958D02*
Y106958D01*
G01X652486Y105171D02*
Y102336D01*
G01X653266Y106958D02*
Y105958D01*
G01X653711Y83790D02*
Y85716D01*
G01Y98750D02*
Y100676D01*
G01X654411Y83790D02*
Y85716D01*
G01Y98751D02*
Y100677D01*
G01X655262Y106958D02*
Y105958D01*
G01X655266Y105171D02*
Y106958D01*
G01X656282D02*
Y105958D01*
G01X656664Y93238D02*
Y95164D01*
G01X657364Y93239D02*
Y95165D01*
G01X657625Y105958D02*
Y106958D01*
G01X658437D02*
Y105958D01*
G01X658530D02*
Y106958D01*
G01X659015Y105958D02*
Y106958D01*
G01X659067Y105958D02*
Y106958D01*
G01X659474Y105958D02*
Y106958D01*
G01X659616Y81034D02*
Y82960D01*
G01Y95994D02*
Y97920D01*
G01X660316Y81034D02*
Y82960D01*
G01Y95995D02*
Y97921D01*
G01X660459Y106958D02*
Y105958D01*
G01X660870D02*
Y106958D01*
G01X660922Y105958D02*
Y106958D01*
G01X648262Y96578D02*
G03X649262Y97578I0J1000D01*
G01Y104171D02*
G03X648262Y105171I-1000J0D01*
G01X648870Y96542D02*
G03X647870Y97542I-1000J0D01*
G01Y91636D02*
G03X648870Y92636I0J1000D01*
G01X639222Y87182D02*
G03X640222Y86182I1000J0D01*
G01Y94578D02*
G03X639222Y93578I0J-1000D01*
G01X645742Y107942D02*
G03X644019Y106958I0J-2000D01*
G01X643742Y77812D02*
X648262D01*
G01X656664Y78276D02*
X657364D01*
G01Y78493D02*
X656664D01*
G01X657364Y78588D02*
X656664D01*
G01X657364Y78650D02*
X656664D01*
G01X657364Y78749D02*
X656664D01*
G01X644742Y78812D02*
X643742D01*
G01X644742Y77580D02*
X646679Y75643D01*
G01X647679Y77812D02*
Y96578D01*
G01X656664Y78278D02*
Y80204D01*
G01X657364Y78278D02*
Y80204D01*
G01X643742Y77628D02*
X641758Y75643D01*
G01X649262Y76812D02*
G03X648262Y77812I-1000J0D01*
G01X670994Y137794D02*
X668533D01*
G01X663120Y149856D02*
Y137794D01*
G01X668533D02*
Y149856D01*
G01X663120Y137794D02*
X660659D01*
G01X655246D02*
X652785D01*
G01X638514D02*
X641467D01*
G01X639006Y140307D02*
X640974D01*
G01D02*
X642943Y140810D01*
G01X641467Y137794D02*
X643927Y138297D01*
G01X652785Y137794D02*
Y153877D01*
G01X655246Y150359D02*
Y137794D01*
G01X660659D02*
Y149856D01*
G01X647864Y141312D02*
X648848Y143825D01*
G01X646388Y139805D02*
X647864Y141312D01*
G01X643927Y138297D02*
X646388Y139805D01*
G01X642943Y140810D02*
X644911Y141815D01*
G01X649663Y107942D02*
X645742D01*
G01X666565Y151867D02*
X665089D01*
G01X665581Y153877D02*
X667549D01*
G01D02*
X669026Y153375D01*
G01X667549Y151364D02*
X666565Y151867D01*
G01X668041Y150862D02*
X667549Y151364D01*
G01X669026Y153375D02*
X670010Y152369D01*
G01X668533Y149856D02*
X668041Y150862D01*
G01X670010Y152369D02*
X670994Y149856D01*
G01X663612Y150862D02*
X663120Y149856D01*
G01X662628Y151867D02*
X664104Y153375D01*
G01Y151364D02*
X663612Y150862D01*
G01X665089Y151867D02*
X664104Y151364D01*
G01Y153375D02*
X665581Y153877D01*
G01X642943Y148349D02*
X640974Y148851D01*
G01Y150862D02*
X642943Y151364D01*
G01X640974Y148851D02*
X639006D01*
G01Y150862D02*
X640974D01*
G01X658691Y151867D02*
X657707D01*
G01X652785Y153877D02*
X655246D01*
G01X657707D02*
X659675D01*
G01X640974Y158903D02*
X639006D01*
G01X640974Y161416D02*
X639006D01*
G01X643435Y160914D02*
X640974Y161416D01*
G01X642943Y158401D02*
X640974Y158903D01*
G01X659675Y153877D02*
X661152Y153375D01*
G01X644911Y147343D02*
X642943Y148349D01*
G01X645896Y149354D02*
X644911Y149856D01*
G01X659675Y151364D02*
X658691Y151867D01*
G01X645896Y159406D02*
X643435Y160914D01*
G01X647864Y147846D02*
X645896Y149354D01*
G01X644911Y156893D02*
X642943Y158401D01*
G01X647372Y157898D02*
X645896Y159406D01*
G01X660167Y150862D02*
X659675Y151364D01*
G01X661152Y153375D02*
X662628Y151867D01*
G01X645896Y155385D02*
X644911Y156893D01*
G01X660659Y149856D02*
X660167Y150862D01*
G01X648356Y155385D02*
X647372Y157898D01*
G01X645896Y154380D02*
Y155385D01*
G01X648356Y153877D02*
Y155385D01*
G01X655246Y153877D02*
Y152369D01*
G01X647372Y151867D02*
X648356Y153877D01*
G01X644911Y152872D02*
X645896Y154380D01*
G01Y150359D02*
X647372Y151867D01*
G01X655246Y152369D02*
X656230Y153375D01*
G01Y151364D02*
X655246Y150359D01*
G01X642943Y151364D02*
X644911Y152872D01*
G01Y149856D02*
X645896Y150359D01*
G01X656230Y153375D02*
X657707Y153877D01*
G01Y151867D02*
X656230Y151364D01*
G01X646388Y145333D02*
X644911Y147343D01*
G01X648848Y145333D02*
X647864Y147846D01*
G01X646388Y143825D02*
Y145333D01*
G01X648848Y143825D02*
Y145333D01*
G01X644911Y141815D02*
X646388Y143825D01*
G01X663114Y238385D02*
X662626D01*
Y239106D01*
X663114Y238385D01*
G01X670909D02*
X669935Y239106D01*
X669447Y239828D01*
X668960Y241272D01*
Y244159D01*
X669447Y245603D01*
X669935Y246324D01*
X670909Y247046D01*
X671883Y246324D01*
X672371Y245603D01*
X672858Y244159D01*
Y241272D01*
X672371Y239828D01*
X671883Y239106D01*
X670909Y238385D01*
G01X655319D02*
X654344Y239106D01*
X653857Y239828D01*
X653370Y241272D01*
Y244159D01*
X653857Y245603D01*
X654344Y246324D01*
X655319Y247046D01*
X656293Y246324D01*
X656780Y245603D01*
X657267Y244159D01*
Y241272D01*
X656780Y239828D01*
X656293Y239106D01*
X655319Y238385D01*
G01X645574Y241272D02*
X646061Y242716D01*
X647523Y243437D01*
X648985Y242716D01*
X649472Y241272D01*
X648985Y239828D01*
X648498Y239106D01*
X647523Y238385D01*
X646549Y239106D01*
X646061Y239828D01*
X645574Y241272D01*
Y244159D01*
X646061Y245603D01*
X646549Y246324D01*
X647523Y247046D01*
X648498Y246324D01*
X648985Y245603D01*
G01X663114Y285629D02*
X662626D01*
Y286351D01*
X663114Y285629D01*
G01X670909D02*
X669935Y286351D01*
X669447Y287072D01*
X668960Y288516D01*
Y291403D01*
X669447Y292847D01*
X669935Y293568D01*
X670909Y294290D01*
X671883Y293568D01*
X672371Y292847D01*
X672858Y291403D01*
Y288516D01*
X672371Y287072D01*
X671883Y286351D01*
X670909Y285629D01*
G01X647523D02*
X648010Y289238D01*
X648498Y291403D01*
G01D02*
X649472Y294290D01*
X645574D01*
G01X653370Y292847D02*
X653857Y293568D01*
X654831Y294290D01*
X655806D01*
X656780Y293568D01*
X657267Y292847D01*
Y291403D01*
X656780Y290681D01*
X654831Y289238D01*
G01D02*
X653857Y287794D01*
X653370Y285629D01*
X657267D01*
G01X646006Y474684D02*
Y493112D01*
G01X650927Y514054D02*
Y474684D01*
G01D02*
X646006D01*
G01X674713Y500651D02*
X663230Y494788D01*
G01D02*
X674713Y488924D01*
G01X646006Y498138D02*
Y514054D01*
G01X657489Y494788D02*
X673072Y503164D01*
G01Y486411D02*
X657489Y494788D01*
G01X646006Y514054D02*
X650927D01*
G01X669695Y871445D02*
X669203Y871193D01*
G01X665266Y872199D02*
X666004Y872450D01*
G01Y871445D02*
X665266Y871193D01*
G01X669203Y872199D02*
X669941Y872450D01*
G01X664774Y871696D02*
X665266Y872199D01*
G01Y871193D02*
X664774Y870691D01*
G01X668465Y871445D02*
X669203Y872199D01*
G01Y871193D02*
X668957Y870942D01*
G01D02*
X668711Y870440D01*
G01X661329Y867927D02*
X661575Y869183D01*
G01D02*
Y871445D01*
G01X662894Y892519D02*
Y883464D01*
G01X663543Y864408D02*
Y872450D01*
G01X663878Y883464D02*
Y892519D01*
G01X664774Y872450D02*
Y871696D01*
G01Y870691D02*
Y864408D01*
G01X666043Y892519D02*
Y883464D01*
G01X667028D02*
Y892519D01*
G01X667480Y864408D02*
Y870440D01*
G01X668711D02*
Y864408D01*
G01X669193Y892519D02*
Y883464D01*
G01X670177D02*
Y892519D01*
G01X661575Y871445D02*
X661329Y872701D01*
G01X667480Y870440D02*
X667234Y870942D01*
G01D02*
X666988Y871193D01*
G01X667726Y872199D02*
X668465Y871445D01*
G01X666988Y872450D02*
X667726Y872199D01*
G01X666988Y871193D02*
X666496Y871445D01*
G01X670925Y871193D02*
X670433Y871445D01*
G01X664774Y864408D02*
X663543D01*
G01X668711D02*
X667480D01*
G01X670433Y871445D02*
X669695D01*
G01X666496D02*
X666004D01*
G01X663543Y872450D02*
X664774D01*
G01X666004D02*
X666988D01*
G01X669941D02*
X670925D01*
G01X672343Y883464D02*
X670177D01*
G01X669193D02*
X667028D01*
G01X666043D02*
X663878D01*
G01X655669Y875968D02*
X654439Y875214D01*
G01D02*
X653701Y874460D01*
G01X655915Y874712D02*
X655177Y874209D01*
G01X658376Y865916D02*
X659114Y866419D01*
G01X658622Y864660D02*
X659852Y865414D01*
G01D02*
X660591Y866168D01*
G01X653701Y874460D02*
X653209Y873455D01*
G01X660591Y866168D02*
X661083Y867173D01*
G01X655177Y874209D02*
X654193Y872701D01*
G01X659114Y866419D02*
X660098Y867927D01*
G01X653209Y873455D02*
X652963Y872701D01*
G01X661083Y867173D02*
X661329Y867927D01*
G01X654193Y872701D02*
X653947Y871193D01*
G01X652963Y872701D02*
X652717Y871445D01*
G01X637697Y892519D02*
Y883464D01*
G01X638681D02*
Y892519D01*
G01X640846D02*
Y883464D01*
G01X641831D02*
Y892519D01*
G01X643366Y864408D02*
Y869937D01*
G01Y871445D02*
Y876219D01*
G01X643996Y892519D02*
Y883464D01*
G01X644843Y876219D02*
Y864408D01*
G01X644980Y883464D02*
Y892519D01*
G01X646811Y868429D02*
Y869434D01*
G01Y871445D02*
Y872450D01*
G01X647146Y892519D02*
Y883464D01*
G01X660098Y867927D02*
X660344Y869434D01*
G01X648130Y883464D02*
Y892519D01*
G01X650295D02*
Y883464D01*
G01X650748Y872450D02*
Y871445D01*
G01Y869434D02*
Y868429D01*
G01X651280Y883464D02*
Y892519D01*
G01X652717Y871445D02*
Y869183D01*
G01X653445Y892519D02*
Y883464D01*
G01X653947Y871193D02*
Y869434D01*
G01X654429Y883464D02*
Y892519D01*
G01X656594D02*
Y883464D01*
G01X657579D02*
Y892519D01*
G01X659744D02*
Y883464D01*
G01X660344Y869434D02*
Y871193D01*
G01X660728Y883464D02*
Y892519D01*
G01X652717Y869183D02*
X652963Y867927D01*
G01X653947Y869434D02*
X654193Y867927D01*
G01X660344Y871193D02*
X660098Y872701D01*
G01X652963Y867927D02*
X653209Y867173D01*
G01X661329Y872701D02*
X661083Y873455D01*
G01X653209Y867173D02*
X653701Y866168D01*
G01X661083Y873455D02*
X660591Y874460D01*
G01X654193Y867927D02*
X655177Y866419D01*
G01X660098Y872701D02*
X659114Y874209D01*
G01X653701Y866168D02*
X654439Y865414D01*
G01X660591Y874460D02*
X659852Y875214D01*
G01X654439Y865414D02*
X655669Y864660D01*
G01X655177Y866419D02*
X655915Y865916D01*
G01X659114Y874209D02*
X658376Y874712D01*
G01X659852Y875214D02*
X658622Y875968D01*
G01X657146Y865665D02*
X658376Y865916D01*
G01X657146Y874963D02*
X655915Y874712D01*
G01X657146Y864408D02*
X658622Y864660D01*
G01X657146Y876219D02*
X655669Y875968D01*
G01X644843Y864408D02*
X643366D01*
G01X650748Y868429D02*
X646811D01*
G01Y869434D02*
X650748D01*
G01Y871445D02*
X646811D01*
G01Y872450D02*
X650748D01*
G01X643366Y876219D02*
X644843D01*
G01X662894Y883464D02*
X660728D01*
G01X659744D02*
X657579D01*
G01X656594D02*
X654429D01*
G01X653445D02*
X651280D01*
G01X650295D02*
X648130D01*
G01X647146D02*
X644980D01*
G01X643996D02*
X641831D01*
G01X640846D02*
X638681D01*
G01X655669Y864660D02*
X657146Y864408D01*
G01X658622Y875968D02*
X657146Y876219D01*
G01X655915Y865916D02*
X657146Y865665D01*
G01X658376Y874712D02*
X657146Y874963D01*
G01X667028Y892519D02*
X669193D01*
G01X663878D02*
X666043D01*
G01X670177D02*
X672343D01*
G01X638681D02*
X640846D01*
G01X641831D02*
X643996D01*
G01X648130D02*
X650295D01*
G01X644980D02*
X647146D01*
G01X651280D02*
X653445D01*
G01X657579D02*
X659744D01*
G01X654429D02*
X656594D01*
G01X660728D02*
X662894D01*
G01X668103Y948039D02*
Y939377D01*
G01X642841Y948039D02*
Y939377D01*
G01X652513D02*
X651538Y940099D01*
X651051Y940821D01*
X650564Y942265D01*
Y945152D01*
X651051Y946595D01*
X651538Y947317D01*
X652513Y948039D01*
X653487Y947317D01*
X653974Y946595D01*
X654461Y945152D01*
Y942265D01*
X653974Y940821D01*
X653487Y940099D01*
X652513Y939377D01*
G01X660308D02*
X659820D01*
Y940099D01*
X660308Y939377D01*
G01X638510D02*
X647171D01*
G01X638510Y943708D02*
X647171D01*
G01X696698Y-271866D02*
Y-277640D01*
G01Y-273310D02*
X697672Y-271866D01*
X698646D01*
X699621Y-273310D01*
Y-277640D01*
G01Y-273310D02*
X700595Y-271866D01*
X701570D01*
X702544Y-273310D01*
Y-277640D01*
G01X682569Y-276919D02*
X681594Y-275475D01*
X681107Y-273310D01*
X681594Y-271144D01*
G01D02*
X682569Y-269701D01*
X683543Y-268979D01*
X684518D01*
X685492Y-269701D01*
X685979Y-270423D01*
G01Y-276197D02*
X685492Y-276919D01*
X684518Y-277640D01*
X683543D01*
X682569Y-276919D01*
G01X693774Y-275475D02*
X692800Y-276919D01*
X691826Y-277640D01*
X690851Y-276919D01*
X689877Y-275475D01*
Y-274031D01*
X690851Y-272588D01*
X691826Y-271866D01*
X692800Y-272588D01*
X693774Y-274031D01*
Y-275475D01*
G01X686959Y-42635D02*
X687010Y-42626D01*
X687040Y-42596D01*
X687049Y-42545D01*
G01X688246Y-40442D02*
X688049Y-40444D01*
G01X687025Y-41640D02*
X688049Y-41635D01*
G01X684484Y-31255D02*
X676316Y-31261D01*
G01X688049Y-42635D02*
X672810D01*
G01X688049Y-42342D02*
X687049D01*
G01X687749Y-42135D02*
X687649D01*
G01X688049Y-41928D02*
X687049D01*
G01X687042Y-41635D02*
X688049D01*
G01X688443Y-41435D02*
X673411D01*
G01X688443Y-40845D02*
X688049D01*
G01X687049Y-40746D02*
X686986D01*
G01X688443Y-40679D02*
X688049D01*
G01Y-40670D02*
X688443D01*
G01X687049Y-40535D02*
X686949D01*
G01X688443Y-40442D02*
X688246D01*
G01X688049Y-40057D02*
X688443D01*
G01X687049Y-39762D02*
X686986D01*
G01X686949Y-39535D02*
X687049D01*
G01X684144Y-39469D02*
X680309D01*
G01X683947Y-39154D02*
X679719D01*
G01X688049Y-38336D02*
X684512D01*
G01X688049Y-34399D02*
X684512D01*
G01X684484Y-33775D02*
X676301D01*
G01X684144Y-33249D02*
X680309D01*
G01X684484Y-33102D02*
X676315D01*
G01Y-32967D02*
X684484D01*
G01X688443Y-32016D02*
X684681D01*
G01X688443Y-31425D02*
X688049D01*
G01X688443Y-31261D02*
X688049D01*
G01X676315Y-30829D02*
X684484D01*
G01Y-30744D02*
X676315D01*
G01X686049Y-29423D02*
X688049D01*
G01X687049Y-28769D02*
X688049D01*
G01Y-27769D02*
X687049D01*
G01X686049Y-27423D02*
X687049D01*
G01X671689Y-41928D02*
X672103Y-42342D01*
G01X674829Y-33775D02*
X674823Y-33744D01*
X674819Y-33713D01*
X674816Y-33682D01*
G01Y-33663D02*
X674819Y-33701D01*
X674823Y-33738D01*
X674829Y-33775D01*
G01X674816Y-33682D02*
X674815Y-33647D01*
G01Y-33621D02*
X674816Y-33663D01*
G01X670896Y-41835D02*
Y-40398D01*
G01X671211Y-32749D02*
Y-34319D01*
G01X674816Y-33663D02*
Y-33682D01*
G01X674815Y-17548D02*
Y-33647D01*
G01X676315D02*
Y-17548D01*
G01X676314Y-33663D02*
Y-33682D01*
G01X679719Y-39154D02*
Y-33339D01*
G01X683512Y-35399D02*
Y-37336D01*
G01X684484Y-17548D02*
Y-33866D01*
G01X684537Y-33339D02*
Y-38564D01*
G01X684681Y-32016D02*
Y-33866D01*
G01X684734Y-33839D02*
Y-38879D01*
G01X686049Y-32749D02*
Y-42635D01*
G01Y-32016D02*
Y106958D01*
G01X686081Y-41435D02*
Y-32016D01*
G01X686949Y-39535D02*
Y-41435D01*
G01X686986Y-41402D02*
Y-39762D01*
G01X687049Y-42635D02*
Y-32749D01*
G01Y-29423D02*
Y106958D01*
G01X688049Y-38336D02*
Y-36368D01*
G01Y-42635D02*
Y106958D01*
G01Y-36368D02*
Y-34399D01*
G01X688443Y-31255D02*
Y-41435D01*
G01Y-40442D02*
X688441Y-40670D01*
G01X676314Y-33663D02*
X676315Y-33621D01*
G01Y-33647D02*
X676314Y-33682D01*
G01X688441Y-40670D02*
X688431Y-40975D01*
X688394Y-41222D01*
X688311Y-41381D01*
X688170Y-41435D01*
G01X676314Y-33682D02*
X676311Y-33713D01*
X676307Y-33744D01*
X676301Y-33775D01*
G01D02*
X676307Y-33738D01*
X676311Y-33701D01*
X676314Y-33663D01*
G01X689673Y-23671D02*
X688106Y-30744D01*
G01X690058Y-23756D02*
X688490Y-30829D01*
G01X688006Y-42635D02*
X688031Y-42625D01*
X688045Y-42595D01*
X688049Y-42545D01*
G01X671689Y-41928D02*
G03X670981Y-41635I-707J-707D01*
G01X672103Y-42342D02*
G03X672810Y-42635I707J707D01*
G01X672451Y-40670D02*
G03X670896Y-40845I-768J-175D01*
G01X683512Y-37336D02*
G03X684512Y-38336I1000J0D01*
G01X672451Y-40670D02*
G03X673411Y-41435I960J219D01*
G01X686986Y-41402D02*
G03X688443I729J0D01*
G01X686949Y-41435D02*
G03X687649Y-42135I700J0D01*
G01X687749D02*
G03X688051Y-42067I1J700D01*
G01X683947Y-39154D02*
G03X684537Y-38564I0J590D01*
G01X684144Y-39469D02*
G03X684734Y-38879I0J590D01*
G01X679719D02*
G03X680309Y-39469I590J0D01*
G01X674829Y-33775D02*
G03X675565Y-34378I734J145D01*
G01D02*
G03X676301Y-33775I2J748D01*
G01X680309Y-32749D02*
G03X679719Y-33339I0J-590D01*
G01X680309Y-33249D02*
G03X679719Y-33839I0J-590D01*
G01X675565Y-32016D02*
G03X676315Y-31261I2J748D01*
G01X674815D02*
G03X675565Y-32016I748J-7D01*
G01X684512Y-34399D02*
G03X683512Y-35399I0J-1000D01*
G01X684537Y-33339D02*
G03X683947Y-32749I-590J0D01*
G01X684734Y-33839D02*
G03X684144Y-33249I-590J0D01*
G01X684537Y-33839D02*
G03X683947Y-33249I-590J0D01*
G01X684484Y-33866D02*
G03X684681I98J0D01*
G01X688106Y-30744D02*
G03X688049Y-31261I2305J-516D01*
G01X688490Y-30829D02*
G03X688443Y-31261I1921J-428D01*
G01X686049Y-27423D02*
G03Y-29423I0J-1000D01*
G01X684484Y-31425D02*
G03X685075Y-32016I591J0D01*
G01X677102Y-16798D02*
X676950Y-16813D01*
X676802Y-16857D01*
X676667Y-16929D01*
X676546Y-17028D01*
X676448Y-17146D01*
X676376Y-17281D01*
X676331Y-17427D01*
X676315Y-17582D01*
G01X677102Y-16904D02*
X676950Y-16917D01*
X676802Y-16954D01*
X676667Y-17015D01*
X676546Y-17099D01*
X676448Y-17199D01*
X676376Y-17313D01*
X676331Y-17437D01*
X676315Y-17568D01*
G01X687049Y1845D02*
X687391Y1853D01*
X687645Y1897D01*
X687815Y2018D01*
X687893Y2231D01*
X687914Y2505D01*
X687915Y2845D01*
G01X686957Y-4525D02*
X687332Y-4520D01*
X687608Y-4485D01*
X687799Y-4371D01*
X687890Y-4158D01*
X687913Y-3876D01*
X687915Y-3525D01*
G01X684112Y-21261D02*
X688049D01*
G01X684484Y-18862D02*
X676315D01*
G01Y-18845D02*
X684484D01*
G01Y-18516D02*
X676315D01*
G01Y-18481D02*
X684484D01*
G01Y-18138D02*
X676315D01*
G01Y-18104D02*
X684484D01*
G01X676315Y-17890D02*
X684484D01*
G01Y-17679D02*
X676315D01*
G01X679367Y-17318D02*
X674445D01*
G01X677102Y-17116D02*
X683697D01*
G01Y-16904D02*
X677102D01*
G01Y-16798D02*
X683697D01*
G01Y-16764D02*
X677102D01*
G01X679367Y-14786D02*
X674445D01*
G01Y-14307D02*
X679367D01*
G01X684112Y-13551D02*
X688049D01*
G01X686049Y-12551D02*
X689309D01*
G01X687915Y-11551D02*
X687049D01*
G01X688049Y-11383D02*
X689309D01*
G01X687915Y-10551D02*
X687049D01*
G01X679367Y-9699D02*
X674445D01*
G01X687049Y-9460D02*
X687915D01*
G01X674445Y-9220D02*
X679367D01*
G01X687781Y-8460D02*
X682537D01*
G01X674445Y-6688D02*
X679367D01*
G01X682537Y-4525D02*
X687781D01*
G01X688049Y-2525D02*
X687049D01*
G01X689309Y-2040D02*
X688049D01*
G01X687049Y-1874D02*
X688049D01*
G01X687049Y-1777D02*
X688049D01*
G01X679367Y-1570D02*
X674445D01*
G01X687049Y-1273D02*
X688049D01*
G01X687049Y-1244D02*
X688049D01*
G01Y-1208D02*
X689309D01*
G01X688049Y-832D02*
X687049D01*
G01Y153D02*
X688049D01*
G01X687049Y560D02*
X688049D01*
G01X687049Y590D02*
X688049D01*
G01X679367Y962D02*
X674445D01*
G01X687049Y1097D02*
X688049D01*
G01Y1190D02*
X687049D01*
G01X674445Y1441D02*
X679367D01*
G01X688049Y1845D02*
X687049D01*
G01X687915Y2845D02*
X687049D01*
G01X688049Y3845D02*
X687049D01*
G01X688049Y4436D02*
X687049D01*
G01X679367Y6049D02*
X674445D01*
G01X687050Y-8460D02*
X687380Y-8467D01*
X687632Y-8507D01*
X687806Y-8621D01*
X687891Y-8831D01*
X687913Y-9108D01*
X687915Y-9460D01*
G01X674028Y-17116D02*
X674181Y-17128D01*
X674328Y-17166D01*
X674463Y-17227D01*
X674585Y-17310D01*
X674682Y-17410D01*
X674755Y-17525D01*
X674800Y-17649D01*
X674815Y-17780D01*
G01X683697Y-17116D02*
X683850Y-17128D01*
X683997Y-17166D01*
X684133Y-17227D01*
X684254Y-17310D01*
X684351Y-17410D01*
X684424Y-17525D01*
X684469Y-17649D01*
X684484Y-17780D01*
G01X674028Y-16764D02*
X674181Y-16779D01*
X674328Y-16823D01*
X674463Y-16895D01*
X674585Y-16994D01*
X674682Y-17112D01*
X674755Y-17247D01*
X674800Y-17393D01*
X674815Y-17548D01*
G01X683697Y-16764D02*
X683850Y-16779D01*
X683997Y-16823D01*
X684133Y-16895D01*
X684254Y-16994D01*
X684351Y-17112D01*
X684424Y-17247D01*
X684469Y-17393D01*
X684484Y-17548D01*
G01X686969Y-8460D02*
X687015Y-8469D01*
X687041Y-8495D01*
X687049Y-8541D01*
G01X690352Y-17568D02*
X690684Y-17780D01*
G01X690775Y-16904D02*
X691107Y-17116D01*
G01X674815Y-17582D02*
X674800Y-17430D01*
X674756Y-17284D01*
X674683Y-17149D01*
X674585Y-17028D01*
X674466Y-16931D01*
X674330Y-16858D01*
X674183Y-16814D01*
X674028Y-16798D01*
G01X684484Y-17582D02*
X684469Y-17430D01*
X684425Y-17284D01*
X684353Y-17149D01*
X684254Y-17028D01*
X684135Y-16931D01*
X684000Y-16858D01*
X683853Y-16814D01*
X683697Y-16798D01*
G01X674815Y-17568D02*
X674800Y-17439D01*
X674756Y-17315D01*
X674683Y-17201D01*
X674585Y-17099D01*
X674466Y-17016D01*
X674330Y-16955D01*
X674183Y-16917D01*
X674028Y-16904D01*
G01X684484Y-17568D02*
X684469Y-17439D01*
X684425Y-17315D01*
X684353Y-17201D01*
X684254Y-17099D01*
X684135Y-17016D01*
X684000Y-16955D01*
X683853Y-16917D01*
X683697Y-16904D01*
G01X687915Y-3525D02*
X687913Y-3173D01*
X687890Y-2895D01*
X687805Y-2685D01*
X687630Y-2571D01*
X687378Y-2531D01*
X687049Y-2525D01*
G01X686957Y-4525D02*
X686960Y-5836D01*
X686966Y-7148D01*
X686969Y-8460D01*
G01X686958Y-4525D02*
X686915Y18242D01*
G01X674028Y-16764D02*
Y-16798D01*
G01Y-17116D02*
Y-16904D01*
G01X674445Y9060D02*
Y-1570D01*
G01Y-6688D02*
Y-17318D01*
G01X677102Y-16904D02*
Y-17116D01*
G01Y-16798D02*
Y-16764D01*
G01X679367Y-17318D02*
Y-6688D01*
G01Y-1570D02*
Y9060D01*
G01X681537Y-5525D02*
Y-7460D01*
G01X683112Y-20261D02*
Y-14551D01*
G01X683697Y-16764D02*
Y-16798D01*
G01Y-17116D02*
Y-16904D01*
G01X687781Y-8460D02*
Y-4525D01*
G01X687915Y3845D02*
Y2845D01*
G01Y-9460D02*
Y-12551D01*
G01X689309D02*
Y35593D01*
G01X686915Y-12551D02*
X686957Y-4525D01*
G01X676315Y-17548D02*
X676330Y-17396D01*
X676374Y-17249D01*
X676447Y-17114D01*
X676546Y-16994D01*
X676665Y-16896D01*
X676800Y-16824D01*
X676947Y-16779D01*
X677102Y-16764D01*
G01X676315Y-17780D02*
X676330Y-17651D01*
X676374Y-17527D01*
X676447Y-17412D01*
X676546Y-17310D01*
X676665Y-17228D01*
X676800Y-17167D01*
X676947Y-17129D01*
X677102Y-17116D01*
G01X687049Y-4444D02*
X687041Y-4490D01*
X687013Y-4516D01*
X686957Y-4525D01*
G01X690775Y-16904D02*
X690282Y-17679D01*
G01X691107Y-17116D02*
X690614Y-17890D01*
G01X687049Y-15551D02*
G03X686049Y-14551I-1000J0D01*
G01X683112Y-20261D02*
G03X684112Y-21261I1000J0D01*
G01X686049Y-12551D02*
G03Y-14551I0J-1000D01*
G01X684112Y-13551D02*
G03X683112Y-14551I0J-1000D01*
G01X681537Y-7460D02*
G03X682537Y-8460I1000J0D01*
G01X690282Y-17679D02*
G03X689914Y-18845I1992J-1270D01*
G01X690614Y-17890D02*
G03X690307Y-18862I1660J-1059D01*
G01X682537Y-4525D02*
G03X681537Y-5525I0J-1000D01*
G01X687049Y-24261D02*
X688049D01*
G01X676315Y-24077D02*
X684484D01*
G01Y-23942D02*
X676315D01*
G01X684484Y-23756D02*
X676315D01*
G01Y-23671D02*
X684484D01*
G01X676315Y-23348D02*
X684484D01*
G01Y-23331D02*
X676315D01*
G01X687049Y-23261D02*
X688049D01*
G01X676315Y-23097D02*
X684484D01*
G01Y-23063D02*
X676315D01*
G01X689914Y-18845D02*
X689718Y-23331D01*
G01X690307Y-18862D02*
X690111Y-23348D01*
G01X690058Y-23756D02*
G03X690111Y-23348I-2307J507D01*
G01X689673Y-23671D02*
G03X689718Y-23331I-1921J427D01*
G01X688049Y14915D02*
X689427D01*
G01X687049Y17242D02*
X687915D01*
G01X689427Y17868D02*
X688049D01*
G01X687781Y18242D02*
X682537D01*
G01X671428Y18393D02*
X672128D01*
G01X674380D02*
X675080D01*
G01X677333D02*
X678033D01*
G01X675080Y21371D02*
X674380D01*
G01X678033D02*
X677333D01*
G01X672128D02*
X671428D01*
G01X675080Y24336D02*
X674380D01*
G01X678033D02*
X677333D01*
G01X672128D02*
X671428D01*
G01X675080Y24561D02*
X674380D01*
G01X678033D02*
X677333D01*
G01X672128D02*
X671428D01*
G01X682537Y26116D02*
X687781D01*
G01X687915Y27116D02*
X687049D01*
G01Y18242D02*
X687380Y18235D01*
X687632Y18195D01*
X687806Y18080D01*
X687891Y17871D01*
X687913Y17593D01*
X687915Y17242D01*
G01X686969Y18242D02*
X687015Y18233D01*
X687041Y18206D01*
X687049Y18161D01*
G01X686967Y26116D02*
X687014Y26124D01*
X687041Y26151D01*
X687049Y26196D01*
G01X689309Y33593D02*
X688049D01*
G01X687049Y34908D02*
X687915D01*
G01X689309Y35593D02*
X687309D01*
G01X688049Y35908D02*
X687049D01*
G01X683490Y36767D02*
X673037D01*
G01X688049Y36908D02*
X687049D01*
G01X675663Y37588D02*
X673770D01*
G01X671329Y38588D02*
X675797D01*
G01X672001Y39032D02*
X671974D01*
G01X676132Y39392D02*
X674163D01*
G01X675797Y38588D02*
X675930Y38552D01*
X676049Y38447D01*
X676132Y38288D01*
X676163Y38088D01*
G01X689427Y19836D02*
X688049Y20632D01*
G01X672001Y37940D02*
X674083Y35857D01*
G01X672840Y36569D02*
X673904Y35267D01*
G01X671974Y38069D02*
X673037Y36767D01*
G01X671974Y38069D02*
X672840Y36569D01*
G01X673904Y35267D02*
X673037Y36767D01*
G01X687878Y35593D02*
X687907Y35403D01*
X687915Y35171D01*
Y34908D01*
G01X676163Y38088D02*
X676153Y38173D01*
X676119Y38258D01*
X676060Y38341D01*
X675978Y38418D01*
X675872Y38484D01*
X675743Y38538D01*
X675595Y38574D01*
X675431Y38588D01*
G01X686959Y26116D02*
X686915Y35645D01*
G01X686958Y26116D02*
X686961Y23491D01*
X686967Y20866D01*
X686969Y18242D01*
G01X671428Y24561D02*
Y18393D01*
G01X671974Y44408D02*
Y38069D01*
G01X672001Y44408D02*
Y37940D01*
G01X672128Y24561D02*
Y18393D01*
G01X672699Y44408D02*
Y37242D01*
G01X672840Y36569D02*
Y44408D01*
G01X673770Y40780D02*
Y34257D01*
G01X673913Y43930D02*
Y38588D01*
G01X674163Y44408D02*
Y36767D01*
G01X674380Y24561D02*
Y18393D01*
G01X675080Y24561D02*
Y18393D01*
G01X675163Y43930D02*
Y38588D01*
G01X676132Y44408D02*
Y36767D01*
G01X676163Y43930D02*
Y38088D01*
G01X677333Y24561D02*
Y18393D01*
G01X678033Y24561D02*
Y18393D01*
G01X681325Y35141D02*
Y14955D01*
G01X681537Y25116D02*
Y19242D01*
G01X687781Y18242D02*
Y26116D01*
G01X687915Y34908D02*
Y27116D01*
G01X689427Y19836D02*
Y12946D01*
G01X686915Y18242D02*
X686958Y26116D01*
G01X687915Y27116D02*
X687913Y26754D01*
X687887Y26472D01*
X687797Y26266D01*
X687619Y26158D01*
X687368Y26121D01*
X687049Y26116D01*
G01X689427Y12946D02*
X688049Y12151D01*
G01X682537Y26116D02*
G03X681537Y25116I0J-1000D01*
G01Y19242D02*
G03X682537Y18242I1000J0D01*
G01X687049Y38570D02*
G03X687309Y35593I261J-1477D01*
G01X675663Y37588D02*
G03X676163Y38088I0J500D01*
G01X674445Y6528D02*
X679367D01*
G01X687049Y6877D02*
X688049D01*
G01Y7468D02*
X687049D01*
G01X674445Y9060D02*
X679367D01*
G01X681325Y14955D02*
X682506Y11019D01*
G01X681325Y14955D02*
X682506Y11019D01*
G01X683490D02*
Y44408D01*
G01X687915Y17242D02*
Y7468D01*
G01X686969Y68775D02*
X687014Y68783D01*
X687041Y68810D01*
X687049Y68855D01*
G01X674380Y48355D02*
X675080D01*
G01Y48571D02*
X674380D01*
G01X675080Y48667D02*
X674380D01*
G01X675080Y48729D02*
X674380D01*
G01X675080Y48827D02*
X674380D01*
G01X675080Y49812D02*
X674380D01*
G01X675080Y49910D02*
X674380D01*
G01X675080Y49973D02*
X674380D01*
G01X675080Y50068D02*
X674380D01*
G01Y50284D02*
X675080D01*
G01X687049Y50541D02*
X688049D01*
G01X687049Y50638D02*
X688049D01*
G01X677333Y51111D02*
X678033D01*
G01X687049Y51142D02*
X688049D01*
G01X687049Y51171D02*
X688049D01*
G01X678033Y51327D02*
X677333D01*
G01X678033Y51423D02*
X677333D01*
G01X678033Y51485D02*
X677333D01*
G01X678033Y51583D02*
X677333D01*
G01X688049D02*
X687049D01*
G01X678033Y52568D02*
X677333D01*
G01X687049D02*
X688049D01*
G01X678033Y52666D02*
X677333D01*
G01X678033Y52729D02*
X677333D01*
G01X678033Y52823D02*
X677333D01*
G01X687049Y52975D02*
X688049D01*
G01X687049Y53005D02*
X688049D01*
G01X677333Y53040D02*
X678033D01*
G01X687049Y53512D02*
X688049D01*
G01Y53605D02*
X687049D01*
G01X672128Y53867D02*
X671428D01*
G01Y54083D02*
X672128D01*
G01X671428Y54179D02*
X672128D01*
G01X671428Y54241D02*
X672128D01*
G01X688049Y54260D02*
X687049D01*
G01X688049Y54275D02*
X687049D01*
G01X672128Y54339D02*
X671428D01*
G01X672128Y55323D02*
X671428D01*
G01X672128Y55422D02*
X671428D01*
G01Y55484D02*
X672128D01*
G01X671428Y55579D02*
X672128D01*
G01Y55796D02*
X671428D01*
G01X688050Y56275D02*
X683530D01*
G01X674380Y63316D02*
X675080D01*
G01Y63532D02*
X674380D01*
G01X675080Y63627D02*
X674380D01*
G01X675080Y63690D02*
X674380D01*
G01X675080Y63788D02*
X674380D01*
G01X675080Y64772D02*
X674380D01*
G01X675080Y64871D02*
X674380D01*
G01X675080Y64933D02*
X674380D01*
G01X675080Y65028D02*
X674380D01*
G01Y65245D02*
X675080D01*
G01X677333Y66071D02*
X678033D01*
G01Y66288D02*
X677333D01*
G01X678033Y66383D02*
X677333D01*
G01X678033Y66445D02*
X677333D01*
G01X678033Y66544D02*
X677333D01*
G01X678033Y67528D02*
X677333D01*
G01X678033Y67627D02*
X677333D01*
G01X678033Y67689D02*
X677333D01*
G01X678033Y67784D02*
X677333D01*
G01Y68001D02*
X678033D01*
G01X683530Y68775D02*
X688049D01*
G01X672128Y68827D02*
X671428D01*
G01Y69044D02*
X672128D01*
G01X671428Y69139D02*
X672128D01*
G01X671428Y69201D02*
X672128D01*
G01Y69300D02*
X671428D01*
G01X672128Y70284D02*
X671428D01*
G01X672128Y70382D02*
X671428D01*
G01Y70445D02*
X672128D01*
G01Y70540D02*
X671428D01*
G01X672128Y70756D02*
X671428D01*
G01X688049Y70775D02*
X687049D01*
G01X688049Y71775D02*
X687049D01*
G01X686969Y56275D02*
X687015Y56266D01*
X687041Y56240D01*
X687049Y56195D01*
G01X671428Y53868D02*
Y55794D01*
G01Y68829D02*
Y70755D01*
G01X672128Y53869D02*
Y55795D01*
G01Y68829D02*
Y70755D01*
G01X674380Y48356D02*
Y50282D01*
G01Y63317D02*
Y65243D01*
G01X675080Y48357D02*
Y50283D01*
G01Y63318D02*
Y65243D01*
G01X677333Y51112D02*
Y53038D01*
G01Y66073D02*
Y67999D01*
G01X678033Y51113D02*
Y53039D01*
G01Y66073D02*
Y67999D01*
G01X682530Y67775D02*
Y57275D01*
G01X684065Y68775D02*
Y92474D01*
G01X684402Y68775D02*
Y56275D01*
G01X689427Y72001D02*
Y78891D01*
G01Y72001D02*
X688049Y71206D01*
G01X683530Y68775D02*
G03X682530Y67775I0J-1000D01*
G01Y57275D02*
G03X683530Y56275I1000J0D01*
G01X676132Y41062D02*
X674163D01*
G01X687049Y43930D02*
X671329D01*
G01X682024Y105171D02*
Y44408D01*
G01X683437Y105171D02*
Y44408D01*
G01X684065D02*
Y56275D01*
G01X685065Y44408D02*
Y105171D01*
G01X675080Y79733D02*
X674380D01*
G01X675080Y79831D02*
X674380D01*
G01X675080Y79894D02*
X674380D01*
G01X675080Y79989D02*
X674380D01*
G01Y80205D02*
X675080D01*
G01X677333Y81032D02*
X678033D01*
G01Y81249D02*
X677333D01*
G01X678033Y81344D02*
X677333D01*
G01X678033Y81406D02*
X677333D01*
G01X678033Y81505D02*
X677333D01*
G01X678033Y82489D02*
X677333D01*
G01X678033Y82587D02*
X677333D01*
G01X678033Y82650D02*
X677333D01*
G01X678033Y82745D02*
X677333D01*
G01Y82961D02*
X678033D01*
G01X672128Y83788D02*
X671428D01*
G01Y84005D02*
X672128D01*
G01X671428Y84100D02*
X672128D01*
G01X671428Y84162D02*
X672128D01*
G01Y84260D02*
X671428D01*
G01X672128Y85245D02*
X671428D01*
G01X672128Y85343D02*
X671428D01*
G01Y85406D02*
X672128D01*
G01Y85501D02*
X671428D01*
G01X672128Y85717D02*
X671428D01*
G01X687049Y89474D02*
X688049D01*
G01Y90474D02*
X687049D01*
G01X683530Y92474D02*
X688049D01*
G01X674380Y93237D02*
X675080D01*
G01Y93453D02*
X674380D01*
G01X675080Y93549D02*
X674380D01*
G01X675080Y93611D02*
X674380D01*
G01X675080Y93709D02*
X674380D01*
G01X675080Y94693D02*
X674380D01*
G01X675080Y94792D02*
X674380D01*
G01X675080Y94855D02*
X674380D01*
G01X675080Y94949D02*
X674380D01*
G01X689230Y94974D02*
X688049D01*
G01X674380Y95166D02*
X675080D01*
G01X677333Y95993D02*
X678033D01*
G01Y96209D02*
X677333D01*
G01X678033Y96305D02*
X677333D01*
G01X678033Y96367D02*
X677333D01*
G01X678033Y96465D02*
X677333D01*
G01X688049Y96942D02*
X689230D01*
G01Y96974D02*
X687837D01*
G01X678033Y97449D02*
X677333D01*
G01X678033Y97548D02*
X677333D01*
G01X678033Y97610D02*
X677333D01*
G01X678033Y97705D02*
X677333D01*
G01Y97922D02*
X678033D01*
G01X672128Y98749D02*
X671428D01*
G01Y98965D02*
X672128D01*
G01X671428Y99060D02*
X672128D01*
G01X671428Y99123D02*
X672128D01*
G01Y99221D02*
X671428D01*
G01X672128Y100205D02*
X671428D01*
G01X672128Y100304D02*
X671428D01*
G01Y100366D02*
X672128D01*
G01Y100461D02*
X671428D01*
G01X672128Y100678D02*
X671428D01*
G01X687049Y104974D02*
X687837D01*
G01X687230Y105169D02*
X687837D01*
G01Y105191D02*
X688049D01*
G01Y105464D02*
X687049D01*
G01X686969Y92474D02*
X687015Y92466D01*
X687041Y92439D01*
X687049Y92394D01*
G01X689427Y78891D02*
X688049Y79687D01*
G01Y94974D02*
X687837Y95186D01*
G01X671428Y83790D02*
Y85716D01*
G01Y98750D02*
Y100676D01*
G01X672128Y83790D02*
Y85716D01*
G01Y98751D02*
Y100677D01*
G01X673352Y105171D02*
Y102336D01*
G01X673998Y106958D02*
Y105958D01*
G01X674380Y93238D02*
Y95164D01*
G01X674730Y105171D02*
Y102336D01*
G01X675080Y93239D02*
Y95165D01*
G01X675498Y105958D02*
Y106958D01*
G01X676154D02*
Y105958D01*
G01X676246D02*
Y106958D01*
G01X676506D02*
Y105958D01*
G01X676510Y105171D02*
Y106958D01*
G01X676732Y105958D02*
Y106958D01*
G01X676783Y105958D02*
Y106958D01*
G01X677191Y105958D02*
Y106958D01*
G01X677333Y81034D02*
Y82960D01*
G01Y95994D02*
Y97920D01*
G01X678033Y81034D02*
Y82960D01*
G01Y95995D02*
Y97921D01*
G01X678175Y106958D02*
Y105958D01*
G01X678506Y106958D02*
Y105958D01*
G01X678587D02*
Y106958D01*
G01X678638Y105958D02*
Y106958D01*
G01X679120Y105958D02*
Y106958D01*
G01X679217Y105958D02*
Y106958D01*
G01X679258Y105171D02*
Y102336D01*
G01X679506Y106958D02*
Y105958D01*
G01X680024Y106958D02*
Y105958D01*
G01X681368D02*
Y106958D01*
G01X682128Y107942D02*
Y106958D01*
G01X682530Y104171D02*
Y93474D01*
G01X683128Y107942D02*
Y106958D01*
G01X684402Y105171D02*
Y92474D01*
G01X685352Y105958D02*
Y106958D01*
G01X685852Y105958D02*
Y106958D01*
G01X686352D02*
Y105958D01*
G01X686852D02*
Y106958D01*
G01X687837Y95186D02*
Y105753D01*
G01X689230Y104958D02*
Y94974D01*
G01Y104958D02*
G03X687230Y106958I-2000J0D01*
G01X682530Y93474D02*
G03X683530Y92474I1000J0D01*
G01Y105171D02*
G03X682530Y104171I0J-1000D01*
G01X687049Y105549D02*
G03X686962Y105958I-1000J1D01*
G01X687837Y105753D02*
G03X687230Y105958I-607J-795D01*
G01X687822Y106869D02*
G03X686049Y107942I-1772J-927D01*
G01X688049Y73970D02*
X689427D01*
G01Y76923D02*
X688049D01*
G01X674380Y78276D02*
X675080D01*
G01Y78493D02*
X674380D01*
G01X675080Y78588D02*
X674380D01*
G01X675080Y78650D02*
X674380D01*
G01X675080Y78749D02*
X674380D01*
G01Y78278D02*
Y80204D01*
G01X675080Y78278D02*
Y80204D01*
G01X687049Y77628D02*
X685065Y75643D01*
G01X693140Y137794D02*
X690679D01*
G01X685266D02*
X682805D01*
G01X677392D02*
X674931D01*
G01X670994Y149856D02*
Y137794D01*
G01X674931D02*
Y153877D01*
G01X677392Y150359D02*
Y137794D01*
G01X682805D02*
Y149856D01*
G01X685266D02*
Y137794D01*
G01X690679D02*
Y149856D01*
G01X693140D02*
Y137794D01*
G01X686049Y107942D02*
X682128D01*
G01X688711Y151867D02*
X687234D01*
G01X680837D02*
X679852D01*
G01X674931Y153877D02*
X677392D01*
G01X679852D02*
X681821D01*
G01X687726D02*
X689695D01*
G01X681821D02*
X683297Y153375D01*
G01X689695Y153877D02*
X691171Y153375D01*
G01X681821Y151364D02*
X680837Y151867D01*
G01X689695Y151364D02*
X688711Y151867D01*
G01X682313Y150862D02*
X681821Y151364D01*
G01X683297Y153375D02*
X684774Y151867D01*
G01X690187Y150862D02*
X689695Y151364D01*
G01X691171Y153375D02*
X692156Y152369D01*
G01X682805Y149856D02*
X682313Y150862D01*
G01X690679Y149856D02*
X690187Y150862D01*
G01X692156Y152369D02*
X693140Y149856D01*
G01X677392Y153877D02*
Y152369D01*
G01X685758Y150862D02*
X685266Y149856D01*
G01X677392Y152369D02*
X678376Y153375D01*
G01Y151364D02*
X677392Y150359D01*
G01X684774Y151867D02*
X686250Y153375D01*
G01Y151364D02*
X685758Y150862D01*
G01X687234Y151867D02*
X686250Y151364D01*
G01X678376Y153375D02*
X679852Y153877D01*
G01Y151867D02*
X678376Y151364D01*
G01X686250Y153375D02*
X687726Y153877D01*
G01X779615Y236219D02*
X686933D01*
G01X678704Y238385D02*
X677730Y239106D01*
X677243Y239828D01*
X676756Y241272D01*
Y244159D01*
X677243Y245603D01*
X677730Y246324D01*
X678704Y247046D01*
X679679Y246324D01*
X680166Y245603D01*
X680653Y244159D01*
Y241272D01*
X680166Y239828D01*
X679679Y239106D01*
X678704Y238385D01*
G01X785914Y283464D02*
X686933D01*
G01X678704Y285629D02*
X677730Y286351D01*
X677243Y287072D01*
X676756Y288516D01*
Y291403D01*
X677243Y292847D01*
X677730Y293568D01*
X678704Y294290D01*
X679679Y293568D01*
X680166Y292847D01*
X680653Y291403D01*
Y288516D01*
X680166Y287072D01*
X679679Y286351D01*
X678704Y285629D01*
G01X681275Y474684D02*
Y478872D01*
G01X710802Y474684D02*
X681275D01*
G01X704241Y499814D02*
X705881Y503164D01*
G01Y504840D02*
X704241Y507353D01*
G01X701780Y509028D02*
X697679Y509866D01*
G01X704241Y507353D02*
X701780Y509028D01*
G01X674713Y488924D02*
X673072Y486411D01*
G01X687836Y507353D02*
X686196Y504840D01*
G01X682915Y508190D02*
X686196Y511541D01*
G01X690297Y509028D02*
X687836Y507353D01*
G01X686196Y511541D02*
X689477Y513216D01*
G01X682095Y504840D02*
X682915Y508190D01*
G01X673072Y503164D02*
X674713Y500651D01*
G01X694398Y509866D02*
X690297Y509028D01*
G01X686196Y504840D02*
X682095D01*
G01X697679Y509866D02*
X694398D01*
G01X681275Y478872D02*
X704241Y499814D01*
G01X708342Y497301D02*
X687836Y478872D01*
G01D02*
X710802D01*
G01X695218Y514054D02*
X698499D01*
G01D02*
X703420Y513216D01*
G01D02*
X706701Y511541D01*
G01X689477Y513216D02*
X695218Y514054D01*
G01X702087Y882952D02*
X701991Y882910D01*
G01X702183Y881695D02*
X702278Y881737D01*
G01X702183Y880983D02*
X702278Y881025D01*
G01X702067Y882742D02*
X702010Y882700D01*
G01X702202Y881905D02*
X702259Y881946D01*
G01Y881234D02*
X702202Y881193D01*
G01X702010Y882700D02*
X701952Y882617D01*
G01X702259Y881946D02*
X702317Y882030D01*
G01X702278Y881737D02*
X702393Y881905D01*
G01X702317Y881318D02*
X702259Y881234D01*
G01X701991Y882910D02*
X701895Y882784D01*
G01X702278Y881025D02*
X702374Y881151D01*
G01X703276Y882114D02*
X702950Y881318D01*
G01X702317Y882030D02*
X702355Y882114D01*
G01X701952Y882617D02*
X701914Y882491D01*
G01X702355Y881444D02*
X702317Y881318D01*
G01X701895Y882784D02*
X701837Y882617D01*
G01X702374Y881151D02*
X702432Y881318D01*
G01X703410Y882114D02*
X702950Y880983D01*
G01X701914Y882491D02*
X701895Y882365D01*
G01X702355Y882114D02*
X702374Y882240D01*
G01Y881569D02*
X702355Y881444D01*
G01X704139Y882449D02*
X704216Y882952D01*
G01X704120Y882282D02*
X703947Y881151D01*
G01X704331Y882952D02*
X704024Y880983D01*
G01X701837Y882617D02*
X701799Y882407D01*
G01X702432Y881318D02*
X702470Y881528D01*
G01X695374Y883464D02*
Y892519D01*
G01X697539D02*
Y883464D01*
G01X698524D02*
Y892519D01*
G01X700689D02*
Y883464D01*
G01X701673D02*
Y890845D01*
G01X701799Y882407D02*
Y882198D01*
G01X701895Y882365D02*
Y882240D01*
G01X702374D02*
Y882365D01*
G01X702393Y881905D02*
Y881821D01*
G01X702489D02*
Y882114D01*
G01X702643D02*
Y882365D01*
G01X702835D02*
Y882952D01*
G01Y880983D02*
Y882114D01*
G01X702950Y882952D02*
Y882365D01*
G01Y881318D02*
Y882114D01*
G01X703410Y882365D02*
Y882114D01*
G01X703839Y890845D02*
Y883464D01*
G01X702470Y881528D02*
X702489Y881821D01*
G01X702393D02*
X702374Y881569D01*
G01X702489Y882114D02*
X702470Y882407D01*
G01X701799Y882198D02*
X701837Y881988D01*
G01X702470Y882407D02*
X702432Y882617D01*
G01X703870Y880983D02*
X703564Y882952D01*
G01X701837Y881444D02*
X701856Y881318D01*
G01X701895Y882240D02*
X701914Y882114D01*
G01X702374Y882365D02*
X702355Y882491D01*
G01X703947Y881151D02*
X703774Y882282D01*
G01X703679Y882952D02*
X703756Y882449D01*
G01X701856Y881318D02*
X701914Y881151D01*
G01X702432Y882617D02*
X702374Y882784D01*
G01X701972Y881318D02*
X701933Y881444D01*
G01X702355Y882491D02*
X702317Y882617D01*
G01X701837Y881988D02*
X701895Y881863D01*
G01X701914Y882114D02*
X701952Y882030D01*
G01X701914Y881151D02*
X702010Y881025D01*
G01X701895Y881863D02*
X701991Y881737D01*
G01X702374Y882784D02*
X702278Y882910D01*
G01X702029Y881234D02*
X701972Y881318D01*
G01X701952Y882030D02*
X702010Y881946D01*
G01X702317Y882617D02*
X702259Y882700D01*
G01X702087Y881193D02*
X702029Y881234D01*
G01X702010Y881946D02*
X702067Y881905D01*
G01X702259Y882700D02*
X702202Y882742D01*
G01X704024Y880983D02*
X703870D01*
G01X702950D02*
X702835D01*
G01X702106D02*
X702183D01*
G01X702202Y881193D02*
X702087D01*
G01X701933Y881444D02*
X701837D01*
G01X702087Y881695D02*
X702183D01*
G01X702067Y881905D02*
X702202D01*
G01X702835Y882114D02*
X702643D01*
G01X702950D02*
X703276D01*
G01X703774Y882282D02*
X704120D01*
G01X702950Y882365D02*
X703410D01*
G01X702643D02*
X702835D01*
G01X703756Y882449D02*
X704139D01*
G01X702202Y882742D02*
X702067D01*
G01X702183Y882952D02*
X702087D01*
G01X704216D02*
X704331D01*
G01X703564D02*
X703679D01*
G01X702835D02*
X702950D01*
G01X703839Y883464D02*
X701673D01*
G01X700689D02*
X698524D01*
G01X697539D02*
X695374D01*
G01X702010Y881025D02*
X702106Y880983D01*
G01X701991Y881737D02*
X702087Y881695D01*
G01X702278Y882910D02*
X702183Y882952D01*
G01X680768Y871445D02*
X680276Y871193D01*
G01X676339Y872199D02*
X677077Y872450D01*
G01Y871445D02*
X676339Y871193D01*
G01X680276Y872199D02*
X681014Y872450D01*
G01X675846Y871696D02*
X676339Y872199D01*
G01Y871193D02*
X675846Y870691D01*
G01X679537Y871445D02*
X680276Y872199D01*
G01Y871193D02*
X680030Y870942D01*
G01D02*
X679783Y870440D01*
G01X671417Y864408D02*
Y870440D01*
G01X672343Y892519D02*
Y883464D01*
G01X672648Y870440D02*
Y864408D01*
G01X673327Y883464D02*
Y892519D01*
G01X674616Y864408D02*
Y872450D01*
G01X675492Y892519D02*
Y883464D01*
G01X675846Y872450D02*
Y871696D01*
G01Y870691D02*
Y864408D01*
G01X676476Y883464D02*
Y892519D01*
G01X678553Y864408D02*
Y870440D01*
G01X678642Y892519D02*
Y883464D01*
G01X679626D02*
Y892519D01*
G01X679783Y870440D02*
Y864408D01*
G01X681791Y892519D02*
Y883464D01*
G01X682490Y864408D02*
Y870440D01*
G01X682776Y883464D02*
Y892519D01*
G01X683720Y870440D02*
Y864408D01*
G01X684941Y892519D02*
Y883464D01*
G01X685925D02*
Y892519D01*
G01X688091D02*
Y883464D01*
G01X689075D02*
Y892519D01*
G01X691240D02*
Y883464D01*
G01X692224D02*
Y892519D01*
G01X694390D02*
Y883464D01*
G01X671417Y870440D02*
X671171Y870942D01*
G01X678553Y870440D02*
X678307Y870942D01*
G01X682490Y870440D02*
X682244Y870942D01*
G01X672156Y871696D02*
X672648Y870440D01*
G01X683228Y871696D02*
X683720Y870440D01*
G01X671171Y870942D02*
X670925Y871193D01*
G01X671663Y872199D02*
X672156Y871696D01*
G01X678307Y870942D02*
X678061Y871193D01*
G01X678799Y872199D02*
X679537Y871445D01*
G01X682244Y870942D02*
X681998Y871193D01*
G01X682736Y872199D02*
X683228Y871696D01*
G01X670925Y872450D02*
X671663Y872199D01*
G01X678061Y872450D02*
X678799Y872199D01*
G01X681998Y872450D02*
X682736Y872199D01*
G01X678061Y871193D02*
X677569Y871445D01*
G01X681998Y871193D02*
X681506Y871445D01*
G01X683720Y864408D02*
X682490D01*
G01X679783D02*
X678553D01*
G01X675846D02*
X674616D01*
G01X672648D02*
X671417D01*
G01X681506Y871445D02*
X680768D01*
G01X677569D02*
X677077D01*
G01X674616Y872450D02*
X675846D01*
G01X677077D02*
X678061D01*
G01X681014D02*
X681998D01*
G01X694390Y883464D02*
X692224D01*
G01X691240D02*
X689075D01*
G01X688091D02*
X685925D01*
G01X684941D02*
X682776D01*
G01X681791D02*
X679626D01*
G01X678642D02*
X676476D01*
G01X675492D02*
X673327D01*
G01X701673Y890845D02*
X703839D01*
G01X695374Y892519D02*
X697539D01*
G01X698524D02*
X700689D01*
G01X676476D02*
X678642D01*
G01X673327D02*
X675492D01*
G01X679626D02*
X681791D01*
G01X685925D02*
X688091D01*
G01X682776D02*
X684941D01*
G01X689075D02*
X691240D01*
G01X692224D02*
X694390D01*
G01X675898Y939377D02*
X674924Y940099D01*
X674437Y940821D01*
X673950Y942265D01*
Y945152D01*
X674437Y946595D01*
X674924Y947317D01*
X675898Y948039D01*
X676873Y947317D01*
X677360Y946595D01*
X677847Y945152D01*
Y942265D01*
X677360Y940821D01*
X676873Y940099D01*
X675898Y939377D01*
G01X730985Y-1132018D02*
X731698Y-1130117D01*
X733837Y-1129166D01*
X735976Y-1130117D01*
X736689Y-1132018D01*
X735976Y-1133919D01*
X735263Y-1134870D01*
X733837Y-1135820D01*
X732411Y-1134870D01*
X731698Y-1133919D01*
X730985Y-1132018D01*
Y-1128215D01*
X731698Y-1126314D01*
X732411Y-1125364D01*
X733837Y-1124413D01*
X735263Y-1125364D01*
X735976Y-1126314D01*
G01X737136Y-277640D02*
Y-271866D01*
G01X732264Y-276197D02*
X731776Y-276919D01*
X730802Y-277640D01*
X729828Y-276919D01*
X728853Y-275475D01*
Y-274031D01*
X729828Y-272588D01*
X730802Y-271866D01*
X731776Y-272588D01*
X732264Y-274031D01*
X728853D01*
G01X737136Y-273310D02*
X738110Y-271866D01*
X739085D01*
X740059Y-273310D01*
Y-277640D01*
G01X705468Y-271866D02*
Y-280527D01*
G01X721545Y-277640D02*
Y-271866D01*
G01X705468Y-274031D02*
X706442Y-272588D01*
X707416Y-271866D01*
X708391Y-272588D01*
X709365Y-274031D01*
Y-275475D01*
X708391Y-276919D01*
X707416Y-277640D01*
X706442D01*
X705468Y-275475D01*
G01X717160D02*
X716186Y-276919D01*
X715211Y-277640D01*
X714237Y-276919D01*
X713263Y-275475D01*
Y-274031D01*
X714237Y-272588D01*
X715211Y-271866D01*
X716186Y-272588D01*
X717160Y-274031D01*
Y-275475D01*
G01X721545Y-273310D02*
X722520Y-271866D01*
X723494D01*
X724469Y-273310D01*
Y-277640D01*
G01X732352Y69017D02*
X732343Y69015D01*
G01X731494Y69030D02*
X731504Y69032D01*
G01X731270Y69030D02*
X731280Y69032D01*
G01X731472Y69118D02*
X731462Y69115D01*
G01X731248Y69118D02*
X731238Y69115D01*
G01X730377Y69030D02*
X730387Y69032D01*
G01X730354Y69118D02*
X730344Y69115D01*
G01X732340Y69027D02*
X732352Y69030D01*
G01X732190Y69017D02*
X732178Y69015D01*
G01X732328Y69120D02*
X732316Y69118D01*
G01X732030Y69070D02*
X732018Y69068D01*
G01X731673Y69017D02*
X731661Y69015D01*
G01X731506Y69017D02*
X731494Y69015D01*
G01X731376D02*
X731388Y69017D01*
G01X731890Y69120D02*
X731878Y69118D01*
G01X731282Y69017D02*
X731270Y69015D01*
G01X731363Y69090D02*
X731351Y69088D01*
G01X731459Y69130D02*
X731472Y69133D01*
G01X730879Y69015D02*
X730891Y69017D01*
G01X731363Y69133D02*
X731351Y69130D01*
G01X730879Y69057D02*
X730891Y69060D01*
G01X731235Y69130D02*
X731248Y69133D01*
G01X731031Y69120D02*
X731019Y69118D01*
G01X730389Y69017D02*
X730377Y69015D01*
G01X730866Y69133D02*
X730854Y69130D01*
G01X730342D02*
X730354Y69133D01*
G01X732313Y69130D02*
X732330Y69133D01*
G01X731875Y69130D02*
X731893Y69133D01*
G01X731017Y69130D02*
X731033Y69133D01*
G01X735236Y67322D02*
X732087D01*
G01X733996Y68641D02*
X733922D01*
G01X733578D02*
X733504D01*
G01X733873Y68792D02*
X733627D01*
G01X733861Y68842D02*
X733639D01*
G01X729813Y69015D02*
X729724D01*
G01X729892D02*
X729872D01*
G01X730039D02*
X729951D01*
G01X730261D02*
X730172D01*
G01X730295D02*
X730281D01*
G01X730377D02*
X730354D01*
G01X730529D02*
X730515D01*
G01X730446D02*
X730431D01*
G01X730603D02*
X730588D01*
G01X730810D02*
X730795D01*
G01X731080D02*
X730992D01*
G01X731130D02*
X731115D01*
G01X731270D02*
X731248D01*
G01X731494D02*
X731472D01*
G01X731661D02*
X731602D01*
G01X731831D02*
X731816D01*
G01X731728D02*
X731713D01*
G01X731781D02*
X731762D01*
G01X731939D02*
X731850D01*
G01X731974D02*
X731959D01*
G01X732099D02*
X732084D01*
G01X732178D02*
X732119D01*
G01X732343D02*
X732323D01*
G01X732451D02*
X732436D01*
G01X730135D02*
X730153D01*
G01X730059D02*
X730074D01*
G01X730869D02*
X730879D01*
G01X731363D02*
X731376D01*
G01X730881Y69027D02*
X730866D01*
G01X731011D02*
X731080D01*
G01X731361D02*
X731378D01*
G01X731870D02*
X731939D01*
G01X732326D02*
X732340D01*
G01X731663Y69030D02*
X731617D01*
G01X732180D02*
X732133D01*
G01X729739D02*
X729813D01*
G01X729966D02*
X730039D01*
G01X730187D02*
X730261D01*
G01X730354D02*
X730377D01*
G01X731248D02*
X731270D01*
G01X731472D02*
X731494D01*
G01X730846Y69042D02*
X730834D01*
G01X732289D02*
X732301D01*
G01X731513Y69045D02*
X731528D01*
G01X730972Y69057D02*
X730938D01*
G01X731582D02*
X731548D01*
G01X730866D02*
X730879D01*
G01X730396Y69065D02*
X730374D01*
G01X731289D02*
X731267D01*
G01X732018Y69068D02*
X731974D01*
G01X730074D02*
X730116D01*
G01X731617D02*
X731663D01*
G01X732133D02*
X732180D01*
G01X729803Y69070D02*
X729739D01*
G01X730030D02*
X729966D01*
G01X730515D02*
X730446D01*
G01X732338D02*
X732328D01*
G01X730864D02*
X730881D01*
G01X730938D02*
X730972D01*
G01X731548D02*
X731582D01*
G01X731378Y69077D02*
X731361D01*
G01X730374Y69080D02*
X730411D01*
G01X731267D02*
X731304D01*
G01X732328D02*
X732338D01*
G01X730074Y69082D02*
X730121D01*
G01X731617D02*
X731663D01*
G01X731974D02*
X732020D01*
G01X732133D02*
X732180D01*
G01X729739Y69085D02*
X729803D01*
G01X729966D02*
X730030D01*
G01X730446D02*
X730515D01*
G01X731376Y69090D02*
X731363D01*
G01X730411Y69103D02*
X730396D01*
G01X731304D02*
X731289D01*
G01X731528D02*
X731513D01*
G01X731007Y69105D02*
X730994D01*
G01X731865D02*
X731853D01*
G01X732303D02*
X732291D01*
G01X731395D02*
X731407D01*
G01X729813Y69118D02*
X729739D01*
G01X730039D02*
X729966D01*
G01X730377D02*
X730354D01*
G01X731270D02*
X731248D01*
G01X731494D02*
X731472D01*
G01X731663D02*
X731617D01*
G01X732180D02*
X732133D01*
G01X730121Y69120D02*
X730074D01*
G01X730588D02*
X730549D01*
G01X730643D02*
X730603D01*
G01X730881D02*
X730864D01*
G01X731041D02*
X731031D01*
G01X731900D02*
X731890D01*
G01X732020D02*
X731974D01*
G01X732338D02*
X732328D01*
G01X732436D02*
X732397D01*
G01X732490D02*
X732451D01*
G01X731361D02*
X731376D01*
G01X730118Y69133D02*
X730059D01*
G01X730879D02*
X730866D01*
G01X731373D02*
X731363D01*
G01X729724D02*
X729813D01*
G01X729917D02*
X729931D01*
G01X729833D02*
X729848D01*
G01X729951D02*
X730039D01*
G01X730172D02*
X730187D01*
G01X730281D02*
X730295D01*
G01X730354D02*
X730377D01*
G01X730515D02*
X730529D01*
G01X730431D02*
X730446D01*
G01X730549D02*
X730643D01*
G01X730795D02*
X730810D01*
G01X731033D02*
X731043D01*
G01X731115D02*
X731130D01*
G01X731248D02*
X731270D01*
G01X731472D02*
X731494D01*
G01X731602D02*
X731661D01*
G01X731809D02*
X731831D01*
G01X731713D02*
X731735D01*
G01X731893D02*
X731902D01*
G01X731959D02*
X732018D01*
G01X732084D02*
X732099D01*
G01X732119D02*
X732178D01*
G01X732330D02*
X732335D01*
G01X732397D02*
X732490D01*
G01X733701Y69231D02*
X733799D01*
G01X732087Y70471D02*
X735236D01*
G01X732335Y69133D02*
X732352Y69130D01*
G01X731043Y69133D02*
X731058Y69130D01*
G01X731902Y69133D02*
X731917Y69130D01*
G01X732352Y69068D02*
X732338Y69070D01*
G01X730354Y69015D02*
X730342Y69017D01*
G01X730131Y69130D02*
X730118Y69133D01*
G01X730856Y69017D02*
X730869Y69015D01*
G01X730377Y69133D02*
X730389Y69130D01*
G01X730854Y69060D02*
X730866Y69057D01*
G01X731248Y69015D02*
X731235Y69017D01*
G01X731351D02*
X731363Y69015D01*
G01X730891Y69130D02*
X730879Y69133D01*
G01X731472Y69015D02*
X731459Y69017D01*
G01X731053Y69118D02*
X731041Y69120D01*
G01X731388Y69088D02*
X731376Y69090D01*
G01X731270Y69133D02*
X731282Y69130D01*
G01X731385D02*
X731373Y69133D01*
G01X731494D02*
X731506Y69130D01*
G01X731661Y69133D02*
X731673Y69130D01*
G01X732313Y69030D02*
X732326Y69027D01*
G01X731912Y69118D02*
X731900Y69120D01*
G01X732018Y69133D02*
X732030Y69130D01*
G01X732178Y69133D02*
X732190Y69130D01*
G01X732350Y69118D02*
X732338Y69120D01*
G01X731462Y69032D02*
X731472Y69030D01*
G01X731280Y69115D02*
X731270Y69118D01*
G01X732323Y69015D02*
X732313Y69017D01*
G01X730344Y69032D02*
X730354Y69030D01*
G01X730387Y69115D02*
X730377Y69118D01*
G01X731238Y69032D02*
X731248Y69030D01*
G01X731504Y69115D02*
X731494Y69118D01*
G01X730128D02*
X730121Y69120D01*
G01X730866Y69027D02*
X730859Y69030D01*
G01X730856Y69072D02*
X730864Y69070D01*
G01X730889Y69118D02*
X730881Y69120D01*
G01X731354Y69030D02*
X731361Y69027D01*
G01X731385Y69075D02*
X731378Y69077D01*
G01X731376Y69120D02*
X731383Y69118D01*
G01X731663Y69068D02*
X731671Y69065D01*
G01Y69115D02*
X731663Y69118D01*
G01X732028D02*
X732020Y69120D01*
G01X732180Y69068D02*
X732188Y69065D01*
G01Y69115D02*
X732180Y69118D01*
G01X732357Y69075D02*
X732370Y69070D01*
G01X730342Y69017D02*
X730332Y69022D01*
G01X730389Y69130D02*
X730399Y69125D01*
G01X731235Y69017D02*
X731226Y69022D01*
G01X731058Y69130D02*
X731068Y69125D01*
G01X731459Y69017D02*
X731450Y69022D01*
G01X731282Y69130D02*
X731292Y69125D01*
G01X731506Y69130D02*
X731516Y69125D01*
G01X731678Y69075D02*
X731683Y69072D01*
G01X731917Y69130D02*
X731927Y69125D01*
G01X732195Y69075D02*
X732200Y69072D01*
G01X732313Y69017D02*
X732303Y69022D01*
G01X732308Y69032D02*
X732313Y69030D01*
G01X732352Y69130D02*
X732362Y69125D01*
G01X730844Y69025D02*
X730856Y69017D01*
G01X730842Y69068D02*
X730854Y69060D01*
G01X730903Y69123D02*
X730891Y69130D01*
G01X731339Y69025D02*
X731351Y69017D01*
G01X731400Y69080D02*
X731388Y69088D01*
G01X731398Y69123D02*
X731385Y69130D01*
G01X730337Y69037D02*
X730344Y69032D01*
G01X730394Y69110D02*
X730387Y69115D01*
G01X730859Y69030D02*
X730852Y69035D01*
G01X730849Y69077D02*
X730856Y69072D01*
G01X730896Y69113D02*
X730889Y69118D01*
G01X731157Y69040D02*
X731149Y69045D01*
G01X731061Y69113D02*
X731053Y69118D01*
G01X731230Y69037D02*
X731238Y69032D01*
G01X731181Y69108D02*
X731189Y69103D01*
G01X731346Y69035D02*
X731354Y69030D01*
G01X731287Y69110D02*
X731280Y69115D01*
G01X731393Y69070D02*
X731385Y69075D01*
G01X731454Y69037D02*
X731462Y69032D01*
G01X731383Y69118D02*
X731391Y69113D01*
G01X731511Y69110D02*
X731504Y69115D01*
G01X731919Y69113D02*
X731912Y69118D01*
G01X732237Y69040D02*
X732230Y69045D01*
G01X732303Y69022D02*
X732296Y69027D01*
G01X732261Y69108D02*
X732269Y69103D01*
G01X732360Y69062D02*
X732352Y69068D01*
G01X732357Y69113D02*
X732350Y69118D01*
G01X730141Y69123D02*
X730131Y69130D01*
G01X731673D02*
X731683Y69123D01*
G01X732030Y69130D02*
X732040Y69123D01*
G01X732190Y69130D02*
X732200Y69123D01*
G01X731671Y69065D02*
X731676Y69060D01*
G01Y69110D02*
X731671Y69115D01*
G01X732188Y69065D02*
X732193Y69060D01*
G01Y69110D02*
X732188Y69115D01*
G01X730133Y69113D02*
X730128Y69118D01*
G01X730332Y69022D02*
X730322Y69032D01*
G01X730399Y69125D02*
X730409Y69115D01*
G01X731068Y69125D02*
X731078Y69115D01*
G01X731226Y69022D02*
X731216Y69032D01*
G01X731292Y69125D02*
X731302Y69115D01*
G01X731398Y69065D02*
X731393Y69070D01*
G01X731450Y69022D02*
X731440Y69032D01*
G01X731407Y69072D02*
X731400Y69080D01*
G01X731516Y69125D02*
X731526Y69115D01*
G01X731927Y69125D02*
X731937Y69115D01*
G01X732033Y69113D02*
X732028Y69118D01*
G01X732303Y69037D02*
X732308Y69032D01*
G01X732362Y69125D02*
X732372Y69115D01*
G01X730148Y69113D02*
X730141Y69123D01*
G01X730837Y69035D02*
X730844Y69025D01*
G01X730834Y69077D02*
X730842Y69068D01*
G01X730911Y69113D02*
X730903Y69123D01*
G01X731331Y69035D02*
X731339Y69025D01*
G01X731405Y69113D02*
X731398Y69123D01*
G01X731683Y69072D02*
X731691Y69062D01*
G01X731683Y69123D02*
X731691Y69113D01*
G01X732040Y69123D02*
X732047Y69113D01*
G01X732200Y69072D02*
X732207Y69062D01*
G01X732200Y69123D02*
X732207Y69113D01*
G01X730332Y69045D02*
X730337Y69037D01*
G01X730852Y69035D02*
X730846Y69042D01*
G01X730844Y69085D02*
X730849Y69077D01*
G01X730901Y69105D02*
X730896Y69113D01*
G01X731066Y69105D02*
X731061Y69113D01*
G01X731226Y69045D02*
X731230Y69037D01*
G01X731341Y69042D02*
X731346Y69035D01*
G01X731391Y69113D02*
X731395Y69105D01*
G01X731450Y69045D02*
X731454Y69037D01*
G01X731924Y69105D02*
X731919Y69113D01*
G01X732296Y69027D02*
X732291Y69035D01*
G01X732370Y69070D02*
X732375Y69062D01*
G01X732362Y69105D02*
X732357Y69113D01*
G01X730322Y69032D02*
X730318Y69042D01*
G01X731216Y69032D02*
X731211Y69042D01*
G01X731440Y69032D02*
X731435Y69042D01*
G01X732301D02*
X732303Y69037D01*
G01X732365Y69052D02*
X732360Y69062D01*
G01X730830Y69090D02*
X730834Y69077D01*
G01X730915Y69100D02*
X730911Y69113D01*
G01X731326Y69047D02*
X731331Y69035D01*
G01X731413Y69060D02*
X731407Y69072D01*
G01X730153Y69015D02*
X730131Y69072D01*
G01X730116Y69068D02*
X730135Y69015D01*
G01X731762D02*
X731728Y69108D01*
G01X731735Y69133D02*
X731772Y69027D01*
G01X729848Y69133D02*
X729882Y69030D01*
G01X729872Y69015D02*
X729833Y69133D01*
G01X733799Y69231D02*
X733996Y68641D01*
G01X730135Y69105D02*
X730133Y69113D01*
G01X730150Y69105D02*
X730148Y69113D01*
G01X730396Y69103D02*
X730394Y69110D01*
G01X730834Y69042D02*
X730837Y69035D01*
G01X730842Y69093D02*
X730844Y69085D01*
G01X730903Y69097D02*
X730901Y69105D01*
G01X731289Y69103D02*
X731287Y69110D01*
G01X731339Y69050D02*
X731341Y69042D01*
G01X731400Y69057D02*
X731398Y69065D01*
G01X731407Y69105D02*
X731405Y69113D01*
G01X731513Y69103D02*
X731511Y69110D01*
G01X731676Y69060D02*
X731678Y69052D01*
G01X731691Y69062D02*
X731693Y69055D01*
G01X731678Y69103D02*
X731676Y69110D01*
G01X731691Y69113D02*
X731693Y69105D01*
G01X732035D02*
X732033Y69113D01*
G01X732047D02*
X732050Y69105D01*
G01X732193Y69060D02*
X732195Y69052D01*
G01X732207Y69062D02*
X732210Y69055D01*
G01X732195Y69103D02*
X732193Y69110D01*
G01X732207Y69113D02*
X732210Y69105D01*
G01X732291Y69035D02*
X732289Y69042D01*
G01X733922Y68641D02*
X733873Y68792D01*
G01X733750Y69181D02*
X733861Y68842D01*
G01X730330Y69055D02*
X730332Y69045D01*
G01X731078Y69115D02*
X731080Y69105D01*
G01X731223Y69055D02*
X731226Y69045D01*
G01X731447Y69055D02*
X731450Y69045D01*
G01X731937Y69115D02*
X731939Y69105D01*
G01X732375Y69062D02*
X732377Y69052D01*
G01X732372Y69115D02*
X732375Y69105D01*
G01X730318Y69042D02*
X730315Y69055D01*
G01X730409Y69115D02*
X730411Y69103D01*
G01X731211Y69042D02*
X731208Y69055D01*
G01X731302Y69115D02*
X731304Y69103D01*
G01X731435Y69042D02*
X731432Y69055D01*
G01X731526Y69115D02*
X731528Y69103D01*
G01X730918Y69082D02*
X730915Y69100D01*
G01X731324Y69065D02*
X731326Y69047D01*
G01X729331Y67322D02*
Y70471D01*
G01X729724Y69015D02*
Y69133D01*
G01X729739Y69070D02*
Y69030D01*
G01Y69118D02*
Y69085D01*
G01X729803D02*
Y69070D01*
G01X729813Y69133D02*
Y69118D01*
G01Y69030D02*
Y69015D01*
G01X729951D02*
Y69133D01*
G01X729966Y69070D02*
Y69030D01*
G01Y69118D02*
Y69085D01*
G01X730030D02*
Y69070D01*
G01X730039Y69133D02*
Y69118D01*
G01Y69030D02*
Y69015D01*
G01X730059Y69133D02*
Y69015D01*
G01X730074Y69120D02*
Y69082D01*
G01Y69015D02*
Y69068D01*
G01X730135Y69097D02*
Y69105D01*
G01X730150Y69095D02*
Y69105D01*
G01X730172Y69015D02*
Y69133D01*
G01X730187D02*
Y69030D01*
G01X730261D02*
Y69015D01*
G01X730281D02*
Y69133D01*
G01X730295D02*
Y69015D01*
G01X730315Y69055D02*
Y69093D01*
G01X730330D02*
Y69055D01*
G01X730374Y69065D02*
Y69080D01*
G01X730396Y69045D02*
Y69065D01*
G01X730411Y69080D02*
Y69042D01*
G01X730431Y69015D02*
Y69133D01*
G01X730446Y69070D02*
Y69015D01*
G01Y69133D02*
Y69085D01*
G01X730515Y69015D02*
Y69070D01*
G01Y69085D02*
Y69133D01*
G01X730529D02*
Y69015D01*
G01X730549Y69120D02*
Y69133D01*
G01X730588Y69015D02*
Y69120D01*
G01X730603D02*
Y69015D01*
G01X730643Y69133D02*
Y69120D01*
G01X730780Y69095D02*
Y69115D01*
G01X730795Y69015D02*
Y69113D01*
G01X730810Y69133D02*
Y69015D01*
G01X730830Y69100D02*
Y69090D01*
G01X730842Y69097D02*
Y69093D01*
G01X730903D02*
Y69097D01*
G01X730906Y69070D02*
Y69065D01*
G01X730918D02*
Y69082D01*
G01X730938Y69057D02*
Y69070D01*
G01X730972D02*
Y69057D01*
G01X730992Y69015D02*
Y69027D01*
G01X731066Y69100D02*
Y69105D01*
G01X731080Y69027D02*
Y69015D01*
G01Y69105D02*
Y69100D01*
G01X731100Y69095D02*
Y69115D01*
G01X731115Y69015D02*
Y69113D01*
G01X731130Y69133D02*
Y69015D01*
G01X731208Y69055D02*
Y69093D01*
G01X731223D02*
Y69055D01*
G01X731267Y69065D02*
Y69080D01*
G01X731289Y69045D02*
Y69065D01*
G01X731304Y69080D02*
Y69042D01*
G01X731324Y69082D02*
Y69065D01*
G01X731336Y69077D02*
Y69082D01*
G01X731339Y69057D02*
Y69050D01*
G01X731400D02*
Y69057D01*
G01X731413Y69047D02*
Y69060D01*
G01X731432Y69055D02*
Y69093D01*
G01X731447D02*
Y69055D01*
G01X731548Y69057D02*
Y69070D01*
G01X731582D02*
Y69057D01*
G01X731602Y69015D02*
Y69133D01*
G01X731617Y69118D02*
Y69082D01*
G01Y69030D02*
Y69068D01*
G01X731678Y69052D02*
Y69045D01*
G01Y69097D02*
Y69103D01*
G01X731693Y69105D02*
Y69095D01*
G01Y69055D02*
Y69042D01*
G01X731713Y69015D02*
Y69133D01*
G01X731728Y69108D02*
Y69015D01*
G01X731816D02*
Y69108D01*
G01X731831Y69133D02*
Y69015D01*
G01X731850D02*
Y69027D01*
G01X731924Y69100D02*
Y69105D01*
G01X731939Y69027D02*
Y69015D01*
G01Y69105D02*
Y69100D01*
G01X731959Y69015D02*
Y69133D01*
G01X731974Y69068D02*
Y69015D01*
G01Y69120D02*
Y69082D01*
G01X732035Y69097D02*
Y69105D01*
G01X732050D02*
Y69095D01*
G01X732070D02*
Y69115D01*
G01X732084Y69015D02*
Y69113D01*
G01X732087Y67322D02*
Y70471D01*
G01X732099Y69133D02*
Y69015D01*
G01X732119D02*
Y69133D01*
G01X732133Y69118D02*
Y69082D01*
G01Y69030D02*
Y69068D01*
G01X732195Y69052D02*
Y69045D01*
G01Y69097D02*
Y69103D01*
G01X732210Y69105D02*
Y69095D01*
G01Y69055D02*
Y69042D01*
G01X732328Y69070D02*
Y69080D01*
G01X732362Y69100D02*
Y69105D01*
G01X732365Y69042D02*
Y69052D01*
G01X732375Y69105D02*
Y69100D01*
G01X732377Y69052D02*
Y69042D01*
G01X732397Y69120D02*
Y69133D01*
G01X732436Y69015D02*
Y69120D01*
G01X732451D02*
Y69015D01*
G01X732490Y69133D02*
Y69120D01*
G01X732907Y67322D02*
Y70471D01*
G01X733071Y67322D02*
Y70471D01*
G01X733858Y67322D02*
Y70471D01*
G01X735236D02*
Y67322D01*
G01X730915Y69047D02*
X730918Y69065D01*
G01X731326Y69100D02*
X731324Y69082D01*
G01X730906Y69065D02*
X730903Y69050D01*
G01X731336Y69082D02*
X731339Y69097D01*
G01X730315Y69093D02*
X730318Y69105D01*
G01X731208Y69093D02*
X731211Y69105D01*
G01X731432Y69093D02*
X731435Y69105D01*
G01X731528Y69045D02*
X731526Y69032D01*
G01X730332Y69103D02*
X730330Y69093D01*
G01X730411Y69042D02*
X730409Y69032D01*
G01X730994Y69105D02*
X730997Y69115D01*
G01X731080Y69100D02*
X731078Y69090D01*
G01X731226Y69103D02*
X731223Y69093D01*
G01X731304Y69042D02*
X731302Y69032D01*
G01X731450Y69103D02*
X731447Y69093D01*
G01X731853Y69105D02*
X731856Y69115D01*
G01X731939Y69100D02*
X731937Y69090D01*
G01X732291Y69105D02*
X732293Y69115D01*
G01X732375Y69100D02*
X732372Y69090D01*
G01X730133D02*
X730135Y69097D01*
G01X730148Y69088D02*
X730150Y69095D01*
G01X730394Y69037D02*
X730396Y69045D01*
G01X730844Y69105D02*
X730842Y69097D01*
G01X730901Y69085D02*
X730903Y69093D01*
G01Y69050D02*
X730901Y69042D01*
G01X731287Y69037D02*
X731289Y69045D01*
G01X731339Y69097D02*
X731341Y69105D01*
G01Y69065D02*
X731339Y69057D01*
G01X731398Y69042D02*
X731400Y69050D01*
G01X731511Y69037D02*
X731513Y69045D01*
G01X731676Y69090D02*
X731678Y69097D01*
G01X731693Y69095D02*
X731691Y69088D01*
G01X731678Y69045D02*
X731676Y69037D01*
G01X731693Y69042D02*
X731691Y69035D01*
G01X732033Y69090D02*
X732035Y69097D01*
G01X732050Y69095D02*
X732047Y69088D01*
G01X732193Y69090D02*
X732195Y69097D01*
G01X732210Y69095D02*
X732207Y69088D01*
G01X732195Y69045D02*
X732193Y69037D01*
G01X732210Y69042D02*
X732207Y69035D01*
G01X732377Y69042D02*
X732375Y69035D01*
G01X733639Y68842D02*
X733750Y69181D01*
G01X733627Y68792D02*
X733578Y68641D01*
G01X729931Y69133D02*
X729892Y69015D01*
G01X733504Y68641D02*
X733701Y69231D01*
G01X729882Y69030D02*
X729917Y69133D01*
G01X731772Y69027D02*
X731809Y69133D01*
G01X731816Y69108D02*
X731781Y69015D01*
G01X730834Y69113D02*
X730830Y69100D01*
G01X730911Y69035D02*
X730915Y69047D01*
G01X731331Y69113D02*
X731326Y69100D01*
G01X731407Y69035D02*
X731413Y69047D01*
G01X730318Y69105D02*
X730322Y69115D01*
G01X731061Y69090D02*
X731066Y69100D01*
G01X731211Y69105D02*
X731216Y69115D01*
G01X731435Y69105D02*
X731440Y69115D01*
G01X731919Y69090D02*
X731924Y69100D01*
G01X732357Y69090D02*
X732362Y69100D01*
G01Y69037D02*
X732365Y69042D01*
G01X731149Y69045D02*
X731181Y69108D01*
G01X731189Y69103D02*
X731157Y69040D01*
G01X732230Y69045D02*
X732261Y69108D01*
G01X732269Y69103D02*
X732237Y69040D01*
G01X730337Y69110D02*
X730332Y69103D01*
G01X730849Y69113D02*
X730844Y69105D01*
G01X730896Y69077D02*
X730901Y69085D01*
G01Y69042D02*
X730896Y69035D01*
G01X731011Y69113D02*
X731007Y69105D01*
G01X731078Y69090D02*
X731073Y69082D01*
G01X731230Y69110D02*
X731226Y69103D01*
G01X731341Y69105D02*
X731346Y69113D01*
G01X731393Y69035D02*
X731398Y69042D01*
G01X731454Y69110D02*
X731450Y69103D01*
G01X731870Y69113D02*
X731865Y69105D01*
G01X731937Y69090D02*
X731932Y69082D01*
G01X732308Y69113D02*
X732303Y69105D01*
G01X732372Y69090D02*
X732367Y69082D01*
G01X732375Y69035D02*
X732370Y69027D01*
G01X730141Y69077D02*
X730148Y69088D01*
G01X730842Y69123D02*
X730834Y69113D01*
G01X730903Y69025D02*
X730911Y69035D01*
G01X731339Y69123D02*
X731331Y69113D01*
G01X731400Y69025D02*
X731407Y69035D01*
G01X731691Y69088D02*
X731683Y69077D01*
G01X731691Y69035D02*
X731683Y69025D01*
G01X732047Y69088D02*
X732040Y69077D01*
G01X732207Y69088D02*
X732200Y69077D01*
G01X732207Y69035D02*
X732200Y69025D01*
G01X730780Y69115D02*
X730795Y69133D01*
G01Y69113D02*
X730780Y69095D01*
G01X731100Y69115D02*
X731115Y69133D01*
G01Y69113D02*
X731100Y69095D01*
G01X732070Y69115D02*
X732084Y69133D01*
G01Y69113D02*
X732070Y69095D01*
G01X730128Y69085D02*
X730133Y69090D01*
G01X730322Y69115D02*
X730332Y69125D01*
G01X730409Y69032D02*
X730399Y69022D01*
G01X730997Y69115D02*
X731007Y69125D01*
G01X731216Y69115D02*
X731226Y69125D01*
G01X731302Y69032D02*
X731292Y69022D01*
G01X731346Y69070D02*
X731341Y69065D01*
G01X731440Y69115D02*
X731450Y69125D01*
G01X731526Y69032D02*
X731516Y69022D01*
G01X731671Y69085D02*
X731676Y69090D01*
G01Y69037D02*
X731671Y69032D01*
G01X731856Y69115D02*
X731865Y69125D01*
G01X732028Y69085D02*
X732033Y69090D01*
G01X732188Y69085D02*
X732193Y69090D01*
G01Y69037D02*
X732188Y69032D01*
G01X732293Y69115D02*
X732303Y69125D01*
G01X732352Y69085D02*
X732357Y69090D01*
G01Y69032D02*
X732362Y69037D01*
G01X730992Y69027D02*
X731061Y69090D01*
G01X731850Y69027D02*
X731919Y69090D01*
G01X731073Y69082D02*
X731011Y69027D01*
G01X731932Y69082D02*
X731870Y69027D01*
G01X731683Y69025D02*
X731673Y69017D01*
G01X732040Y69077D02*
X732030Y69070D01*
G01X732200Y69025D02*
X732190Y69017D01*
G01X732367Y69082D02*
X732357Y69075D01*
G01X730344Y69115D02*
X730337Y69110D01*
G01X730387Y69032D02*
X730394Y69037D01*
G01X730856Y69118D02*
X730849Y69113D01*
G01X730889Y69072D02*
X730896Y69077D01*
G01X730891Y69060D02*
X730906Y69070D01*
G01X730896Y69035D02*
X730889Y69030D01*
G01X731019Y69118D02*
X731011Y69113D01*
G01X731238Y69115D02*
X731230Y69110D01*
G01X731346Y69113D02*
X731354Y69118D01*
G01X731351Y69088D02*
X731336Y69077D01*
G01X731280Y69032D02*
X731287Y69037D01*
G01X731354Y69075D02*
X731346Y69070D01*
G01X731462Y69115D02*
X731454Y69110D01*
G01X731385Y69030D02*
X731393Y69035D01*
G01X731504Y69032D02*
X731511Y69037D01*
G01X731878Y69118D02*
X731870Y69113D01*
G01X732316Y69118D02*
X732308Y69113D01*
G01X732370Y69027D02*
X732362Y69022D01*
G01X730854Y69130D02*
X730842Y69123D01*
G01X730891Y69017D02*
X730903Y69025D01*
G01X731351Y69130D02*
X731339Y69123D01*
G01X731388Y69017D02*
X731400Y69025D01*
G01X730131Y69072D02*
X730141Y69077D01*
G01X730332Y69125D02*
X730342Y69130D01*
G01X730399Y69022D02*
X730389Y69017D01*
G01X731007Y69125D02*
X731017Y69130D01*
G01X731226Y69125D02*
X731235Y69130D01*
G01X731450Y69125D02*
X731459Y69130D01*
G01X731292Y69022D02*
X731282Y69017D01*
G01X731516Y69022D02*
X731506Y69017D01*
G01X731683Y69077D02*
X731678Y69075D01*
G01X731865Y69125D02*
X731875Y69130D01*
G01X732200Y69077D02*
X732195Y69075D01*
G01X732303Y69125D02*
X732313Y69130D01*
G01X732352Y69030D02*
X732357Y69032D01*
G01X732362Y69022D02*
X732352Y69017D01*
G01X730121Y69082D02*
X730128Y69085D01*
G01X730864Y69120D02*
X730856Y69118D01*
G01X730881Y69070D02*
X730889Y69072D01*
G01Y69030D02*
X730881Y69027D01*
G01X731354Y69118D02*
X731361Y69120D01*
G01Y69077D02*
X731354Y69075D01*
G01X731378Y69027D02*
X731385Y69030D01*
G01X731663Y69082D02*
X731671Y69085D01*
G01Y69032D02*
X731663Y69030D01*
G01X732020Y69082D02*
X732028Y69085D01*
G01X732180Y69082D02*
X732188Y69085D01*
G01Y69032D02*
X732180Y69030D01*
G01X732338Y69080D02*
X732352Y69085D01*
G01X712667Y69017D02*
X712657Y69015D01*
G01X711809Y69030D02*
X711819Y69032D01*
G01X711585Y69030D02*
X711594Y69032D01*
G01X711787Y69118D02*
X711777Y69115D01*
G01X711563Y69118D02*
X711553Y69115D01*
G01X710692Y69030D02*
X710702Y69032D01*
G01X710669Y69118D02*
X710659Y69115D01*
G01X712655Y69027D02*
X712667Y69030D01*
G01X712505Y69017D02*
X712493Y69015D01*
G01X712643Y69120D02*
X712631Y69118D01*
G01X712345Y69070D02*
X712333Y69068D01*
G01X711988Y69017D02*
X711976Y69015D01*
G01X711821Y69017D02*
X711809Y69015D01*
G01X711691D02*
X711703Y69017D01*
G01X712205Y69120D02*
X712193Y69118D01*
G01X711597Y69017D02*
X711585Y69015D01*
G01X711678Y69090D02*
X711666Y69088D01*
G01X711774Y69130D02*
X711787Y69133D01*
G01X711194Y69015D02*
X711206Y69017D01*
G01X711678Y69133D02*
X711666Y69130D01*
G01X711194Y69057D02*
X711206Y69060D01*
G01X711550Y69130D02*
X711563Y69133D01*
G01X711346Y69120D02*
X711334Y69118D01*
G01X710704Y69017D02*
X710692Y69015D01*
G01X711181Y69133D02*
X711169Y69130D01*
G01X710657D02*
X710669Y69133D01*
G01X712628Y69130D02*
X712645Y69133D01*
G01X712190Y69130D02*
X712207Y69133D01*
G01X711331Y69130D02*
X711348Y69133D01*
G01X715551Y67322D02*
X712402D01*
G01X707874D02*
X714173D01*
G01X706496D02*
X709646D01*
G01X727559D02*
X733858D01*
G01X726181D02*
X729331D01*
G01X727923Y68641D02*
X727825D01*
G01X727554D02*
X727480D01*
G01X713893D02*
X713819D01*
G01X714311D02*
X714237D01*
G01X708238D02*
X708140D01*
G01X707869D02*
X707795D01*
G01X714188Y68792D02*
X713942D01*
G01X714176Y68842D02*
X713954D01*
G01X710207Y69015D02*
X710187D01*
G01X710354D02*
X710266D01*
G01X710576D02*
X710487D01*
G01X710610D02*
X710596D01*
G01X710692D02*
X710669D01*
G01X710844D02*
X710830D01*
G01X710761D02*
X710746D01*
G01X710918D02*
X710903D01*
G01X711125D02*
X711110D01*
G01X711395D02*
X711307D01*
G01X711444D02*
X711430D01*
G01X711585D02*
X711563D01*
G01X711809D02*
X711787D01*
G01X711976D02*
X711917D01*
G01X712146D02*
X712131D01*
G01X712043D02*
X712028D01*
G01X712096D02*
X712077D01*
G01X712254D02*
X712165D01*
G01X712289D02*
X712274D01*
G01X712414D02*
X712399D01*
G01X712493D02*
X712434D01*
G01X712657D02*
X712638D01*
G01X712766D02*
X712751D01*
G01X710128D02*
X710039D01*
G01X710450D02*
X710468D01*
G01X710374D02*
X710389D01*
G01X711184D02*
X711194D01*
G01X711678D02*
X711691D01*
G01X711196Y69027D02*
X711181D01*
G01X711326D02*
X711395D01*
G01X711676D02*
X711693D01*
G01X712185D02*
X712254D01*
G01X712641D02*
X712655D01*
G01X711978Y69030D02*
X711932D01*
G01X712495D02*
X712448D01*
G01X710054D02*
X710128D01*
G01X710281D02*
X710354D01*
G01X710502D02*
X710576D01*
G01X710669D02*
X710692D01*
G01X711563D02*
X711585D01*
G01X711787D02*
X711809D01*
G01X711161Y69042D02*
X711149D01*
G01X712604D02*
X712616D01*
G01X711828Y69045D02*
X711843D01*
G01X711287Y69057D02*
X711253D01*
G01X711897D02*
X711863D01*
G01X711181D02*
X711194D01*
G01X710711Y69065D02*
X710689D01*
G01X711604D02*
X711582D01*
G01X712333Y69068D02*
X712289D01*
G01X710389D02*
X710431D01*
G01X711932D02*
X711978D01*
G01X712448D02*
X712495D01*
G01X710344Y69070D02*
X710281D01*
G01X710830D02*
X710761D01*
G01X712653D02*
X712643D01*
G01X710118D02*
X710054D01*
G01X711179D02*
X711196D01*
G01X711253D02*
X711287D01*
G01X711863D02*
X711897D01*
G01X711693Y69077D02*
X711676D01*
G01X710689Y69080D02*
X710726D01*
G01X711582D02*
X711619D01*
G01X712643D02*
X712653D01*
G01X710389Y69082D02*
X710436D01*
G01X711932D02*
X711978D01*
G01X712289D02*
X712335D01*
G01X712448D02*
X712495D01*
G01X710054Y69085D02*
X710118D01*
G01X710281D02*
X710344D01*
G01X710761D02*
X710830D01*
G01X711691Y69090D02*
X711678D01*
G01X710726Y69103D02*
X710711D01*
G01X711619D02*
X711604D01*
G01X711843D02*
X711828D01*
G01X711322Y69105D02*
X711309D01*
G01X712180D02*
X712168D01*
G01X712618D02*
X712606D01*
G01X711710D02*
X711722D01*
G01X710354Y69118D02*
X710281D01*
G01X710692D02*
X710669D01*
G01X711585D02*
X711563D01*
G01X711809D02*
X711787D01*
G01X711978D02*
X711932D01*
G01X712495D02*
X712448D01*
G01X710128D02*
X710054D01*
G01X710436Y69120D02*
X710389D01*
G01X710903D02*
X710864D01*
G01X710957D02*
X710918D01*
G01X711196D02*
X711179D01*
G01X711356D02*
X711346D01*
G01X712215D02*
X712205D01*
G01X712335D02*
X712289D01*
G01X712653D02*
X712643D01*
G01X712751D02*
X712712D01*
G01X712805D02*
X712766D01*
G01X711676D02*
X711691D01*
G01X710433Y69133D02*
X710374D01*
G01X711194D02*
X711181D01*
G01X711688D02*
X711678D01*
G01X710039D02*
X710128D01*
G01X710231D02*
X710246D01*
G01X710148D02*
X710163D01*
G01X710266D02*
X710354D01*
G01X710487D02*
X710502D01*
G01X710596D02*
X710610D01*
G01X710669D02*
X710692D01*
G01X710830D02*
X710844D01*
G01X710746D02*
X710761D01*
G01X710864D02*
X710957D01*
G01X711110D02*
X711125D01*
G01X711348D02*
X711358D01*
G01X711430D02*
X711444D01*
G01X711563D02*
X711585D01*
G01X711787D02*
X711809D01*
G01X711917D02*
X711976D01*
G01X712124D02*
X712146D01*
G01X712028D02*
X712050D01*
G01X712207D02*
X712217D01*
G01X712274D02*
X712333D01*
G01X712399D02*
X712414D01*
G01X712434D02*
X712493D01*
G01X712645D02*
X712650D01*
G01X712712D02*
X712805D01*
G01X708140Y69231D02*
X708238D01*
G01X707795D02*
X707869D01*
G01X714016D02*
X714114D01*
G01X727825D02*
X727923D01*
G01X727480D02*
X727554D01*
G01X733858Y70471D02*
X727559D01*
G01X729331D02*
X726181D01*
G01X714173D02*
X707874D01*
G01X709646D02*
X706496D01*
G01X712402D02*
X715551D01*
G01X712650Y69133D02*
X712667Y69130D01*
G01X711358Y69133D02*
X711373Y69130D01*
G01X712217Y69133D02*
X712232Y69130D01*
G01X712667Y69068D02*
X712653Y69070D01*
G01X710669Y69015D02*
X710657Y69017D01*
G01X710446Y69130D02*
X710433Y69133D01*
G01X711171Y69017D02*
X711184Y69015D01*
G01X710692Y69133D02*
X710704Y69130D01*
G01X711169Y69060D02*
X711181Y69057D01*
G01X711563Y69015D02*
X711550Y69017D01*
G01X711666D02*
X711678Y69015D01*
G01X711206Y69130D02*
X711194Y69133D01*
G01X711787Y69015D02*
X711774Y69017D01*
G01X711368Y69118D02*
X711356Y69120D01*
G01X711703Y69088D02*
X711691Y69090D01*
G01X711585Y69133D02*
X711597Y69130D01*
G01X711700D02*
X711688Y69133D01*
G01X711809D02*
X711821Y69130D01*
G01X711976Y69133D02*
X711988Y69130D01*
G01X712628Y69030D02*
X712641Y69027D01*
G01X712227Y69118D02*
X712215Y69120D01*
G01X712333Y69133D02*
X712345Y69130D01*
G01X712493Y69133D02*
X712505Y69130D01*
G01X712665Y69118D02*
X712653Y69120D01*
G01X711777Y69032D02*
X711787Y69030D01*
G01X711594Y69115D02*
X711585Y69118D01*
G01X712638Y69015D02*
X712628Y69017D01*
G01X710659Y69032D02*
X710669Y69030D01*
G01X710702Y69115D02*
X710692Y69118D01*
G01X711553Y69032D02*
X711563Y69030D01*
G01X711819Y69115D02*
X711809Y69118D01*
G01X710443D02*
X710436Y69120D01*
G01X711181Y69027D02*
X711174Y69030D01*
G01X711171Y69072D02*
X711179Y69070D01*
G01X711204Y69118D02*
X711196Y69120D01*
G01X711669Y69030D02*
X711676Y69027D01*
G01X711700Y69075D02*
X711693Y69077D01*
G01X711691Y69120D02*
X711698Y69118D01*
G01X711978Y69068D02*
X711986Y69065D01*
G01Y69115D02*
X711978Y69118D01*
G01X712343D02*
X712335Y69120D01*
G01X712495Y69068D02*
X712503Y69065D01*
G01Y69115D02*
X712495Y69118D01*
G01X712672Y69075D02*
X712685Y69070D01*
G01X710657Y69017D02*
X710647Y69022D01*
G01X710704Y69130D02*
X710714Y69125D01*
G01X711550Y69017D02*
X711541Y69022D01*
G01X711373Y69130D02*
X711383Y69125D01*
G01X711774Y69017D02*
X711765Y69022D01*
G01X711597Y69130D02*
X711607Y69125D01*
G01X711821Y69130D02*
X711831Y69125D01*
G01X711993Y69075D02*
X711998Y69072D01*
G01X712232Y69130D02*
X712242Y69125D01*
G01X712510Y69075D02*
X712515Y69072D01*
G01X712628Y69017D02*
X712618Y69022D01*
G01X712623Y69032D02*
X712628Y69030D01*
G01X712667Y69130D02*
X712677Y69125D01*
G01X711159Y69025D02*
X711171Y69017D01*
G01X711157Y69068D02*
X711169Y69060D01*
G01X711218Y69123D02*
X711206Y69130D01*
G01X711654Y69025D02*
X711666Y69017D01*
G01X711715Y69080D02*
X711703Y69088D01*
G01X711713Y69123D02*
X711700Y69130D01*
G01X710652Y69037D02*
X710659Y69032D01*
G01X710709Y69110D02*
X710702Y69115D01*
G01X711174Y69030D02*
X711167Y69035D01*
G01X711164Y69077D02*
X711171Y69072D01*
G01X711211Y69113D02*
X711204Y69118D01*
G01X711472Y69040D02*
X711464Y69045D01*
G01X711376Y69113D02*
X711368Y69118D01*
G01X711545Y69037D02*
X711553Y69032D01*
G01X711496Y69108D02*
X711504Y69103D01*
G01X711661Y69035D02*
X711669Y69030D01*
G01X711602Y69110D02*
X711594Y69115D01*
G01X711708Y69070D02*
X711700Y69075D01*
G01X711769Y69037D02*
X711777Y69032D01*
G01X711698Y69118D02*
X711706Y69113D01*
G01X711826Y69110D02*
X711819Y69115D01*
G01X712234Y69113D02*
X712227Y69118D01*
G01X712552Y69040D02*
X712544Y69045D01*
G01X712618Y69022D02*
X712611Y69027D01*
G01X712576Y69108D02*
X712584Y69103D01*
G01X712675Y69062D02*
X712667Y69068D01*
G01X712672Y69113D02*
X712665Y69118D01*
G01X710456Y69123D02*
X710446Y69130D01*
G01X711988D02*
X711998Y69123D01*
G01X712345Y69130D02*
X712355Y69123D01*
G01X712505Y69130D02*
X712515Y69123D01*
G01X711986Y69065D02*
X711991Y69060D01*
G01Y69110D02*
X711986Y69115D01*
G01X712503Y69065D02*
X712507Y69060D01*
G01Y69110D02*
X712503Y69115D01*
G01X710448Y69113D02*
X710443Y69118D01*
G01X710647Y69022D02*
X710637Y69032D01*
G01X710714Y69125D02*
X710724Y69115D01*
G01X711383Y69125D02*
X711393Y69115D01*
G01X711541Y69022D02*
X711531Y69032D01*
G01X711607Y69125D02*
X711617Y69115D01*
G01X711713Y69065D02*
X711708Y69070D01*
G01X711765Y69022D02*
X711755Y69032D01*
G01X711722Y69072D02*
X711715Y69080D01*
G01X711831Y69125D02*
X711841Y69115D01*
G01X712242Y69125D02*
X712252Y69115D01*
G01X712348Y69113D02*
X712343Y69118D01*
G01X712618Y69037D02*
X712623Y69032D01*
G01X712677Y69125D02*
X712687Y69115D01*
G01X710463Y69113D02*
X710456Y69123D01*
G01X711152Y69035D02*
X711159Y69025D01*
G01X711149Y69077D02*
X711157Y69068D01*
G01X711226Y69113D02*
X711218Y69123D01*
G01X711646Y69035D02*
X711654Y69025D01*
G01X711720Y69113D02*
X711713Y69123D01*
G01X711998Y69072D02*
X712006Y69062D01*
G01X711998Y69123D02*
X712006Y69113D01*
G01X712355Y69123D02*
X712362Y69113D01*
G01X712515Y69072D02*
X712522Y69062D01*
G01X712515Y69123D02*
X712522Y69113D01*
G01X710647Y69045D02*
X710652Y69037D01*
G01X711167Y69035D02*
X711161Y69042D01*
G01X711159Y69085D02*
X711164Y69077D01*
G01X711216Y69105D02*
X711211Y69113D01*
G01X711381Y69105D02*
X711376Y69113D01*
G01X711541Y69045D02*
X711545Y69037D01*
G01X711656Y69042D02*
X711661Y69035D01*
G01X711706Y69113D02*
X711710Y69105D01*
G01X711765Y69045D02*
X711769Y69037D01*
G01X712239Y69105D02*
X712234Y69113D01*
G01X712611Y69027D02*
X712606Y69035D01*
G01X712685Y69070D02*
X712690Y69062D01*
G01X712677Y69105D02*
X712672Y69113D01*
G01X708140Y68641D02*
X707956Y68930D01*
G01X727825Y68641D02*
X727641Y68930D01*
G01X708017Y68992D02*
X708238Y68641D01*
G01X727702Y68992D02*
X727923Y68641D01*
G01X710637Y69032D02*
X710633Y69042D01*
G01X711531Y69032D02*
X711526Y69042D01*
G01X711755Y69032D02*
X711750Y69042D01*
G01X712616D02*
X712618Y69037D01*
G01X712680Y69052D02*
X712675Y69062D01*
G01X711144Y69090D02*
X711149Y69077D01*
G01X711230Y69100D02*
X711226Y69113D01*
G01X711641Y69047D02*
X711646Y69035D01*
G01X711728Y69060D02*
X711722Y69072D01*
G01X710468Y69015D02*
X710446Y69072D01*
G01X710431Y69068D02*
X710450Y69015D01*
G01X712077D02*
X712043Y69108D01*
G01X712050Y69133D02*
X712087Y69027D01*
G01X710163Y69133D02*
X710197Y69030D01*
G01X710187Y69015D02*
X710148Y69133D01*
G01X714114Y69231D02*
X714311Y68641D01*
G01X710450Y69105D02*
X710448Y69113D01*
G01X710465Y69105D02*
X710463Y69113D01*
G01X710711Y69103D02*
X710709Y69110D01*
G01X711149Y69042D02*
X711152Y69035D01*
G01X711157Y69093D02*
X711159Y69085D01*
G01X711218Y69097D02*
X711216Y69105D01*
G01X711604Y69103D02*
X711602Y69110D01*
G01X711654Y69050D02*
X711656Y69042D01*
G01X711715Y69057D02*
X711713Y69065D01*
G01X711722Y69105D02*
X711720Y69113D01*
G01X711828Y69103D02*
X711826Y69110D01*
G01X711991Y69060D02*
X711993Y69052D01*
G01X712006Y69062D02*
X712008Y69055D01*
G01X711993Y69103D02*
X711991Y69110D01*
G01X712006Y69113D02*
X712008Y69105D01*
G01X712350D02*
X712348Y69113D01*
G01X712362D02*
X712365Y69105D01*
G01X712507Y69060D02*
X712510Y69052D01*
G01X712522Y69062D02*
X712525Y69055D01*
G01X712510Y69103D02*
X712507Y69110D01*
G01X712522Y69113D02*
X712525Y69105D01*
G01X712606Y69035D02*
X712604Y69042D01*
G01X714237Y68641D02*
X714188Y68792D01*
G01X714065Y69181D02*
X714176Y68842D01*
G01X710645Y69055D02*
X710647Y69045D01*
G01X711393Y69115D02*
X711395Y69105D01*
G01X711538Y69055D02*
X711541Y69045D01*
G01X711762Y69055D02*
X711765Y69045D01*
G01X712252Y69115D02*
X712254Y69105D01*
G01X712690Y69062D02*
X712692Y69052D01*
G01X712687Y69115D02*
X712690Y69105D01*
G01X710633Y69042D02*
X710630Y69055D01*
G01X710724Y69115D02*
X710726Y69103D01*
G01X711526Y69042D02*
X711523Y69055D01*
G01X711617Y69115D02*
X711619Y69103D01*
G01X711750Y69042D02*
X711747Y69055D01*
G01X711841Y69115D02*
X711843Y69103D01*
G01X711233Y69082D02*
X711230Y69100D01*
G01X711639Y69065D02*
X711641Y69047D01*
G01X706496Y70471D02*
Y67322D01*
G01X707795Y68641D02*
Y69231D01*
G01X707869Y68842D02*
Y68641D01*
G01Y69231D02*
Y68942D01*
G01X707874Y70471D02*
Y67322D01*
G01X708661D02*
Y70471D01*
G01X708826D02*
Y67322D01*
G01X709646D02*
Y70471D01*
G01X710039Y69015D02*
Y69133D01*
G01X710054Y69070D02*
Y69030D01*
G01Y69118D02*
Y69085D01*
G01X710118D02*
Y69070D01*
G01X710128Y69133D02*
Y69118D01*
G01Y69030D02*
Y69015D01*
G01X710266D02*
Y69133D01*
G01X710281Y69070D02*
Y69030D01*
G01Y69118D02*
Y69085D01*
G01X710344D02*
Y69070D01*
G01X710354Y69133D02*
Y69118D01*
G01Y69030D02*
Y69015D01*
G01X710374Y69133D02*
Y69015D01*
G01X710389Y69120D02*
Y69082D01*
G01Y69015D02*
Y69068D01*
G01X710450Y69097D02*
Y69105D01*
G01X710465Y69095D02*
Y69105D01*
G01X710487Y69015D02*
Y69133D01*
G01X710502D02*
Y69030D01*
G01X710576D02*
Y69015D01*
G01X710596D02*
Y69133D01*
G01X710610D02*
Y69015D01*
G01X710630Y69055D02*
Y69093D01*
G01X710645D02*
Y69055D01*
G01X710689Y69065D02*
Y69080D01*
G01X710711Y69045D02*
Y69065D01*
G01X710726Y69080D02*
Y69042D01*
G01X710746Y69015D02*
Y69133D01*
G01X710761Y69070D02*
Y69015D01*
G01Y69133D02*
Y69085D01*
G01X710830Y69015D02*
Y69070D01*
G01Y69085D02*
Y69133D01*
G01X710844D02*
Y69015D01*
G01X710864Y69120D02*
Y69133D01*
G01X710903Y69015D02*
Y69120D01*
G01X710918D02*
Y69015D01*
G01X710957Y69133D02*
Y69120D01*
G01X711095Y69095D02*
Y69115D01*
G01X711110Y69015D02*
Y69113D01*
G01X711125Y69133D02*
Y69015D01*
G01X711144Y69100D02*
Y69090D01*
G01X711157Y69097D02*
Y69093D01*
G01X711218D02*
Y69097D01*
G01X711220Y69070D02*
Y69065D01*
G01X711233D02*
Y69082D01*
G01X711253Y69057D02*
Y69070D01*
G01X711287D02*
Y69057D01*
G01X711307Y69015D02*
Y69027D01*
G01X711381Y69100D02*
Y69105D01*
G01X711395Y69027D02*
Y69015D01*
G01Y69105D02*
Y69100D01*
G01X711415Y69095D02*
Y69115D01*
G01X711430Y69015D02*
Y69113D01*
G01X711444Y69133D02*
Y69015D01*
G01X711523Y69055D02*
Y69093D01*
G01X711538D02*
Y69055D01*
G01X711582Y69065D02*
Y69080D01*
G01X711604Y69045D02*
Y69065D01*
G01X711619Y69080D02*
Y69042D01*
G01X711639Y69082D02*
Y69065D01*
G01X711651Y69077D02*
Y69082D01*
G01X711654Y69057D02*
Y69050D01*
G01X711715D02*
Y69057D01*
G01X711728Y69047D02*
Y69060D01*
G01X711747Y69055D02*
Y69093D01*
G01X711762D02*
Y69055D01*
G01X711863Y69057D02*
Y69070D01*
G01X711897D02*
Y69057D01*
G01X711917Y69015D02*
Y69133D01*
G01X711932Y69118D02*
Y69082D01*
G01Y69030D02*
Y69068D01*
G01X711993Y69052D02*
Y69045D01*
G01Y69097D02*
Y69103D01*
G01X712008Y69105D02*
Y69095D01*
G01Y69055D02*
Y69042D01*
G01X712028Y69015D02*
Y69133D01*
G01X712043Y69108D02*
Y69015D01*
G01X712131D02*
Y69108D01*
G01X712146Y69133D02*
Y69015D01*
G01X712165D02*
Y69027D01*
G01X712239Y69100D02*
Y69105D01*
G01X712254Y69027D02*
Y69015D01*
G01Y69105D02*
Y69100D01*
G01X712274Y69015D02*
Y69133D01*
G01X712289Y69068D02*
Y69015D01*
G01Y69120D02*
Y69082D01*
G01X712350Y69097D02*
Y69105D01*
G01X712365D02*
Y69095D01*
G01X712385D02*
Y69115D01*
G01X712399Y69015D02*
Y69113D01*
G01X712402Y67322D02*
Y70471D01*
G01X712414Y69133D02*
Y69015D01*
G01X712434D02*
Y69133D01*
G01X712448Y69118D02*
Y69082D01*
G01Y69030D02*
Y69068D01*
G01X712510Y69052D02*
Y69045D01*
G01Y69097D02*
Y69103D01*
G01X712525Y69105D02*
Y69095D01*
G01Y69055D02*
Y69042D01*
G01X712643Y69070D02*
Y69080D01*
G01X712677Y69100D02*
Y69105D01*
G01X712680Y69042D02*
Y69052D01*
G01X712690Y69105D02*
Y69100D01*
G01X712692Y69052D02*
Y69042D01*
G01X712712Y69120D02*
Y69133D01*
G01X712751Y69015D02*
Y69120D01*
G01X712766D02*
Y69015D01*
G01X712805Y69133D02*
Y69120D01*
G01X713222Y67322D02*
Y70471D01*
G01X713386Y67322D02*
Y70471D01*
G01X714173Y67322D02*
Y70471D01*
G01X715551D02*
Y67322D01*
G01X726181Y70471D02*
Y67322D01*
G01X727480Y68641D02*
Y69231D01*
G01X727554Y68842D02*
Y68641D01*
G01Y69231D02*
Y68942D01*
G01X727559Y70471D02*
Y67322D01*
G01X728346D02*
Y70471D01*
G01X728511D02*
Y67322D01*
G01X711230Y69047D02*
X711233Y69065D01*
G01X711641Y69100D02*
X711639Y69082D01*
G01X711220Y69065D02*
X711218Y69050D01*
G01X711651Y69082D02*
X711654Y69097D01*
G01X710630Y69093D02*
X710633Y69105D01*
G01X711523Y69093D02*
X711526Y69105D01*
G01X711747Y69093D02*
X711750Y69105D01*
G01X711843Y69045D02*
X711841Y69032D01*
G01X710647Y69103D02*
X710645Y69093D01*
G01X710726Y69042D02*
X710724Y69032D01*
G01X711309Y69105D02*
X711312Y69115D01*
G01X711395Y69100D02*
X711393Y69090D01*
G01X711541Y69103D02*
X711538Y69093D01*
G01X711619Y69042D02*
X711617Y69032D01*
G01X711765Y69103D02*
X711762Y69093D01*
G01X712168Y69105D02*
X712170Y69115D01*
G01X712254Y69100D02*
X712252Y69090D01*
G01X712606Y69105D02*
X712608Y69115D01*
G01X712690Y69100D02*
X712687Y69090D01*
G01X710448D02*
X710450Y69097D01*
G01X710463Y69088D02*
X710465Y69095D01*
G01X710709Y69037D02*
X710711Y69045D01*
G01X711159Y69105D02*
X711157Y69097D01*
G01X711216Y69085D02*
X711218Y69093D01*
G01Y69050D02*
X711216Y69042D01*
G01X711602Y69037D02*
X711604Y69045D01*
G01X711654Y69097D02*
X711656Y69105D01*
G01Y69065D02*
X711654Y69057D01*
G01X711713Y69042D02*
X711715Y69050D01*
G01X711826Y69037D02*
X711828Y69045D01*
G01X711991Y69090D02*
X711993Y69097D01*
G01X712008Y69095D02*
X712006Y69088D01*
G01X711993Y69045D02*
X711991Y69037D01*
G01X712008Y69042D02*
X712006Y69035D01*
G01X712348Y69090D02*
X712350Y69097D01*
G01X712365Y69095D02*
X712362Y69088D01*
G01X712507Y69090D02*
X712510Y69097D01*
G01X712525Y69095D02*
X712522Y69088D01*
G01X712510Y69045D02*
X712507Y69037D01*
G01X712525Y69042D02*
X712522Y69035D01*
G01X712692Y69042D02*
X712690Y69035D01*
G01X713954Y68842D02*
X714065Y69181D01*
G01X713942Y68792D02*
X713893Y68641D01*
G01X710246Y69133D02*
X710207Y69015D01*
G01X713819Y68641D02*
X714016Y69231D01*
G01X710197Y69030D02*
X710231Y69133D01*
G01X712087Y69027D02*
X712124Y69133D01*
G01X712131Y69108D02*
X712096Y69015D01*
G01X711149Y69113D02*
X711144Y69100D01*
G01X711226Y69035D02*
X711230Y69047D01*
G01X711646Y69113D02*
X711641Y69100D01*
G01X711722Y69035D02*
X711728Y69047D01*
G01X710633Y69105D02*
X710637Y69115D01*
G01X711376Y69090D02*
X711381Y69100D01*
G01X711526Y69105D02*
X711531Y69115D01*
G01X711750Y69105D02*
X711755Y69115D01*
G01X712234Y69090D02*
X712239Y69100D01*
G01X712672Y69090D02*
X712677Y69100D01*
G01Y69037D02*
X712680Y69042D01*
G01X711464Y69045D02*
X711496Y69108D01*
G01X711504Y69103D02*
X711472Y69040D01*
G01X712544Y69045D02*
X712576Y69108D01*
G01X712584Y69103D02*
X712552Y69040D01*
G01X710652Y69110D02*
X710647Y69103D01*
G01X711164Y69113D02*
X711159Y69105D01*
G01X711211Y69077D02*
X711216Y69085D01*
G01Y69042D02*
X711211Y69035D01*
G01X711326Y69113D02*
X711322Y69105D01*
G01X711393Y69090D02*
X711388Y69082D01*
G01X711545Y69110D02*
X711541Y69103D01*
G01X711656Y69105D02*
X711661Y69113D01*
G01X711708Y69035D02*
X711713Y69042D01*
G01X711769Y69110D02*
X711765Y69103D01*
G01X712185Y69113D02*
X712180Y69105D01*
G01X712252Y69090D02*
X712247Y69082D01*
G01X712623Y69113D02*
X712618Y69105D01*
G01X712687Y69090D02*
X712682Y69082D01*
G01X712690Y69035D02*
X712685Y69027D01*
G01X710456Y69077D02*
X710463Y69088D01*
G01X711157Y69123D02*
X711149Y69113D01*
G01X711218Y69025D02*
X711226Y69035D01*
G01X711654Y69123D02*
X711646Y69113D01*
G01X711715Y69025D02*
X711722Y69035D01*
G01X712006Y69088D02*
X711998Y69077D01*
G01X712006Y69035D02*
X711998Y69025D01*
G01X712362Y69088D02*
X712355Y69077D01*
G01X712522Y69088D02*
X712515Y69077D01*
G01X712522Y69035D02*
X712515Y69025D01*
G01X711095Y69115D02*
X711110Y69133D01*
G01Y69113D02*
X711095Y69095D01*
G01X711415Y69115D02*
X711430Y69133D01*
G01Y69113D02*
X711415Y69095D01*
G01X712385Y69115D02*
X712399Y69133D01*
G01Y69113D02*
X712385Y69095D01*
G01X708238Y69231D02*
X708017Y68992D01*
G01X727923Y69231D02*
X727702Y68992D01*
G01X707869Y68942D02*
X708140Y69231D01*
G01X727554Y68942D02*
X727825Y69231D01*
G01X707956Y68930D02*
X707869Y68842D01*
G01X710443Y69085D02*
X710448Y69090D01*
G01X710637Y69115D02*
X710647Y69125D01*
G01X710724Y69032D02*
X710714Y69022D01*
G01X711312Y69115D02*
X711322Y69125D01*
G01X711531Y69115D02*
X711541Y69125D01*
G01X711617Y69032D02*
X711607Y69022D01*
G01X711661Y69070D02*
X711656Y69065D01*
G01X711755Y69115D02*
X711765Y69125D01*
G01X711841Y69032D02*
X711831Y69022D01*
G01X711986Y69085D02*
X711991Y69090D01*
G01Y69037D02*
X711986Y69032D01*
G01X712170Y69115D02*
X712180Y69125D01*
G01X712343Y69085D02*
X712348Y69090D01*
G01X712503Y69085D02*
X712507Y69090D01*
G01Y69037D02*
X712503Y69032D01*
G01X712608Y69115D02*
X712618Y69125D01*
G01X712667Y69085D02*
X712672Y69090D01*
G01Y69032D02*
X712677Y69037D01*
G01X727641Y68930D02*
X727554Y68842D01*
G01X711307Y69027D02*
X711376Y69090D01*
G01X712165Y69027D02*
X712234Y69090D01*
G01X711388Y69082D02*
X711326Y69027D01*
G01X712247Y69082D02*
X712185Y69027D01*
G01X711998Y69025D02*
X711988Y69017D01*
G01X712355Y69077D02*
X712345Y69070D01*
G01X712515Y69025D02*
X712505Y69017D01*
G01X712682Y69082D02*
X712672Y69075D01*
G01X710659Y69115D02*
X710652Y69110D01*
G01X710702Y69032D02*
X710709Y69037D01*
G01X711171Y69118D02*
X711164Y69113D01*
G01X711204Y69072D02*
X711211Y69077D01*
G01X711206Y69060D02*
X711220Y69070D01*
G01X711211Y69035D02*
X711204Y69030D01*
G01X711334Y69118D02*
X711326Y69113D01*
G01X711553Y69115D02*
X711545Y69110D01*
G01X711661Y69113D02*
X711669Y69118D01*
G01X711666Y69088D02*
X711651Y69077D01*
G01X711594Y69032D02*
X711602Y69037D01*
G01X711669Y69075D02*
X711661Y69070D01*
G01X711777Y69115D02*
X711769Y69110D01*
G01X711700Y69030D02*
X711708Y69035D01*
G01X711819Y69032D02*
X711826Y69037D01*
G01X712193Y69118D02*
X712185Y69113D01*
G01X712631Y69118D02*
X712623Y69113D01*
G01X712685Y69027D02*
X712677Y69022D01*
G01X711169Y69130D02*
X711157Y69123D01*
G01X711206Y69017D02*
X711218Y69025D01*
G01X711666Y69130D02*
X711654Y69123D01*
G01X711703Y69017D02*
X711715Y69025D01*
G01X710446Y69072D02*
X710456Y69077D01*
G01X710647Y69125D02*
X710657Y69130D01*
G01X710714Y69022D02*
X710704Y69017D01*
G01X711322Y69125D02*
X711331Y69130D01*
G01X711541Y69125D02*
X711550Y69130D01*
G01X711765Y69125D02*
X711774Y69130D01*
G01X711607Y69022D02*
X711597Y69017D01*
G01X711831Y69022D02*
X711821Y69017D01*
G01X711998Y69077D02*
X711993Y69075D01*
G01X712180Y69125D02*
X712190Y69130D01*
G01X712515Y69077D02*
X712510Y69075D01*
G01X712618Y69125D02*
X712628Y69130D01*
G01X712667Y69030D02*
X712672Y69032D01*
G01X712677Y69022D02*
X712667Y69017D01*
G01X710436Y69082D02*
X710443Y69085D01*
G01X711179Y69120D02*
X711171Y69118D01*
G01X711196Y69070D02*
X711204Y69072D01*
G01Y69030D02*
X711196Y69027D01*
G01X711669Y69118D02*
X711676Y69120D01*
G01Y69077D02*
X711669Y69075D01*
G01X711693Y69027D02*
X711700Y69030D01*
G01X711978Y69082D02*
X711986Y69085D01*
G01Y69032D02*
X711978Y69030D01*
G01X712335Y69082D02*
X712343Y69085D01*
G01X712495Y69082D02*
X712503Y69085D01*
G01Y69032D02*
X712495Y69030D01*
G01X712653Y69080D02*
X712667Y69085D01*
G01X855351Y261502D02*
G03I-68612J0D01*
G01X732948Y474684D02*
Y507353D01*
G01X737869Y514054D02*
Y474684D01*
G01D02*
X732948D01*
G01X710802Y478872D02*
Y474684D01*
G01X717364D02*
Y478872D01*
G01X721465D02*
Y474684D01*
G01D02*
X717364D01*
G01X705881Y503164D02*
Y504840D01*
G01X710802Y503164D02*
X709982Y499814D01*
G01D02*
X708342Y497301D01*
G01X728027Y508190D02*
X732948Y514054D01*
G01Y507353D02*
X728027Y501489D01*
G01X710802Y504840D02*
Y503164D01*
G01X728027Y501489D02*
Y508190D01*
G01X706701Y511541D02*
X709982Y508190D01*
G01D02*
X710802Y504840D01*
G01X717364Y478872D02*
X721465D01*
G01X732948Y514054D02*
X737869D01*
G01X729035Y892519D02*
Y883464D01*
G01X730020D02*
Y892519D01*
G01X732185D02*
Y883464D01*
G01X733169D02*
Y892519D01*
G01X735335D02*
Y883464D01*
G01X736319D02*
Y892519D01*
G01X738484Y883464D02*
X736319D01*
G01X732185D02*
X730020D01*
G01X735335D02*
X733169D01*
G01X713780Y879920D02*
Y1032536D01*
G01Y879920D02*
Y1033312D01*
G01X712377Y864841D02*
X711929Y864172D01*
G01X711722D02*
X712274Y864981D01*
G01X713780Y866062D02*
X715076Y867802D01*
G01X721194Y882075D02*
X720588Y880944D01*
G01X722408Y882075D02*
X721802Y880944D01*
G01X721018Y882075D02*
X720588Y881279D01*
G01X722231Y882075D02*
X721802Y881279D01*
G01X723369Y882410D02*
X723470Y882912D01*
G01X723344Y882242D02*
X723117Y881111D01*
G01X723622Y882912D02*
X723218Y880944D01*
G01X704823Y883464D02*
Y892519D01*
G01X706988D02*
Y883464D01*
G01X709449Y892519D02*
Y875983D01*
G01Y892519D02*
Y875983D01*
G01X712274Y864981D02*
Y865826D01*
G01X712480D02*
Y864981D01*
G01X713780Y866062D02*
Y907558D01*
G01X718110Y892519D02*
Y875983D01*
G01Y892519D02*
Y875983D01*
G01X720183Y882075D02*
Y882326D01*
G01X720436D02*
Y882912D01*
G01Y880944D02*
Y882075D01*
G01X720571Y883464D02*
Y892519D01*
G01X720588Y882912D02*
Y882326D01*
G01Y881279D02*
Y882075D01*
G01X721194Y882326D02*
Y882075D01*
G01X721397D02*
Y882326D01*
G01X721650D02*
Y882912D01*
G01Y880944D02*
Y882075D01*
G01X721802Y882912D02*
Y882326D01*
G01Y881279D02*
Y882075D01*
G01X722408Y882326D02*
Y882075D01*
G01X722736Y892519D02*
Y883464D01*
G01X723720D02*
Y892519D01*
G01X725886D02*
Y883464D01*
G01X726870D02*
Y892519D01*
G01X723015Y880944D02*
X722611Y882912D01*
G01X723117Y881111D02*
X722889Y882242D01*
G01X722763Y882912D02*
X722864Y882410D01*
G01X713780Y866062D02*
X712559Y867802D01*
G01X712480Y864981D02*
X713031Y864172D01*
G01X712825D02*
X712377Y864841D01*
G01X711929Y864172D02*
X711722D01*
G01X713031D02*
X712825D01*
G01X712274Y865826D02*
X712480D01*
G01X723218Y880944D02*
X723015D01*
G01X721802D02*
X721650D01*
G01X720588D02*
X720436D01*
G01X721650Y882075D02*
X721397D01*
G01X720436D02*
X720183D01*
G01X721802D02*
X722231D01*
G01X720588D02*
X721018D01*
G01X722889Y882242D02*
X723344D01*
G01X721802Y882326D02*
X722408D01*
G01X721397D02*
X721650D01*
G01X720588D02*
X721194D01*
G01X720183D02*
X720436D01*
G01X722864Y882410D02*
X723369D01*
G01X723470Y882912D02*
X723622D01*
G01X722611D02*
X722763D01*
G01X721650D02*
X721802D01*
G01X720436D02*
X720588D01*
G01X729035Y883464D02*
X726870D01*
G01X722736D02*
X720571D01*
G01X725886D02*
X723720D01*
G01X706988D02*
X704823D01*
G01X709449Y875983D02*
G03X718110I4331J0D01*
G01X709449D02*
G03X718110I4331J0D01*
G01X730020Y892519D02*
X732185D01*
G01X733169D02*
X735335D01*
G01X736319D02*
X738484D01*
G01X718110Y896456D02*
Y941149D01*
G01X709449Y896456D02*
Y941149D01*
G01X710784Y892519D02*
X711850Y893267D01*
G01X711575Y898030D02*
X710641Y896683D01*
G01X710476Y896964D02*
X711245Y898030D01*
G01X710476Y896459D02*
X709707Y895393D01*
G01X709377D02*
X710311Y896683D01*
G01X722047Y897637D02*
X718110Y892519D01*
G01D02*
X722047Y897637D01*
G01X705512D02*
X709449Y892519D01*
G01X705512Y897637D02*
X709449Y892519D01*
G01X710641Y896683D02*
X711575Y895393D01*
G01X711245D02*
X710476Y896459D01*
G01X709707Y898030D02*
X710476Y896964D01*
G01X710311Y896683D02*
X709377Y898030D01*
G01X710784Y892519D02*
X711850Y891724D01*
G01X716768Y892519D02*
X710784D01*
G01X704823D02*
X706988D01*
G01X718110D02*
X860236D01*
G01X720571D02*
X722736D01*
G01X723720D02*
X725886D01*
G01X726870D02*
X729035D01*
G01X711575Y895393D02*
X711245D01*
G01X709707D02*
X709377D01*
G01X722047Y897637D02*
X856299D01*
G01X722047D02*
X856299D01*
G01X709377Y898030D02*
X709707D01*
G01X711245D02*
X711575D01*
G01X718110Y937212D02*
X737795D01*
G01D02*
X713780D01*
G01Y1029375D02*
X961811D01*
G01X730985Y2159695D02*
X731698Y2161596D01*
X733837Y2162547D01*
X735976Y2161596D01*
X736689Y2159695D01*
X735976Y2157793D01*
X735263Y2156843D01*
X733837Y2155892D01*
X732411Y2156843D01*
X731698Y2157793D01*
X730985Y2159695D01*
Y2163497D01*
X731698Y2165399D01*
X732411Y2166349D01*
X733837Y2167300D01*
X735263Y2166349D01*
X735976Y2165399D01*
G01X769779Y-268979D02*
Y-269701D01*
G01Y-271866D02*
Y-277640D01*
G01X760522Y-276919D02*
X759547Y-275475D01*
G01X763932Y-270423D02*
X763445Y-269701D01*
X762470Y-268979D01*
X761496D01*
X760522Y-269701D01*
X760034Y-270423D01*
Y-271144D01*
X760522Y-271866D01*
G01D02*
X763445Y-274031D01*
X763932Y-274753D01*
Y-276197D01*
X763445Y-276919D01*
X762470Y-277640D01*
X761496D01*
X760522Y-276919D01*
G01X746393Y-277640D02*
Y-268979D01*
G01X744931Y-272588D02*
X747854D01*
G01X764173Y-1970D02*
X766142D01*
G01X762598D02*
X766535D01*
G01X775984Y1968D02*
X764173D01*
G01X766535D02*
X762598D01*
G01X764975Y-558D02*
X763392Y-42D01*
G01X765210Y-616D02*
X765913Y-845D01*
G01Y-1190D02*
X763157Y-271D01*
G01X762598Y1968D02*
Y-1970D01*
G01X763157Y-271D02*
Y188D01*
G01X764173Y1968D02*
Y-1970D01*
G01X764975Y475D02*
Y-558D01*
G01X765210Y532D02*
Y-616D01*
G01X765913Y-845D02*
Y-1190D01*
G01Y1106D02*
Y762D01*
G01X766535Y-1970D02*
Y1968D01*
G01X763157Y188D02*
X765913Y1106D01*
G01X763392Y-42D02*
X764975Y475D01*
G01X765913Y762D02*
X765210Y532D01*
G01X766142Y-1970D02*
G03X774016I3937J0D01*
G01X752037Y69017D02*
X752028Y69015D01*
G01X751179Y69030D02*
X751189Y69032D01*
G01X750955Y69030D02*
X750965Y69032D01*
G01X751157Y69118D02*
X751147Y69115D01*
G01X750933Y69118D02*
X750923Y69115D01*
G01X750062Y69030D02*
X750072Y69032D01*
G01X750039Y69118D02*
X750030Y69115D01*
G01X752025Y69027D02*
X752037Y69030D01*
G01X751875Y69017D02*
X751863Y69015D01*
G01X752013Y69120D02*
X752001Y69118D01*
G01X751715Y69070D02*
X751703Y69068D01*
G01X751358Y69017D02*
X751346Y69015D01*
G01X751191Y69017D02*
X751179Y69015D01*
G01X751061D02*
X751073Y69017D01*
G01X751575Y69120D02*
X751563Y69118D01*
G01X750967Y69017D02*
X750955Y69015D01*
G01X751048Y69090D02*
X751036Y69088D01*
G01X751144Y69130D02*
X751157Y69133D01*
G01X750564Y69015D02*
X750576Y69017D01*
G01X751048Y69133D02*
X751036Y69130D01*
G01X750564Y69057D02*
X750576Y69060D01*
G01X750920Y69130D02*
X750933Y69133D01*
G01X750716Y69120D02*
X750704Y69118D01*
G01X750074Y69017D02*
X750062Y69015D01*
G01X750551Y69133D02*
X750539Y69130D01*
G01X750027D02*
X750039Y69133D01*
G01X751998Y69130D02*
X752015Y69133D01*
G01X751560Y69130D02*
X751578Y69133D01*
G01X750702Y69130D02*
X750719Y69133D01*
G01X754921Y67322D02*
X751772D01*
G01X747244D02*
X753543D01*
G01X745866D02*
X749016D01*
G01X753263Y68641D02*
X753189D01*
G01X753681D02*
X753607D01*
G01X747608D02*
X747510D01*
G01X747239D02*
X747165D01*
G01X753558Y68792D02*
X753312D01*
G01X753546Y68842D02*
X753324D01*
G01X749498Y69015D02*
X749409D01*
G01X749577D02*
X749557D01*
G01X749724D02*
X749636D01*
G01X749946D02*
X749857D01*
G01X749980D02*
X749966D01*
G01X750062D02*
X750039D01*
G01X750214D02*
X750200D01*
G01X750131D02*
X750116D01*
G01X750288D02*
X750273D01*
G01X750495D02*
X750480D01*
G01X750765D02*
X750677D01*
G01X750815D02*
X750800D01*
G01X750955D02*
X750933D01*
G01X751179D02*
X751157D01*
G01X751346D02*
X751287D01*
G01X751516D02*
X751501D01*
G01X751413D02*
X751398D01*
G01X751467D02*
X751447D01*
G01X751624D02*
X751535D01*
G01X751659D02*
X751644D01*
G01X751784D02*
X751769D01*
G01X751863D02*
X751804D01*
G01X752028D02*
X752008D01*
G01X752136D02*
X752121D01*
G01X749820D02*
X749838D01*
G01X749744D02*
X749759D01*
G01X750554D02*
X750564D01*
G01X751048D02*
X751061D01*
G01X750566Y69027D02*
X750551D01*
G01X750696D02*
X750765D01*
G01X751046D02*
X751063D01*
G01X751555D02*
X751624D01*
G01X752011D02*
X752025D01*
G01X751348Y69030D02*
X751302D01*
G01X751865D02*
X751819D01*
G01X749424D02*
X749498D01*
G01X749651D02*
X749724D01*
G01X749872D02*
X749946D01*
G01X750039D02*
X750062D01*
G01X750933D02*
X750955D01*
G01X751157D02*
X751179D01*
G01X750531Y69042D02*
X750519D01*
G01X751974D02*
X751986D01*
G01X751198Y69045D02*
X751213D01*
G01X750657Y69057D02*
X750623D01*
G01X751267D02*
X751233D01*
G01X750551D02*
X750564D01*
G01X750081Y69065D02*
X750059D01*
G01X750974D02*
X750952D01*
G01X751703Y69068D02*
X751659D01*
G01X749759D02*
X749801D01*
G01X751302D02*
X751348D01*
G01X751819D02*
X751865D01*
G01X749488Y69070D02*
X749424D01*
G01X749715D02*
X749651D01*
G01X750200D02*
X750131D01*
G01X752023D02*
X752013D01*
G01X750549D02*
X750566D01*
G01X750623D02*
X750657D01*
G01X751233D02*
X751267D01*
G01X751063Y69077D02*
X751046D01*
G01X750059Y69080D02*
X750096D01*
G01X750952D02*
X750989D01*
G01X752013D02*
X752023D01*
G01X749759Y69082D02*
X749806D01*
G01X751302D02*
X751348D01*
G01X751659D02*
X751706D01*
G01X751819D02*
X751865D01*
G01X749424Y69085D02*
X749488D01*
G01X749651D02*
X749715D01*
G01X750131D02*
X750200D01*
G01X751061Y69090D02*
X751048D01*
G01X750096Y69103D02*
X750081D01*
G01X750989D02*
X750974D01*
G01X751213D02*
X751198D01*
G01X750692Y69105D02*
X750679D01*
G01X751550D02*
X751538D01*
G01X751988D02*
X751976D01*
G01X751080D02*
X751093D01*
G01X749498Y69118D02*
X749424D01*
G01X749724D02*
X749651D01*
G01X750062D02*
X750039D01*
G01X750955D02*
X750933D01*
G01X751179D02*
X751157D01*
G01X751348D02*
X751302D01*
G01X751865D02*
X751819D01*
G01X749806Y69120D02*
X749759D01*
G01X750273D02*
X750234D01*
G01X750328D02*
X750288D01*
G01X750566D02*
X750549D01*
G01X750726D02*
X750716D01*
G01X751585D02*
X751575D01*
G01X751706D02*
X751659D01*
G01X752023D02*
X752013D01*
G01X752121D02*
X752082D01*
G01X752175D02*
X752136D01*
G01X751046D02*
X751061D01*
G01X749803Y69133D02*
X749744D01*
G01X750564D02*
X750551D01*
G01X751058D02*
X751048D01*
G01X749409D02*
X749498D01*
G01X749602D02*
X749616D01*
G01X749518D02*
X749533D01*
G01X749636D02*
X749724D01*
G01X749857D02*
X749872D01*
G01X749966D02*
X749980D01*
G01X750039D02*
X750062D01*
G01X750200D02*
X750214D01*
G01X750116D02*
X750131D01*
G01X750234D02*
X750328D01*
G01X750480D02*
X750495D01*
G01X750719D02*
X750728D01*
G01X750800D02*
X750815D01*
G01X750933D02*
X750955D01*
G01X751157D02*
X751179D01*
G01X751287D02*
X751346D01*
G01X751494D02*
X751516D01*
G01X751398D02*
X751420D01*
G01X751578D02*
X751587D01*
G01X751644D02*
X751703D01*
G01X751769D02*
X751784D01*
G01X751804D02*
X751863D01*
G01X752015D02*
X752020D01*
G01X752082D02*
X752175D01*
G01X747510Y69231D02*
X747608D01*
G01X747165D02*
X747239D01*
G01X753386D02*
X753484D01*
G01X753543Y70471D02*
X747244D01*
G01X749016D02*
X745866D01*
G01X751772D02*
X754921D01*
G01X752020Y69133D02*
X752037Y69130D01*
G01X750728Y69133D02*
X750743Y69130D01*
G01X751587Y69133D02*
X751602Y69130D01*
G01X752037Y69068D02*
X752023Y69070D01*
G01X750039Y69015D02*
X750027Y69017D01*
G01X749816Y69130D02*
X749803Y69133D01*
G01X750541Y69017D02*
X750554Y69015D01*
G01X750062Y69133D02*
X750074Y69130D01*
G01X750539Y69060D02*
X750551Y69057D01*
G01X750933Y69015D02*
X750920Y69017D01*
G01X751036D02*
X751048Y69015D01*
G01X750576Y69130D02*
X750564Y69133D01*
G01X751157Y69015D02*
X751144Y69017D01*
G01X750738Y69118D02*
X750726Y69120D01*
G01X751073Y69088D02*
X751061Y69090D01*
G01X750955Y69133D02*
X750967Y69130D01*
G01X751070D02*
X751058Y69133D01*
G01X751179D02*
X751191Y69130D01*
G01X751346Y69133D02*
X751358Y69130D01*
G01X751998Y69030D02*
X752011Y69027D01*
G01X751597Y69118D02*
X751585Y69120D01*
G01X751703Y69133D02*
X751715Y69130D01*
G01X751863Y69133D02*
X751875Y69130D01*
G01X752035Y69118D02*
X752023Y69120D01*
G01X751147Y69032D02*
X751157Y69030D01*
G01X750965Y69115D02*
X750955Y69118D01*
G01X752008Y69015D02*
X751998Y69017D01*
G01X750030Y69032D02*
X750039Y69030D01*
G01X750072Y69115D02*
X750062Y69118D01*
G01X750923Y69032D02*
X750933Y69030D01*
G01X751189Y69115D02*
X751179Y69118D01*
G01X749813D02*
X749806Y69120D01*
G01X750551Y69027D02*
X750544Y69030D01*
G01X750541Y69072D02*
X750549Y69070D01*
G01X750574Y69118D02*
X750566Y69120D01*
G01X751039Y69030D02*
X751046Y69027D01*
G01X751070Y69075D02*
X751063Y69077D01*
G01X751061Y69120D02*
X751068Y69118D01*
G01X751348Y69068D02*
X751356Y69065D01*
G01Y69115D02*
X751348Y69118D01*
G01X751713D02*
X751706Y69120D01*
G01X751865Y69068D02*
X751873Y69065D01*
G01Y69115D02*
X751865Y69118D01*
G01X752043Y69075D02*
X752055Y69070D01*
G01X750027Y69017D02*
X750017Y69022D01*
G01X750074Y69130D02*
X750084Y69125D01*
G01X750920Y69017D02*
X750911Y69022D01*
G01X750743Y69130D02*
X750753Y69125D01*
G01X751144Y69017D02*
X751135Y69022D01*
G01X750967Y69130D02*
X750977Y69125D01*
G01X751191Y69130D02*
X751201Y69125D01*
G01X751363Y69075D02*
X751368Y69072D01*
G01X751602Y69130D02*
X751612Y69125D01*
G01X751880Y69075D02*
X751885Y69072D01*
G01X751998Y69017D02*
X751988Y69022D01*
G01X751993Y69032D02*
X751998Y69030D01*
G01X752037Y69130D02*
X752047Y69125D01*
G01X750529Y69025D02*
X750541Y69017D01*
G01X750527Y69068D02*
X750539Y69060D01*
G01X750588Y69123D02*
X750576Y69130D01*
G01X751024Y69025D02*
X751036Y69017D01*
G01X751085Y69080D02*
X751073Y69088D01*
G01X751083Y69123D02*
X751070Y69130D01*
G01X750022Y69037D02*
X750030Y69032D01*
G01X750079Y69110D02*
X750072Y69115D01*
G01X750544Y69030D02*
X750537Y69035D01*
G01X750534Y69077D02*
X750541Y69072D01*
G01X750581Y69113D02*
X750574Y69118D01*
G01X750842Y69040D02*
X750834Y69045D01*
G01X750746Y69113D02*
X750738Y69118D01*
G01X750915Y69037D02*
X750923Y69032D01*
G01X750866Y69108D02*
X750874Y69103D01*
G01X751031Y69035D02*
X751039Y69030D01*
G01X750972Y69110D02*
X750965Y69115D01*
G01X751078Y69070D02*
X751070Y69075D01*
G01X751139Y69037D02*
X751147Y69032D01*
G01X751068Y69118D02*
X751076Y69113D01*
G01X751196Y69110D02*
X751189Y69115D01*
G01X751604Y69113D02*
X751597Y69118D01*
G01X751922Y69040D02*
X751915Y69045D01*
G01X751988Y69022D02*
X751981Y69027D01*
G01X751946Y69108D02*
X751954Y69103D01*
G01X752045Y69062D02*
X752037Y69068D01*
G01X752043Y69113D02*
X752035Y69118D01*
G01X749826Y69123D02*
X749816Y69130D01*
G01X751358D02*
X751368Y69123D01*
G01X751715Y69130D02*
X751725Y69123D01*
G01X751875Y69130D02*
X751885Y69123D01*
G01X751356Y69065D02*
X751361Y69060D01*
G01Y69110D02*
X751356Y69115D01*
G01X751873Y69065D02*
X751878Y69060D01*
G01Y69110D02*
X751873Y69115D01*
G01X749818Y69113D02*
X749813Y69118D01*
G01X750017Y69022D02*
X750007Y69032D01*
G01X750084Y69125D02*
X750094Y69115D01*
G01X750753Y69125D02*
X750763Y69115D01*
G01X750911Y69022D02*
X750901Y69032D01*
G01X750977Y69125D02*
X750987Y69115D01*
G01X751083Y69065D02*
X751078Y69070D01*
G01X751135Y69022D02*
X751125Y69032D01*
G01X751093Y69072D02*
X751085Y69080D01*
G01X751201Y69125D02*
X751211Y69115D01*
G01X751612Y69125D02*
X751622Y69115D01*
G01X751718Y69113D02*
X751713Y69118D01*
G01X751988Y69037D02*
X751993Y69032D01*
G01X752047Y69125D02*
X752057Y69115D01*
G01X749833Y69113D02*
X749826Y69123D01*
G01X750522Y69035D02*
X750529Y69025D01*
G01X750519Y69077D02*
X750527Y69068D01*
G01X750596Y69113D02*
X750588Y69123D01*
G01X751017Y69035D02*
X751024Y69025D01*
G01X751090Y69113D02*
X751083Y69123D01*
G01X751368Y69072D02*
X751376Y69062D01*
G01X751368Y69123D02*
X751376Y69113D01*
G01X751725Y69123D02*
X751732Y69113D01*
G01X751885Y69072D02*
X751893Y69062D01*
G01X751885Y69123D02*
X751893Y69113D01*
G01X750017Y69045D02*
X750022Y69037D01*
G01X750537Y69035D02*
X750531Y69042D01*
G01X750529Y69085D02*
X750534Y69077D01*
G01X750586Y69105D02*
X750581Y69113D01*
G01X750751Y69105D02*
X750746Y69113D01*
G01X750911Y69045D02*
X750915Y69037D01*
G01X751026Y69042D02*
X751031Y69035D01*
G01X751076Y69113D02*
X751080Y69105D01*
G01X751135Y69045D02*
X751139Y69037D01*
G01X751609Y69105D02*
X751604Y69113D01*
G01X751981Y69027D02*
X751976Y69035D01*
G01X752055Y69070D02*
X752060Y69062D01*
G01X752047Y69105D02*
X752043Y69113D01*
G01X747510Y68641D02*
X747326Y68930D01*
G01X747387Y68992D02*
X747608Y68641D01*
G01X750007Y69032D02*
X750003Y69042D01*
G01X750901Y69032D02*
X750896Y69042D01*
G01X751125Y69032D02*
X751120Y69042D01*
G01X751986D02*
X751988Y69037D01*
G01X752050Y69052D02*
X752045Y69062D01*
G01X750515Y69090D02*
X750519Y69077D01*
G01X750600Y69100D02*
X750596Y69113D01*
G01X751011Y69047D02*
X751017Y69035D01*
G01X751098Y69060D02*
X751093Y69072D01*
G01X749838Y69015D02*
X749816Y69072D01*
G01X749801Y69068D02*
X749820Y69015D01*
G01X751447D02*
X751413Y69108D01*
G01X751420Y69133D02*
X751457Y69027D01*
G01X749533Y69133D02*
X749567Y69030D01*
G01X749557Y69015D02*
X749518Y69133D01*
G01X753484Y69231D02*
X753681Y68641D01*
G01X749820Y69105D02*
X749818Y69113D01*
G01X749835Y69105D02*
X749833Y69113D01*
G01X750081Y69103D02*
X750079Y69110D01*
G01X750519Y69042D02*
X750522Y69035D01*
G01X750527Y69093D02*
X750529Y69085D01*
G01X750588Y69097D02*
X750586Y69105D01*
G01X750974Y69103D02*
X750972Y69110D01*
G01X751024Y69050D02*
X751026Y69042D01*
G01X751085Y69057D02*
X751083Y69065D01*
G01X751093Y69105D02*
X751090Y69113D01*
G01X751198Y69103D02*
X751196Y69110D01*
G01X751361Y69060D02*
X751363Y69052D01*
G01X751376Y69062D02*
X751378Y69055D01*
G01X751363Y69103D02*
X751361Y69110D01*
G01X751376Y69113D02*
X751378Y69105D01*
G01X751720D02*
X751718Y69113D01*
G01X751732D02*
X751735Y69105D01*
G01X751878Y69060D02*
X751880Y69052D01*
G01X751893Y69062D02*
X751895Y69055D01*
G01X751880Y69103D02*
X751878Y69110D01*
G01X751893Y69113D02*
X751895Y69105D01*
G01X751976Y69035D02*
X751974Y69042D01*
G01X753607Y68641D02*
X753558Y68792D01*
G01X753435Y69181D02*
X753546Y68842D01*
G01X750015Y69055D02*
X750017Y69045D01*
G01X750763Y69115D02*
X750765Y69105D01*
G01X750908Y69055D02*
X750911Y69045D01*
G01X751132Y69055D02*
X751135Y69045D01*
G01X751622Y69115D02*
X751624Y69105D01*
G01X752060Y69062D02*
X752062Y69052D01*
G01X752057Y69115D02*
X752060Y69105D01*
G01X750003Y69042D02*
X750000Y69055D01*
G01X750094Y69115D02*
X750096Y69103D01*
G01X750896Y69042D02*
X750893Y69055D01*
G01X750987Y69115D02*
X750989Y69103D01*
G01X751120Y69042D02*
X751117Y69055D01*
G01X751211Y69115D02*
X751213Y69103D01*
G01X750603Y69082D02*
X750600Y69100D01*
G01X751009Y69065D02*
X751011Y69047D01*
G01X745866Y70471D02*
Y67322D01*
G01X747165Y68641D02*
Y69231D01*
G01X747239Y68842D02*
Y68641D01*
G01Y69231D02*
Y68942D01*
G01X747244Y70471D02*
Y67322D01*
G01X748031D02*
Y70471D01*
G01X748196D02*
Y67322D01*
G01X749016D02*
Y70471D01*
G01X749409Y69015D02*
Y69133D01*
G01X749424Y69070D02*
Y69030D01*
G01Y69118D02*
Y69085D01*
G01X749488D02*
Y69070D01*
G01X749498Y69133D02*
Y69118D01*
G01Y69030D02*
Y69015D01*
G01X749636D02*
Y69133D01*
G01X749651Y69070D02*
Y69030D01*
G01Y69118D02*
Y69085D01*
G01X749715D02*
Y69070D01*
G01X749724Y69133D02*
Y69118D01*
G01Y69030D02*
Y69015D01*
G01X749744Y69133D02*
Y69015D01*
G01X749759Y69120D02*
Y69082D01*
G01Y69015D02*
Y69068D01*
G01X749820Y69097D02*
Y69105D01*
G01X749835Y69095D02*
Y69105D01*
G01X749857Y69015D02*
Y69133D01*
G01X749872D02*
Y69030D01*
G01X749946D02*
Y69015D01*
G01X749966D02*
Y69133D01*
G01X749980D02*
Y69015D01*
G01X750000Y69055D02*
Y69093D01*
G01X750015D02*
Y69055D01*
G01X750059Y69065D02*
Y69080D01*
G01X750081Y69045D02*
Y69065D01*
G01X750096Y69080D02*
Y69042D01*
G01X750116Y69015D02*
Y69133D01*
G01X750131Y69070D02*
Y69015D01*
G01Y69133D02*
Y69085D01*
G01X750200Y69015D02*
Y69070D01*
G01Y69085D02*
Y69133D01*
G01X750214D02*
Y69015D01*
G01X750234Y69120D02*
Y69133D01*
G01X750273Y69015D02*
Y69120D01*
G01X750288D02*
Y69015D01*
G01X750328Y69133D02*
Y69120D01*
G01X750465Y69095D02*
Y69115D01*
G01X750480Y69015D02*
Y69113D01*
G01X750495Y69133D02*
Y69015D01*
G01X750515Y69100D02*
Y69090D01*
G01X750527Y69097D02*
Y69093D01*
G01X750588D02*
Y69097D01*
G01X750591Y69070D02*
Y69065D01*
G01X750603D02*
Y69082D01*
G01X750623Y69057D02*
Y69070D01*
G01X750657D02*
Y69057D01*
G01X750677Y69015D02*
Y69027D01*
G01X750751Y69100D02*
Y69105D01*
G01X750765Y69027D02*
Y69015D01*
G01Y69105D02*
Y69100D01*
G01X750785Y69095D02*
Y69115D01*
G01X750800Y69015D02*
Y69113D01*
G01X750815Y69133D02*
Y69015D01*
G01X750893Y69055D02*
Y69093D01*
G01X750908D02*
Y69055D01*
G01X750952Y69065D02*
Y69080D01*
G01X750974Y69045D02*
Y69065D01*
G01X750989Y69080D02*
Y69042D01*
G01X751009Y69082D02*
Y69065D01*
G01X751021Y69077D02*
Y69082D01*
G01X751024Y69057D02*
Y69050D01*
G01X751085D02*
Y69057D01*
G01X751098Y69047D02*
Y69060D01*
G01X751117Y69055D02*
Y69093D01*
G01X751132D02*
Y69055D01*
G01X751233Y69057D02*
Y69070D01*
G01X751267D02*
Y69057D01*
G01X751287Y69015D02*
Y69133D01*
G01X751302Y69118D02*
Y69082D01*
G01Y69030D02*
Y69068D01*
G01X751363Y69052D02*
Y69045D01*
G01Y69097D02*
Y69103D01*
G01X751378Y69105D02*
Y69095D01*
G01Y69055D02*
Y69042D01*
G01X751398Y69015D02*
Y69133D01*
G01X751413Y69108D02*
Y69015D01*
G01X751501D02*
Y69108D01*
G01X751516Y69133D02*
Y69015D01*
G01X751535D02*
Y69027D01*
G01X751609Y69100D02*
Y69105D01*
G01X751624Y69027D02*
Y69015D01*
G01Y69105D02*
Y69100D01*
G01X751644Y69015D02*
Y69133D01*
G01X751659Y69068D02*
Y69015D01*
G01Y69120D02*
Y69082D01*
G01X751720Y69097D02*
Y69105D01*
G01X751735D02*
Y69095D01*
G01X751755D02*
Y69115D01*
G01X751769Y69015D02*
Y69113D01*
G01X751772Y67322D02*
Y70471D01*
G01X751784Y69133D02*
Y69015D01*
G01X751804D02*
Y69133D01*
G01X751819Y69118D02*
Y69082D01*
G01Y69030D02*
Y69068D01*
G01X751880Y69052D02*
Y69045D01*
G01Y69097D02*
Y69103D01*
G01X751895Y69105D02*
Y69095D01*
G01Y69055D02*
Y69042D01*
G01X752013Y69070D02*
Y69080D01*
G01X752047Y69100D02*
Y69105D01*
G01X752050Y69042D02*
Y69052D01*
G01X752060Y69105D02*
Y69100D01*
G01X752062Y69052D02*
Y69042D01*
G01X752082Y69120D02*
Y69133D01*
G01X752121Y69015D02*
Y69120D01*
G01X752136D02*
Y69015D01*
G01X752175Y69133D02*
Y69120D01*
G01X752592Y67322D02*
Y70471D01*
G01X752756Y67322D02*
Y70471D01*
G01X753543Y67322D02*
Y70471D01*
G01X754921D02*
Y67322D01*
G01X750600Y69047D02*
X750603Y69065D01*
G01X751011Y69100D02*
X751009Y69082D01*
G01X750591Y69065D02*
X750588Y69050D01*
G01X751021Y69082D02*
X751024Y69097D01*
G01X750000Y69093D02*
X750003Y69105D01*
G01X750893Y69093D02*
X750896Y69105D01*
G01X751117Y69093D02*
X751120Y69105D01*
G01X751213Y69045D02*
X751211Y69032D01*
G01X750017Y69103D02*
X750015Y69093D01*
G01X750096Y69042D02*
X750094Y69032D01*
G01X750679Y69105D02*
X750682Y69115D01*
G01X750765Y69100D02*
X750763Y69090D01*
G01X750911Y69103D02*
X750908Y69093D01*
G01X750989Y69042D02*
X750987Y69032D01*
G01X751135Y69103D02*
X751132Y69093D01*
G01X751538Y69105D02*
X751541Y69115D01*
G01X751624Y69100D02*
X751622Y69090D01*
G01X751976Y69105D02*
X751978Y69115D01*
G01X752060Y69100D02*
X752057Y69090D01*
G01X749818D02*
X749820Y69097D01*
G01X749833Y69088D02*
X749835Y69095D01*
G01X750079Y69037D02*
X750081Y69045D01*
G01X750529Y69105D02*
X750527Y69097D01*
G01X750586Y69085D02*
X750588Y69093D01*
G01Y69050D02*
X750586Y69042D01*
G01X750972Y69037D02*
X750974Y69045D01*
G01X751024Y69097D02*
X751026Y69105D01*
G01Y69065D02*
X751024Y69057D01*
G01X751083Y69042D02*
X751085Y69050D01*
G01X751196Y69037D02*
X751198Y69045D01*
G01X751361Y69090D02*
X751363Y69097D01*
G01X751378Y69095D02*
X751376Y69088D01*
G01X751363Y69045D02*
X751361Y69037D01*
G01X751378Y69042D02*
X751376Y69035D01*
G01X751718Y69090D02*
X751720Y69097D01*
G01X751735Y69095D02*
X751732Y69088D01*
G01X751878Y69090D02*
X751880Y69097D01*
G01X751895Y69095D02*
X751893Y69088D01*
G01X751880Y69045D02*
X751878Y69037D01*
G01X751895Y69042D02*
X751893Y69035D01*
G01X752062Y69042D02*
X752060Y69035D01*
G01X753324Y68842D02*
X753435Y69181D01*
G01X753312Y68792D02*
X753263Y68641D01*
G01X749616Y69133D02*
X749577Y69015D01*
G01X753189Y68641D02*
X753386Y69231D01*
G01X749567Y69030D02*
X749602Y69133D01*
G01X751457Y69027D02*
X751494Y69133D01*
G01X751501Y69108D02*
X751467Y69015D01*
G01X750519Y69113D02*
X750515Y69100D01*
G01X750596Y69035D02*
X750600Y69047D01*
G01X751017Y69113D02*
X751011Y69100D01*
G01X751093Y69035D02*
X751098Y69047D01*
G01X750003Y69105D02*
X750007Y69115D01*
G01X750746Y69090D02*
X750751Y69100D01*
G01X750896Y69105D02*
X750901Y69115D01*
G01X751120Y69105D02*
X751125Y69115D01*
G01X751604Y69090D02*
X751609Y69100D01*
G01X752043Y69090D02*
X752047Y69100D01*
G01Y69037D02*
X752050Y69042D01*
G01X750834Y69045D02*
X750866Y69108D01*
G01X750874Y69103D02*
X750842Y69040D01*
G01X751915Y69045D02*
X751946Y69108D01*
G01X751954Y69103D02*
X751922Y69040D01*
G01X750022Y69110D02*
X750017Y69103D01*
G01X750534Y69113D02*
X750529Y69105D01*
G01X750581Y69077D02*
X750586Y69085D01*
G01Y69042D02*
X750581Y69035D01*
G01X750696Y69113D02*
X750692Y69105D01*
G01X750763Y69090D02*
X750758Y69082D01*
G01X750915Y69110D02*
X750911Y69103D01*
G01X751026Y69105D02*
X751031Y69113D01*
G01X751078Y69035D02*
X751083Y69042D01*
G01X751139Y69110D02*
X751135Y69103D01*
G01X751555Y69113D02*
X751550Y69105D01*
G01X751622Y69090D02*
X751617Y69082D01*
G01X751993Y69113D02*
X751988Y69105D01*
G01X752057Y69090D02*
X752052Y69082D01*
G01X752060Y69035D02*
X752055Y69027D01*
G01X749826Y69077D02*
X749833Y69088D01*
G01X750527Y69123D02*
X750519Y69113D01*
G01X750588Y69025D02*
X750596Y69035D01*
G01X751024Y69123D02*
X751017Y69113D01*
G01X751085Y69025D02*
X751093Y69035D01*
G01X751376Y69088D02*
X751368Y69077D01*
G01X751376Y69035D02*
X751368Y69025D01*
G01X751732Y69088D02*
X751725Y69077D01*
G01X751893Y69088D02*
X751885Y69077D01*
G01X751893Y69035D02*
X751885Y69025D01*
G01X750465Y69115D02*
X750480Y69133D01*
G01Y69113D02*
X750465Y69095D01*
G01X750785Y69115D02*
X750800Y69133D01*
G01Y69113D02*
X750785Y69095D01*
G01X751755Y69115D02*
X751769Y69133D01*
G01Y69113D02*
X751755Y69095D01*
G01X747608Y69231D02*
X747387Y68992D01*
G01X747239Y68942D02*
X747510Y69231D01*
G01X747326Y68930D02*
X747239Y68842D01*
G01X749813Y69085D02*
X749818Y69090D01*
G01X750007Y69115D02*
X750017Y69125D01*
G01X750094Y69032D02*
X750084Y69022D01*
G01X750682Y69115D02*
X750692Y69125D01*
G01X750901Y69115D02*
X750911Y69125D01*
G01X750987Y69032D02*
X750977Y69022D01*
G01X751031Y69070D02*
X751026Y69065D01*
G01X751125Y69115D02*
X751135Y69125D01*
G01X751211Y69032D02*
X751201Y69022D01*
G01X751356Y69085D02*
X751361Y69090D01*
G01Y69037D02*
X751356Y69032D01*
G01X751541Y69115D02*
X751550Y69125D01*
G01X751713Y69085D02*
X751718Y69090D01*
G01X751873Y69085D02*
X751878Y69090D01*
G01Y69037D02*
X751873Y69032D01*
G01X751978Y69115D02*
X751988Y69125D01*
G01X752037Y69085D02*
X752043Y69090D01*
G01Y69032D02*
X752047Y69037D01*
G01X750677Y69027D02*
X750746Y69090D01*
G01X751535Y69027D02*
X751604Y69090D01*
G01X750758Y69082D02*
X750696Y69027D01*
G01X751617Y69082D02*
X751555Y69027D01*
G01X751368Y69025D02*
X751358Y69017D01*
G01X751725Y69077D02*
X751715Y69070D01*
G01X751885Y69025D02*
X751875Y69017D01*
G01X752052Y69082D02*
X752043Y69075D01*
G01X750030Y69115D02*
X750022Y69110D01*
G01X750072Y69032D02*
X750079Y69037D01*
G01X750541Y69118D02*
X750534Y69113D01*
G01X750574Y69072D02*
X750581Y69077D01*
G01X750576Y69060D02*
X750591Y69070D01*
G01X750581Y69035D02*
X750574Y69030D01*
G01X750704Y69118D02*
X750696Y69113D01*
G01X750923Y69115D02*
X750915Y69110D01*
G01X751031Y69113D02*
X751039Y69118D01*
G01X751036Y69088D02*
X751021Y69077D01*
G01X750965Y69032D02*
X750972Y69037D01*
G01X751039Y69075D02*
X751031Y69070D01*
G01X751147Y69115D02*
X751139Y69110D01*
G01X751070Y69030D02*
X751078Y69035D01*
G01X751189Y69032D02*
X751196Y69037D01*
G01X751563Y69118D02*
X751555Y69113D01*
G01X752001Y69118D02*
X751993Y69113D01*
G01X752055Y69027D02*
X752047Y69022D01*
G01X750539Y69130D02*
X750527Y69123D01*
G01X750576Y69017D02*
X750588Y69025D01*
G01X751036Y69130D02*
X751024Y69123D01*
G01X751073Y69017D02*
X751085Y69025D01*
G01X749816Y69072D02*
X749826Y69077D01*
G01X750017Y69125D02*
X750027Y69130D01*
G01X750084Y69022D02*
X750074Y69017D01*
G01X750692Y69125D02*
X750702Y69130D01*
G01X750911Y69125D02*
X750920Y69130D01*
G01X751135Y69125D02*
X751144Y69130D01*
G01X750977Y69022D02*
X750967Y69017D01*
G01X751201Y69022D02*
X751191Y69017D01*
G01X751368Y69077D02*
X751363Y69075D01*
G01X751550Y69125D02*
X751560Y69130D01*
G01X751885Y69077D02*
X751880Y69075D01*
G01X751988Y69125D02*
X751998Y69130D01*
G01X752037Y69030D02*
X752043Y69032D01*
G01X752047Y69022D02*
X752037Y69017D01*
G01X749806Y69082D02*
X749813Y69085D01*
G01X750549Y69120D02*
X750541Y69118D01*
G01X750566Y69070D02*
X750574Y69072D01*
G01Y69030D02*
X750566Y69027D01*
G01X751039Y69118D02*
X751046Y69120D01*
G01Y69077D02*
X751039Y69075D01*
G01X751063Y69027D02*
X751070Y69030D01*
G01X751348Y69082D02*
X751356Y69085D01*
G01Y69032D02*
X751348Y69030D01*
G01X751706Y69082D02*
X751713Y69085D01*
G01X751865Y69082D02*
X751873Y69085D01*
G01Y69032D02*
X751865Y69030D01*
G01X752023Y69080D02*
X752037Y69085D01*
G01X817410Y208660D02*
X754409D01*
G01D02*
Y303149D01*
G01X754418Y208660D02*
Y303149D01*
G01X772224Y219307D02*
X765335D01*
G01Y220815D02*
X772224D01*
G01X763858Y225590D02*
X765335D01*
G01D02*
Y220815D01*
G01Y213779D02*
X763858D01*
G01D02*
Y225590D01*
G01X765335Y219307D02*
Y213779D01*
G01X762292Y216534D02*
X809536D01*
G01X762292Y303149D02*
Y216534D01*
G01X809536Y303149D02*
X762292D01*
G01X764936Y495625D02*
Y474684D01*
G01X749352D02*
Y507353D01*
G01X754273Y514054D02*
Y474684D01*
G01X760835D02*
Y501489D01*
G01X764936Y474684D02*
X760835D01*
G01X754273D02*
X749352D01*
G01X764936Y498976D02*
X766576Y500651D01*
G01Y497301D02*
X764936Y495625D01*
G01X766576Y500651D02*
X769037Y501489D01*
G01Y498138D02*
X766576Y497301D01*
G01X764936Y501489D02*
Y498976D01*
G01X770678Y498138D02*
X769037D01*
G01Y501489D02*
X772318D01*
G01Y497301D02*
X770678Y498138D01*
G01X744431Y508190D02*
X749352Y514054D01*
G01Y507353D02*
X744431Y501489D01*
G01D02*
Y508190D01*
G01X760835Y501489D02*
X764936D01*
G01X749352Y514054D02*
X754273D01*
G01X763681Y892519D02*
Y883464D01*
G01X764665D02*
Y892519D01*
G01X766831D02*
Y883464D01*
G01X767815D02*
Y892519D01*
G01X769980D02*
Y883464D01*
G01X770965D02*
Y892519D01*
G01X769980Y883464D02*
X767815D01*
G01X773130D02*
X770965D01*
G01X766831D02*
X764665D01*
G01X738484Y892519D02*
Y883464D01*
G01X739469D02*
Y892519D01*
G01X741634D02*
Y883464D01*
G01X742618D02*
Y892519D01*
G01X744783D02*
Y883464D01*
G01X745768D02*
Y892519D01*
G01X747933D02*
Y883464D01*
G01X748917D02*
Y892519D01*
G01X751083D02*
Y883464D01*
G01X752067D02*
Y892519D01*
G01X754232D02*
Y883464D01*
G01X755217D02*
Y892519D01*
G01X757382D02*
Y883464D01*
G01X758366D02*
Y892519D01*
G01X760531D02*
Y883464D01*
G01X761516D02*
Y892519D01*
G01X760531Y883464D02*
X758366D01*
G01X763681D02*
X761516D01*
G01X757382D02*
X755217D01*
G01X751083D02*
X748917D01*
G01X754232D02*
X752067D01*
G01X747933D02*
X745768D01*
G01X741634D02*
X739469D01*
G01X744783D02*
X742618D01*
G01X764665Y892519D02*
X766831D01*
G01X767815D02*
X769980D01*
G01X770965D02*
X773130D01*
G01X739469D02*
X741634D01*
G01X742618D02*
X744783D01*
G01X745768D02*
X747933D01*
G01X748917D02*
X751083D01*
G01X752067D02*
X754232D01*
G01X755217D02*
X757382D01*
G01X758366D02*
X760531D01*
G01X761516D02*
X763681D01*
G01X779522Y-268979D02*
Y-277640D01*
G01Y-275475D02*
X778548Y-276919D01*
X777574Y-277640D01*
X776599Y-276919D01*
X775625Y-275475D01*
Y-274031D01*
X776599Y-272588D01*
X777574Y-271866D01*
X778548Y-272588D01*
X779522Y-274031D01*
G01X786831Y-276197D02*
X786343Y-276919D01*
X785369Y-277640D01*
X784394Y-276919D01*
X783420Y-275475D01*
Y-274031D01*
X784394Y-272588D01*
X785369Y-271866D01*
X786343Y-272588D01*
X786831Y-274031D01*
X783420D01*
G01X787685Y-132121D02*
X781911Y-129198D01*
G01X780468Y-140404D02*
X779746Y-139917D01*
X779024Y-138943D01*
Y-137968D01*
X779746Y-136994D01*
X780468Y-136507D01*
X781911D01*
X782633Y-136994D01*
X784076Y-138943D01*
G01D02*
X785520Y-139917D01*
X787685Y-140404D01*
Y-136507D01*
G01X781911Y-132121D02*
X787685Y-129198D01*
G01Y-99479D02*
Y-99966D01*
X786964D01*
X787685Y-99479D01*
G01Y-107274D02*
X786964Y-108249D01*
X786242Y-108736D01*
X784798Y-109223D01*
X781911D01*
X780468Y-108736D01*
X779746Y-108249D01*
X779024Y-107274D01*
X779746Y-106300D01*
X780468Y-105812D01*
X781911Y-105325D01*
X784798D01*
X786242Y-105812D01*
X786964Y-106300D01*
X787685Y-107274D01*
G01Y-115070D02*
X786964Y-116044D01*
X786242Y-116531D01*
X784798Y-117018D01*
X781911D01*
X780468Y-116531D01*
X779746Y-116044D01*
X779024Y-115070D01*
X779746Y-114095D01*
X780468Y-113608D01*
X781911Y-113121D01*
X784798D01*
X786242Y-113608D01*
X786964Y-114095D01*
X787685Y-115070D01*
G01X780468Y-124814D02*
X779746Y-124327D01*
X779024Y-123352D01*
Y-122378D01*
X779746Y-121403D01*
X780468Y-120916D01*
X781911D01*
X782633Y-121403D01*
X784076Y-123352D01*
G01D02*
X785520Y-124327D01*
X787685Y-124814D01*
Y-120916D01*
G01X789851Y232282D02*
Y-75660D01*
G01X780468Y-85837D02*
X779746Y-85350D01*
X779024Y-84376D01*
Y-83401D01*
X779746Y-82427D01*
X780468Y-81940D01*
X781911D01*
X782633Y-82427D01*
X784076Y-84376D01*
G01D02*
X785520Y-85350D01*
X787685Y-85837D01*
Y-81940D01*
G01X784798Y-93632D02*
X783355Y-93145D01*
X782633Y-91684D01*
X783355Y-90222D01*
X784798Y-89735D01*
X786242Y-90222D01*
X786964Y-90709D01*
X787685Y-91684D01*
X786964Y-92658D01*
X786242Y-93145D01*
X784798Y-93632D01*
X781911D01*
X780468Y-93145D01*
X779746Y-92658D01*
X779024Y-91684D01*
X779746Y-90709D01*
X780468Y-90222D01*
G01X801116Y-4922D02*
X800886D01*
G01X800743Y-3624D02*
X801259D01*
G01X800714Y-3457D02*
X801288D01*
G01X805512Y-2954D02*
X799606D01*
G01X803543Y-1970D02*
X805512D01*
G01X815354Y1968D02*
X803543D01*
G01X799606Y2952D02*
X805512D01*
G01X800886Y-4922D02*
X800427Y-2954D01*
G01X801001Y-4755D02*
X800743Y-3624D01*
G01X800599Y-2954D02*
X800714Y-3457D01*
G01X799606Y-2954D02*
Y2952D01*
G01X803543Y-1970D02*
Y1968D01*
G01X804528Y-1970D02*
Y1968D01*
G01X805512Y2952D02*
Y-2954D01*
G01X801288Y-3457D02*
X801403Y-2954D01*
G01X801259Y-3624D02*
X801001Y-4755D01*
G01X801575Y-2954D02*
X801116Y-4922D01*
G01X805512Y-1970D02*
G03X813386I3937J0D01*
G01X777559D02*
X773622D01*
G01X774016D02*
X775984D01*
G01X777193Y-918D02*
X774437D01*
G01Y-574D02*
X775786D01*
G01X776255D02*
X777193D01*
G01X773622Y1968D02*
X777559D01*
G01X774437Y1149D02*
X775551Y115D01*
G01X775786Y-574D02*
X774437Y689D01*
G01X775844Y-172D02*
X776255Y-574D01*
G01X773622Y-1970D02*
Y1968D01*
G01X774437Y689D02*
Y1149D01*
G01Y-918D02*
Y-574D01*
G01X775984Y-1970D02*
Y1968D01*
G01X777193Y1149D02*
Y689D01*
G01Y-574D02*
Y-918D01*
G01X777559Y1968D02*
Y-1970D01*
G01X777193Y689D02*
X775844Y-172D01*
G01X775551Y115D02*
X777193Y1149D01*
G01X833071Y177164D02*
X803543D01*
G01D02*
Y208660D01*
G01X799291Y220815D02*
X798553D01*
G01X798799Y221820D02*
X799783D01*
G01X803474D02*
X804705D01*
G01X799783D02*
X800522Y221569D01*
G01X799783Y220564D02*
X799291Y220815D01*
G01X796585Y221569D02*
X797323Y220815D01*
G01X800030Y220312D02*
X799783Y220564D01*
G01X800522Y221569D02*
X801014Y221066D01*
G01X800276Y219810D02*
X800030Y220312D01*
G01X801014Y221066D02*
X801506Y219810D01*
G01X804705Y221820D02*
Y221066D01*
G01X797815Y220312D02*
X797569Y219810D01*
G01X797323Y220815D02*
X798061Y221569D01*
G01Y220564D02*
X797815Y220312D01*
G01X804705Y221066D02*
X805197Y221569D01*
G01Y220564D02*
X804705Y220061D01*
G01X798553Y220815D02*
X798061Y220564D01*
G01Y221569D02*
X798799Y221820D01*
G01X805197Y221569D02*
X805935Y221820D01*
G01Y220815D02*
X805197Y220564D01*
G01X801506Y213779D02*
X800276D01*
G01X804705D02*
X803474D01*
G01X797569D02*
X796339D01*
G01D02*
Y219810D01*
G01X797569D02*
Y213779D01*
G01X800276D02*
Y219810D01*
G01X801506D02*
Y213779D01*
G01X803474D02*
Y221820D01*
G01X804705Y220061D02*
Y213779D01*
G01X786004Y215035D02*
X787234Y215286D01*
G01X786004Y224333D02*
X784774Y224082D01*
G01X786004Y225590D02*
X784528Y225338D01*
G01X779606Y217799D02*
X775669D01*
G01Y218805D02*
X779606D01*
G01X795354Y220815D02*
X794862D01*
G01X779606D02*
X775669D01*
G01Y221820D02*
X779606D01*
G01X792402D02*
X793632D01*
G01X794862D02*
X795846D01*
G01X772224Y225590D02*
X773701D01*
G01X787480Y225338D02*
X786004Y225590D01*
G01X784774Y215286D02*
X786004Y215035D01*
G01X787234Y224082D02*
X786004Y224333D01*
G01X795846Y221820D02*
X796585Y221569D01*
G01X795846Y220564D02*
X795354Y220815D01*
G01X783297Y214784D02*
X784528Y214030D01*
G01X788711Y224584D02*
X787480Y225338D01*
G01X784035Y215789D02*
X784774Y215286D01*
G01X787972Y223579D02*
X787234Y224082D01*
G01X782559Y215538D02*
X783297Y214784D01*
G01X789449Y223830D02*
X788711Y224584D01*
G01X796093Y220312D02*
X795846Y220564D01*
G01X783051Y217297D02*
X784035Y215789D01*
G01X788957Y222071D02*
X787972Y223579D01*
G01X782067Y216543D02*
X782559Y215538D01*
G01X789941Y222825D02*
X789449Y223830D01*
G01X796339Y219810D02*
X796093Y220312D01*
G01X781821Y217297D02*
X782067Y216543D01*
G01X790187Y222071D02*
X789941Y222825D01*
G01X781575Y218553D02*
X781821Y217297D01*
G01X790433Y220815D02*
X790187Y222071D01*
G01X782805Y218805D02*
X783051Y217297D01*
G01X789203Y220564D02*
X788957Y222071D01*
G01X772224Y220815D02*
Y225590D01*
G01X775669Y217799D02*
Y218805D01*
G01Y220815D02*
Y221820D01*
G01X779606D02*
Y220815D01*
G01Y218805D02*
Y217799D01*
G01X781575Y220815D02*
Y218553D01*
G01X782805Y220564D02*
Y218805D01*
G01X789203D02*
Y220564D01*
G01X790433Y218553D02*
Y220815D01*
G01X793632Y221820D02*
Y221066D01*
G01X783051Y222071D02*
X782805Y220564D01*
G01X788957Y217297D02*
X789203Y218805D01*
G01X781821Y222071D02*
X781575Y220815D01*
G01X790187Y217297D02*
X790433Y218553D01*
G01X782067Y222825D02*
X781821Y222071D01*
G01X789941Y216543D02*
X790187Y217297D01*
G01X782559Y223830D02*
X782067Y222825D01*
G01X789449Y215538D02*
X789941Y216543D01*
G01X784035Y223579D02*
X783051Y222071D01*
G01X787972Y215789D02*
X788957Y217297D01*
G01X783297Y224584D02*
X782559Y223830D01*
G01X793632Y221066D02*
X794124Y221569D01*
G01Y220564D02*
X793632Y220061D01*
G01X788711Y214784D02*
X789449Y215538D01*
G01X784774Y224082D02*
X784035Y223579D01*
G01X787234Y215286D02*
X787972Y215789D01*
G01X784528Y225338D02*
X783297Y224584D01*
G01X787480Y214030D02*
X788711Y214784D01*
G01X794124Y221569D02*
X794862Y221820D01*
G01Y220815D02*
X794124Y220564D01*
G01X796150Y236219D02*
G03I-6299J0D01*
G01X773662Y216534D02*
X787502Y230375D01*
G01X795696Y238568D02*
X809536Y252408D01*
G01X796150Y236219D02*
G03I-6299J0D01*
G01X786004Y213779D02*
X787480Y214030D01*
G01X793632Y213779D02*
X792402D01*
G01X773701D02*
X772224D01*
G01X784528Y214030D02*
X786004Y213779D01*
G01X772224D02*
Y219307D01*
G01X773701Y225590D02*
Y213779D01*
G01X792402D02*
Y221820D01*
G01X793632Y220061D02*
Y213779D01*
G01X804700Y258997D02*
X804371D01*
G01X802832D02*
X802502D01*
G01Y261635D02*
X802832D01*
G01X804371D02*
X804700D01*
G01X800811Y259842D02*
X797889Y261826D01*
G01X803437Y260344D02*
X802502Y261635D01*
G01X804371Y258997D02*
X803602Y260064D01*
G01X802832Y261635D02*
X803602Y260569D01*
G01X803766Y260344D02*
X804700Y258997D01*
G01X802502D02*
X803437Y260344D01*
G01X803602Y260569D02*
X804371Y261635D01*
G01X803602Y260064D02*
X802832Y258997D01*
G01X804700Y261635D02*
X803766Y260344D01*
G01X800811Y259842D02*
X797889Y257852D01*
G01X789851Y259842D02*
X800811D01*
G01X794069Y272731D02*
X793739D01*
G01X792859Y275369D02*
X793189D01*
G01X794618D02*
X794948D01*
G01X793739Y274078D02*
X792859Y275369D01*
G01X789851Y272943D02*
X791840Y270021D01*
G01X793189Y275369D02*
X793904Y274302D01*
G01X789851Y259842D02*
Y272943D01*
G01X793739Y272731D02*
Y274078D01*
G01X794069D02*
Y272731D01*
G01X793904Y274302D02*
X794618Y275369D01*
G01X789851Y272943D02*
X787866Y270021D01*
G01X794948Y275369D02*
X794069Y274078D01*
G01X798741Y303149D02*
X830249Y333204D01*
G01X796150Y283463D02*
G03I-6299J0D01*
G01D02*
G03I-6299J0D01*
G01X801846Y474684D02*
X797744D01*
G01D02*
Y501489D01*
G01X801846Y495625D02*
Y474684D01*
G01X791183D02*
X787082D01*
G01X778059D02*
X773958D01*
G01D02*
Y494788D01*
G01X778059D02*
Y474684D01*
G01X787082D02*
Y494788D01*
G01X791183D02*
Y474684D01*
G01X803486Y500651D02*
X805946Y501489D01*
G01Y498138D02*
X803486Y497301D01*
G01X801846Y498976D02*
X803486Y500651D01*
G01Y497301D02*
X801846Y495625D01*
G01Y501489D02*
Y498976D01*
G01X797744Y501489D02*
X801846D01*
G01X777239Y498138D02*
X779700Y500651D01*
G01X781340Y498138D02*
X779700Y497301D01*
G01Y500651D02*
X782161Y501489D01*
G01X778880Y496463D02*
X778059Y494788D01*
G01X779700Y497301D02*
X778880Y496463D01*
G01X783801Y498138D02*
X781340D01*
G01X782161Y501489D02*
X785441D01*
G01X772318D02*
X774779Y500651D01*
G01X785441Y501489D02*
X787902Y500651D01*
G01X785441Y497301D02*
X783801Y498138D01*
G01X773138Y496463D02*
X772318Y497301D01*
G01X774779Y500651D02*
X777239Y498138D01*
G01X786261Y496463D02*
X785441Y497301D01*
G01X787902Y500651D02*
X789543Y498976D01*
G01X773958Y494788D02*
X773138Y496463D01*
G01X787082Y494788D02*
X786261Y496463D01*
G01X789543Y498976D02*
X791183Y494788D01*
G01X798327Y892519D02*
Y883464D01*
G01X799311D02*
Y892519D01*
G01X801476D02*
Y883464D01*
G01X802461D02*
Y892519D01*
G01X804626D02*
Y883464D01*
G01X805610D02*
Y892519D01*
G01X807776Y883464D02*
X805610D01*
G01X801476D02*
X799311D01*
G01X804626D02*
X802461D01*
G01X773130Y892519D02*
Y883464D01*
G01X774114D02*
Y892519D01*
G01X776280D02*
Y883464D01*
G01X777264D02*
Y892519D01*
G01X779429D02*
Y883464D01*
G01X780413D02*
Y892519D01*
G01X782579D02*
Y883464D01*
G01X783563D02*
Y892519D01*
G01X785728D02*
Y883464D01*
G01X786713D02*
Y892519D01*
G01X788878D02*
Y883464D01*
G01X789862D02*
Y892519D01*
G01X792028D02*
Y883464D01*
G01X793012D02*
Y892519D01*
G01X795177D02*
Y883464D01*
G01X796161D02*
Y892519D01*
G01X798327Y883464D02*
X796161D01*
G01X792028D02*
X789862D01*
G01X795177D02*
X793012D01*
G01X788878D02*
X786713D01*
G01X782579D02*
X780413D01*
G01X785728D02*
X783563D01*
G01X779429D02*
X777264D01*
G01X776280D02*
X774114D01*
G01X799311Y892519D02*
X801476D01*
G01X802461D02*
X804626D01*
G01X805610D02*
X807776D01*
G01X774114D02*
X776280D01*
G01X777264D02*
X779429D01*
G01X780413D02*
X782579D01*
G01X783563D02*
X785728D01*
G01X786713D02*
X788878D01*
G01X789862D02*
X792028D01*
G01X793012D02*
X795177D01*
G01X796161D02*
X798327D01*
G01X816519Y-4922D02*
X816289D01*
G01X817323D02*
X817151D01*
G01X813386Y-2954D02*
X819291D01*
G01X813386Y-1970D02*
X815354D01*
G01X819291Y2952D02*
X813386D01*
G01X816519Y-2954D02*
X816950Y-3917D01*
G01X816806Y-4127D02*
X816289Y-2954D01*
G01X813386Y2952D02*
Y-2954D01*
G01X814370Y-1970D02*
Y1968D01*
G01X815354Y-1970D02*
Y1968D01*
G01X817151Y-4922D02*
Y-3959D01*
G01Y-3624D02*
Y-2954D01*
G01X817323D02*
Y-4922D01*
G01X819291Y-2954D02*
Y2952D01*
G01X816289Y-4922D02*
X816806Y-4127D01*
G01X817151Y-3959D02*
X816519Y-4922D01*
G01X816950Y-3917D02*
X817151Y-3624D01*
G01X833071Y74566D02*
X1092913D01*
G01X833071Y177164D02*
Y74566D01*
G01X817402Y303149D02*
Y208660D01*
G01X835718Y213453D02*
X890214Y159990D01*
G01X810364Y220815D02*
X809626D01*
G01X806427D02*
X805935D01*
G01Y221820D02*
X806919D01*
G01X809872D02*
X810856D01*
G01X806919D02*
X807657Y221569D01*
G01X810856Y221820D02*
X811594Y221569D01*
G01X806919Y220564D02*
X806427Y220815D01*
G01X810856Y220564D02*
X810364Y220815D01*
G01X807165Y220312D02*
X806919Y220564D01*
G01X807657Y221569D02*
X808396Y220815D01*
G01X811102Y220312D02*
X810856Y220564D01*
G01X811594Y221569D02*
X812087Y221066D01*
G01X807411Y219810D02*
X807165Y220312D01*
G01X811348Y219810D02*
X811102Y220312D01*
G01X812087Y221066D02*
X812579Y219810D01*
G01X808888Y220312D02*
X808642Y219810D01*
G01X808396Y220815D02*
X809134Y221569D01*
G01Y220564D02*
X808888Y220312D01*
G01X809626Y220815D02*
X809134Y220564D01*
G01Y221569D02*
X809872Y221820D01*
G01X809536Y216534D02*
Y303149D01*
G01X812579Y213779D02*
X811348D01*
G01X808642D02*
X807411D01*
G01D02*
Y219810D01*
G01X808642D02*
Y213779D01*
G01X811348D02*
Y219810D01*
G01X812579D02*
Y213779D01*
G01X822835Y260826D02*
X815787D01*
G01X814449Y261810D02*
X824173D01*
G01X824016Y262243D02*
X822047D01*
G01X816575D02*
X814606D01*
G01X820571Y264074D02*
X818051D01*
G01X820571D02*
X818051D01*
G01X824016Y264212D02*
X822047D01*
G01X816575D02*
X814606D01*
G01X818839Y264861D02*
X819783D01*
G01Y265806D02*
X818839D01*
G01X820571Y266593D02*
X818051D01*
G01X824016D02*
X822047D01*
G01X816575D02*
X814606D01*
G01X818051D02*
X820571D01*
G01X824016Y268562D02*
X822047D01*
G01X816575D02*
X814606D01*
G01X824173Y269153D02*
X814449D01*
G01X816614Y270137D02*
X822008D01*
G01Y270530D02*
X816614D01*
G01X814449Y271515D02*
X824173D01*
G01X816575Y272086D02*
X814606D01*
G01X824016Y272164D02*
X822047D01*
G01X816575Y274054D02*
X814606D01*
G01X820571Y274074D02*
X818051D01*
G01X824016Y274133D02*
X822047D01*
G01X814449Y271515D02*
X816614Y270530D01*
G01X824173Y269153D02*
X822008Y270137D01*
G01X814449Y261810D02*
X815787Y260826D01*
G01X818051Y266593D02*
X818839Y265806D01*
G01X819783Y264861D02*
X820571Y264074D01*
G01X814449Y279153D02*
Y271515D01*
G01Y269153D02*
Y261810D01*
G01X814606Y274054D02*
Y272086D01*
G01Y268562D02*
Y266593D01*
G01Y264212D02*
Y262243D01*
G01X816575Y274054D02*
Y272086D01*
G01Y268562D02*
Y266593D01*
G01Y264212D02*
Y262243D01*
G01X816614Y270530D02*
Y270137D01*
G01X818051Y276593D02*
Y274074D01*
G01Y266593D02*
Y264074D01*
G01Y286593D02*
Y264074D01*
G01X818839Y264861D02*
Y265806D01*
G01X819783Y264861D02*
Y265806D01*
G01X820571Y276593D02*
Y274074D01*
G01Y266593D02*
Y264074D01*
G01Y286593D02*
Y264074D01*
G01X822008Y270530D02*
Y270137D01*
G01X822047Y274133D02*
Y272164D01*
G01Y268562D02*
Y266593D01*
G01Y264212D02*
Y262243D01*
G01X824016Y274133D02*
Y272164D01*
G01Y268562D02*
Y266593D01*
G01Y264212D02*
Y262243D01*
G01X824173Y279153D02*
Y271515D01*
G01Y269153D02*
Y261810D01*
G01X818839Y264861D02*
X818051Y264074D01*
G01X819783Y265806D02*
X820571Y266593D01*
G01X824173Y261810D02*
X822835Y260826D01*
G01X816614Y270137D02*
X814449Y269153D01*
G01X824173Y271515D02*
X822008Y270530D01*
G01X814449Y281515D02*
X824173D01*
G01X816575Y281928D02*
X814606D01*
G01X824016Y282086D02*
X822047D01*
G01X816575Y283897D02*
X814606D01*
G01X824016Y284054D02*
X822047D01*
G01X820571Y284074D02*
X818051D01*
G01X820571D02*
X818051D01*
G01X818839Y284861D02*
X819783D01*
G01X819944Y285008D02*
X819038D01*
G01Y285121D02*
X819790D01*
G01X819655Y285235D02*
X819809D01*
G01X819732Y285386D02*
X819655D01*
G01X819674Y285499D02*
X819732D01*
G01X819783Y285806D02*
X818839D01*
G01X819443Y285971D02*
X819038D01*
G01X819847D02*
X819558D01*
G01X819038Y286084D02*
X819944D01*
G01X824016Y286279D02*
X822047D01*
G01X816575Y286436D02*
X814606D01*
G01X820571Y286593D02*
X818051D01*
G01D02*
X820571D01*
G01X824016Y288247D02*
X822047D01*
G01X816575Y288405D02*
X814606D01*
G01X824173Y288857D02*
X814449D01*
G01X815787Y289842D02*
X822835D01*
G01X819655Y285386D02*
X819597Y285405D01*
G01X819616Y285518D02*
X819674Y285499D01*
G01X819597Y285405D02*
X819520Y285461D01*
G01X824173Y288857D02*
X822835Y289842D01*
G01X819790Y285121D02*
X819655Y285235D01*
G01X819809D02*
X819944Y285121D01*
G01X819578Y285555D02*
X819616Y285518D01*
G01X819783Y284861D02*
X820571Y284074D01*
G01X818051Y286593D02*
X818839Y285806D01*
G01X819520Y285461D02*
X819462Y285536D01*
G01X814449Y288857D02*
Y281515D01*
G01X814606Y288405D02*
Y286436D01*
G01Y283897D02*
Y281928D01*
G01X816575Y288405D02*
Y286436D01*
G01Y283897D02*
Y281928D01*
G01X818051Y286593D02*
Y284074D01*
G01X818839Y284861D02*
Y285806D01*
G01X819038Y285971D02*
Y286084D01*
G01Y285008D02*
Y285121D01*
G01X819443Y285631D02*
Y285971D01*
G01X819558D02*
Y285612D01*
G01X819783Y284861D02*
Y285806D01*
G01X819847Y285612D02*
Y285971D01*
G01X819944Y286084D02*
Y285631D01*
G01Y285121D02*
Y285008D01*
G01X820571Y286593D02*
Y284074D01*
G01X822047Y288247D02*
Y286279D01*
G01Y284054D02*
Y282086D01*
G01X819558Y285612D02*
X819578Y285555D01*
G01X819462Y285536D02*
X819443Y285631D01*
G01X824016Y288247D02*
Y286279D01*
G01Y284054D02*
Y282086D01*
G01X824173Y288857D02*
Y281515D01*
G01X819944Y285631D02*
X819924Y285536D01*
G01X819828Y285555D02*
X819847Y285612D01*
G01X815787Y289842D02*
X814449Y288857D01*
G01X819732Y285499D02*
X819790Y285518D01*
G01Y285405D02*
X819732Y285386D01*
G01X819924Y285536D02*
X819867Y285461D01*
G01X820571Y286593D02*
X819783Y285806D01*
G01X818839Y284861D02*
X818051Y284074D01*
G01X819790Y285518D02*
X819828Y285555D01*
G01X819867Y285461D02*
X819790Y285405D01*
G01X824016Y276436D02*
X822047D01*
G01X816575Y276515D02*
X814606D01*
G01X820571Y276593D02*
X818051D01*
G01X824016Y278405D02*
X822047D01*
G01X816575Y278483D02*
X814606D01*
G01X824173Y279153D02*
X814449D01*
G01X816614Y280137D02*
X822008D01*
G01Y280530D02*
X816614D01*
G01D02*
X814449Y281515D01*
G01X824173Y279153D02*
X822008Y280137D01*
G01X814606Y278483D02*
Y276515D01*
G01X816575Y278483D02*
Y276515D01*
G01X816614Y280530D02*
Y280137D01*
G01X822008Y280530D02*
Y280137D01*
G01X822047Y278405D02*
Y276436D01*
G01X824016Y278405D02*
Y276436D01*
G01X816614Y280137D02*
X814449Y279153D01*
G01X822008Y280530D02*
X824173Y281515D01*
G01X830249Y333204D02*
X842060D01*
G01X828092Y474684D02*
X823991D01*
G01X814969D02*
X810868D01*
G01D02*
Y494788D01*
G01X814969D02*
Y474684D01*
G01X823991D02*
Y494788D01*
G01X828092D02*
Y474684D01*
G01X818250Y498138D02*
X816609Y497301D01*
G01Y500651D02*
X819070Y501489D01*
G01X814149Y498138D02*
X816609Y500651D01*
G01Y497301D02*
X815789Y496463D01*
G01D02*
X814969Y494788D01*
G01X820710Y498138D02*
X818250D01*
G01X807587D02*
X805946D01*
G01Y501489D02*
X809228D01*
G01X819070D02*
X822351D01*
G01X809228D02*
X811688Y500651D01*
G01X822351Y501489D02*
X824811Y500651D01*
G01X809228Y497301D02*
X807587Y498138D01*
G01X822351Y497301D02*
X820710Y498138D01*
G01X810048Y496463D02*
X809228Y497301D01*
G01X811688Y500651D02*
X814149Y498138D01*
G01X823171Y496463D02*
X822351Y497301D01*
G01X824811Y500651D02*
X826452Y498976D01*
G01X810868Y494788D02*
X810048Y496463D01*
G01X823991Y494788D02*
X823171Y496463D01*
G01X826452Y498976D02*
X828092Y494788D01*
G01X830807Y883464D02*
Y892519D01*
G01X832972D02*
Y883464D01*
G01X833957D02*
Y892519D01*
G01X836122D02*
Y883464D01*
G01X837106D02*
Y892519D01*
G01X839272D02*
Y883464D01*
G01D02*
X837106D01*
G01X836122D02*
X833957D01*
G01X832972D02*
X830807D01*
G01X807776Y892519D02*
Y883464D01*
G01X808760D02*
Y892519D01*
G01X810925D02*
Y883464D01*
G01X811909D02*
Y892519D01*
G01X814075D02*
Y883464D01*
G01X815059D02*
Y892519D01*
G01X817224D02*
Y883464D01*
G01X818209D02*
Y892519D01*
G01X820374D02*
Y883464D01*
G01X821358D02*
Y892519D01*
G01X823524D02*
Y883464D01*
G01X824508D02*
Y892519D01*
G01X826673D02*
Y883464D01*
G01X827657D02*
Y892519D01*
G01X829823D02*
Y883464D01*
G01D02*
X827657D01*
G01X826673D02*
X824508D01*
G01X820374D02*
X818209D01*
G01X823524D02*
X821358D01*
G01X817224D02*
X815059D01*
G01X810925D02*
X808760D01*
G01X814075D02*
X811909D01*
G01X830807Y892519D02*
X832972D01*
G01X833957D02*
X836122D01*
G01X837106D02*
X839272D01*
G01X808760D02*
X810925D01*
G01X811909D02*
X814075D01*
G01X815059D02*
X817224D01*
G01X818209D02*
X820374D01*
G01X821358D02*
X823524D01*
G01X824508D02*
X826673D01*
G01X827657D02*
X829823D01*
G01X842206Y-1120610D02*
Y-1139623D01*
G01X852292Y331760D02*
X855215D01*
G01X859600Y337534D02*
X861548D01*
X862523Y336813D01*
G01D02*
X863497Y335369D01*
X863985Y333204D01*
X863497Y331038D01*
X862523Y329595D01*
G01X844009Y328873D02*
Y337534D01*
X846445D01*
X847420Y336813D01*
X847907Y336091D01*
Y334647D01*
X847420Y333926D01*
X846445Y333204D01*
X844009D01*
G01X851317Y328873D02*
X853753Y337534D01*
X856189Y328873D01*
G01X862523Y329595D02*
X861548Y328873D01*
X859600D01*
Y337534D01*
G01X867323Y845668D02*
Y871653D01*
G01Y845668D02*
Y871653D01*
G01X902134Y840550D02*
X872441D01*
G01X867323Y845668D02*
G03X872441Y840550I5118J0D01*
G01X867323Y845668D02*
G03X872441Y840550I5118J0D01*
G01X867323Y871653D02*
G03X865354Y873621I-1969J-1D01*
G01X867323Y871653D02*
G03X865354Y873621I-1969J-1D01*
G01X856368Y881279D02*
X856614Y881572D01*
G01Y881237D02*
X856368Y880944D01*
G01X858173Y882410D02*
X858337Y882912D01*
G01X858132Y882242D02*
X857763Y881111D01*
G01X858583Y882912D02*
X857927Y880944D01*
G01X840256Y883464D02*
Y892519D01*
G01X842421D02*
Y883464D01*
G01X843406D02*
Y892519D01*
G01X845571D02*
Y883464D01*
G01X846555D02*
Y892519D01*
G01X848720D02*
Y883464D01*
G01X849705D02*
Y892519D01*
G01X851870D02*
Y883464D01*
G01X852854D02*
Y892519D01*
G01X855020D02*
Y883464D01*
G01X856004D02*
Y892519D01*
G01X856122Y880944D02*
Y882912D01*
G01X856368D02*
Y881279D01*
G01X856614Y881572D02*
Y881237D01*
G01X858169Y892519D02*
Y883464D01*
G01X860236Y892519D02*
Y875590D01*
G01D02*
Y892519D01*
G01X857598Y880944D02*
X856943Y882912D01*
G01X857763Y881111D02*
X857394Y882242D01*
G01X857189Y882912D02*
X857352Y882410D01*
G01X865354Y873621D02*
X862205D01*
G01X865354D02*
X862205D01*
G01X857927Y880944D02*
X857598D01*
G01X856368D02*
X856122D01*
G01X857394Y882242D02*
X858132D01*
G01X857352Y882410D02*
X858173D01*
G01X858337Y882912D02*
X858583D01*
G01X856943D02*
X857189D01*
G01X856122D02*
X856368D01*
G01X858169Y883464D02*
X856004D01*
G01X855020D02*
X852854D01*
G01X848720D02*
X846555D01*
G01X851870D02*
X849705D01*
G01X845571D02*
X843406D01*
G01X842421D02*
X840256D01*
G01X860236Y875590D02*
G03X862205Y873621I1969J0D01*
G01X860236Y875590D02*
G03X862205Y873621I1969J0D01*
G01X856299Y897637D02*
X860236Y892519D01*
G01X856299Y897637D02*
X860236Y892519D01*
G01X840256D02*
X842421D01*
G01X843406D02*
X845571D01*
G01X846555D02*
X848720D01*
G01X849705D02*
X851870D01*
G01X852854D02*
X855020D01*
G01X856004D02*
X858169D01*
G01X842206Y2171102D02*
Y2152090D01*
G01X986846Y-622649D02*
X887817D01*
G01X896478Y-616153D02*
X897200Y-613987D01*
X898643Y-612544D01*
X900809Y-611821D01*
X902974Y-612544D01*
X904418Y-613987D01*
X905139Y-616153D01*
X904418Y-618318D01*
X902974Y-619761D01*
X900809Y-620483D01*
X898643Y-619761D01*
X897200Y-618318D01*
X896478Y-616153D01*
G01X897200Y-622648D02*
X904418Y-609657D01*
G01X902461Y-19292D02*
X968012D01*
G01X906988Y-18308D02*
X918504D01*
G01X902461Y-17324D02*
X906988D01*
G01X902461Y-11221D02*
X906004D01*
G01X964469Y-3544D02*
X906004D01*
G01X968012Y-788D02*
X902461D01*
G01X908465Y5905D02*
X905709D01*
G01X902461Y-788D02*
Y-19292D01*
G01X905709Y5905D02*
Y-788D01*
G01X906004Y-3544D02*
Y-17324D01*
G01X906988Y-3544D02*
Y-18308D01*
G01X906004Y-17324D02*
X904035Y-19292D01*
G01X873425Y115156D02*
X1021063D01*
G01X873425Y262794D02*
Y115156D01*
G01X905435Y160712D02*
X907384Y159269D01*
X907871Y158547D01*
Y157103D01*
X907384Y156382D01*
X906409Y155660D01*
X905435D01*
X904461Y156382D01*
X903973Y157103D01*
X903486Y157825D01*
G01X907871Y162878D02*
X907384Y163599D01*
X906409Y164321D01*
X905435D01*
X904461Y163599D01*
X903973Y162878D01*
Y162156D01*
X904461Y161434D01*
X905435Y160712D01*
G01X890214Y159990D02*
X902025D01*
G01X1021063Y262794D02*
X873425D01*
G01X902134Y625983D02*
Y840550D01*
G01X1008433Y625983D02*
X902134D01*
G01X921819Y820865D02*
G03X902134Y840550I-19685J0D01*
G01X935310Y-620483D02*
X934336Y-619761D01*
X933848Y-619040D01*
X933361Y-617596D01*
Y-614709D01*
X933848Y-613265D01*
X934336Y-612544D01*
X935310Y-611821D01*
X936285Y-612544D01*
X936772Y-613265D01*
X937259Y-614709D01*
Y-617596D01*
X936772Y-619040D01*
X936285Y-619761D01*
X935310Y-620483D01*
G01X913386Y-616153D02*
X914360Y-617596D01*
Y-618318D01*
G01D02*
X913386Y-619761D01*
X912411Y-620483D01*
X911437D01*
X910463Y-619761D01*
X909976Y-619040D01*
G01X925566Y-613265D02*
X926053Y-612544D01*
X927028Y-611821D01*
X928002D01*
X928976Y-612544D01*
X929464Y-613265D01*
Y-614709D01*
X928976Y-615431D01*
X928002Y-616153D01*
X927028Y-616874D01*
X926053Y-618318D01*
X925566Y-620483D01*
X929464D01*
G01X910463Y-612544D02*
X911437Y-611821D01*
X912411D01*
X913386Y-612544D01*
X913873Y-613265D01*
Y-613987D01*
X913386Y-614709D01*
X912411Y-615431D01*
X913386Y-616153D01*
G01X919720Y-620483D02*
X919232D01*
Y-619761D01*
X919720Y-620483D01*
G01X911437Y-615431D02*
X912411D01*
G01X934741Y-519413D02*
Y-520134D01*
X933767Y-521578D01*
G01X940101Y-522300D02*
X939613D01*
Y-521578D01*
X940101Y-522300D01*
G01X931818Y-517247D02*
X932793D01*
G01X1007227Y-524465D02*
X908198D01*
G01X916859Y-517969D02*
X917581Y-515804D01*
X919024Y-514360D01*
X921190Y-513638D01*
X923355Y-514360D01*
X924799Y-515804D01*
X925520Y-517969D01*
X924799Y-520134D01*
X923355Y-521578D01*
X921190Y-522300D01*
X919024Y-521578D01*
X917581Y-520134D01*
X916859Y-517969D01*
G01X917581Y-524465D02*
X924799Y-511473D01*
G01X930844Y-514360D02*
X931818Y-513638D01*
X932793D01*
X933767Y-514360D01*
X934254Y-515082D01*
Y-515804D01*
X933767Y-516525D01*
X932793Y-517247D01*
X933767Y-517969D01*
X934741Y-519413D01*
G01X933767Y-521578D02*
X932793Y-522300D01*
X931818D01*
X930844Y-521578D01*
X930357Y-520856D01*
G01X936220Y-18308D02*
X950000D01*
G01X935827Y-17718D02*
X934646D01*
G01X934252Y-17324D02*
X936220D01*
G01Y-15942D02*
X934252D01*
G01X946260Y-1D02*
X939961D01*
G01X938386D02*
X932087D01*
G01X946260Y4213D02*
X939961D01*
G01X938386D02*
X932087D01*
G01X936198Y4297D02*
X934274D01*
G01X936220Y4379D02*
X934252D01*
G01X946260Y4920D02*
X939961D01*
G01X938386D02*
X932087D01*
G01X934646Y5314D02*
X935827D01*
G01X939961Y5905D02*
X938386D01*
G01X936220Y4920D02*
X935827Y5314D01*
G01X934252Y-15942D02*
X934646Y-17718D01*
G01X932087Y5905D02*
Y-1D01*
G01X934252Y-18308D02*
Y-3544D01*
G01Y4379D02*
Y14763D01*
G01X934646Y6495D02*
Y5314D01*
G01X935827D02*
Y6495D01*
G01X936220Y14763D02*
Y4379D01*
G01Y-3544D02*
Y-18308D01*
G01X938386Y5905D02*
Y-1D01*
G01X939961Y5905D02*
Y-1D01*
G01Y-3544D02*
Y-17324D01*
G01X935827Y-17718D02*
X936220Y-15942D01*
G01X934646Y5314D02*
X934252Y4920D01*
G01X939961Y-17324D02*
G03X941929Y-19292I1968J0D01*
G01X934274Y4297D02*
G03X933504Y4920I-770J-164D01*
G01X936969D02*
G03X936198Y4297I-1J-788D01*
G01X912559Y-18610D02*
X926417D01*
G01X920472Y-18308D02*
X934252D01*
G01X927953Y-17718D02*
X926772D01*
G01X920079D02*
X918898D01*
G01X912205D02*
X911024D01*
G01X928307Y-17324D02*
X926417D01*
G01X912559D02*
X910669D01*
G01X918504D02*
X920472D01*
G01X928346Y-15942D02*
X926378D01*
G01X920472D02*
X918504D01*
G01X912598D02*
X910630D01*
G01X926417Y-10434D02*
X912559D01*
G01X926417Y-10040D02*
X912559D01*
G01Y-9056D02*
X926417D01*
G01X930512Y-1D02*
X924213D01*
G01X922638D02*
X916339D01*
G01X914764D02*
X908465D01*
G01X930512Y4213D02*
X924213D01*
G01X922638D02*
X916339D01*
G01X914764D02*
X908465D01*
G01X928324Y4297D02*
X926400D01*
G01X920450D02*
X918526D01*
G01X912576D02*
X910652D01*
G01X928346Y4379D02*
X926378D01*
G01X920472D02*
X918504D01*
G01X912598D02*
X910630D01*
G01X930512Y4920D02*
X924213D01*
G01X922638D02*
X916339D01*
G01X914764D02*
X908465D01*
G01X911024Y5314D02*
X912205D01*
G01X918898D02*
X920079D01*
G01X926772D02*
X927953D01*
G01X932087Y5905D02*
X930512D01*
G01X924213D02*
X922638D01*
G01X916339D02*
X914764D01*
G01X912598Y4920D02*
X912205Y5314D01*
G01X920472Y4920D02*
X920079Y5314D01*
G01X928346Y4920D02*
X927953Y5314D01*
G01X910630Y-15942D02*
X911024Y-17718D01*
G01X918504Y-15942D02*
X918898Y-17718D01*
G01X926378Y-15942D02*
X926772Y-17718D01*
G01X908465Y5905D02*
Y-1D01*
G01X910630Y-15942D02*
Y-3544D01*
G01Y4379D02*
Y14763D01*
G01X910669Y-18308D02*
Y-3544D01*
G01X911024Y6495D02*
Y5314D01*
G01X912205D02*
Y6495D01*
G01X912559Y-3544D02*
Y-19292D01*
G01X912598Y14763D02*
Y4379D01*
G01Y-3544D02*
Y-15942D01*
G01X914764Y5905D02*
Y-1D01*
G01Y-788D02*
Y-9056D01*
G01X916339Y5905D02*
Y-1D01*
G01X918504Y-3544D02*
Y-18308D01*
G01Y4379D02*
Y14763D01*
G01X918898Y6495D02*
Y5314D01*
G01X920079D02*
Y6495D01*
G01X920472Y14763D02*
Y4379D01*
G01Y-18308D02*
Y-3544D01*
G01X922638Y5905D02*
Y-1D01*
G01X924213Y5905D02*
Y-1D01*
G01Y-9056D02*
Y-788D01*
G01X926378Y-15942D02*
Y-3544D01*
G01Y4379D02*
Y14763D01*
G01X926417Y-19292D02*
Y-3544D01*
G01X926772Y6495D02*
Y5314D01*
G01X927953D02*
Y6495D01*
G01X928307Y-18308D02*
Y-3544D01*
G01X928346Y14763D02*
Y4379D01*
G01Y-3544D02*
Y-15942D01*
G01X930512Y5905D02*
Y-1D01*
G01Y-3544D02*
Y-17324D01*
G01X912205Y-17718D02*
X912598Y-15942D01*
G01X920079Y-17718D02*
X920472Y-15942D01*
G01X927953Y-17718D02*
X928346Y-15942D01*
G01X911024Y5314D02*
X910630Y4920D01*
G01X918898Y5314D02*
X918504Y4920D01*
G01X926772Y5314D02*
X926378Y4920D01*
G01X928543Y-19292D02*
G03X930512Y-17324I1J1968D01*
G01X926400Y4297D02*
G03X925630Y4920I-770J-164D01*
G01X929094D02*
G03X928324Y4297I0J-788D01*
G01X918526D02*
G03X917756Y4920I-770J-164D01*
G01X921220D02*
G03X920450Y4297I0J-788D01*
G01X913346Y4920D02*
G03X912576Y4297I0J-788D01*
G01X910652D02*
G03X909882Y4920I-770J-164D01*
G01X936220Y11810D02*
X934252D01*
G01X936220Y12794D02*
X934252D01*
G01X934646Y13188D02*
X935827D01*
G01Y14369D02*
X934646D01*
G01X936220Y14763D02*
X934252D01*
G01X936220Y12794D02*
X935827Y13188D01*
G01X934646Y14369D02*
X934252Y14763D01*
G01X934646Y14369D02*
Y13188D01*
G01X935827D02*
Y14369D01*
G01X934646Y13188D02*
X934252Y12794D01*
G01X935827Y14369D02*
X936220Y14763D01*
G01X935827Y6495D02*
X934646D01*
G01X936220Y6889D02*
X934252D01*
G01X934646Y6495D02*
X934252Y6889D01*
G01X935827Y6495D02*
X936220Y6889D01*
G01X928346Y11810D02*
X926378D01*
G01X920472D02*
X918504D01*
G01X912598D02*
X910630D01*
G01X928346Y12794D02*
X926378D01*
G01X920472D02*
X918504D01*
G01X912598D02*
X910630D01*
G01X911024Y13188D02*
X912205D01*
G01X918898D02*
X920079D01*
G01X926772D02*
X927953D01*
G01Y14369D02*
X926772D01*
G01X920079D02*
X918898D01*
G01X912205D02*
X911024D01*
G01X928346Y14763D02*
X926378D01*
G01X920472D02*
X918504D01*
G01X912598D02*
X910630D01*
G01X912598Y12794D02*
X912205Y13188D01*
G01X911024Y14369D02*
X910630Y14763D01*
G01X920472Y12794D02*
X920079Y13188D01*
G01X918898Y14369D02*
X918504Y14763D01*
G01X928346Y12794D02*
X927953Y13188D01*
G01X926772Y14369D02*
X926378Y14763D01*
G01X911024Y14369D02*
Y13188D01*
G01X912205D02*
Y14369D01*
G01X918898D02*
Y13188D01*
G01X920079D02*
Y14369D01*
G01X926772D02*
Y13188D01*
G01X927953D02*
Y14369D01*
G01X911024Y13188D02*
X910630Y12794D01*
G01X912205Y14369D02*
X912598Y14763D01*
G01X918898Y13188D02*
X918504Y12794D01*
G01X920079Y14369D02*
X920472Y14763D01*
G01X926772Y13188D02*
X926378Y12794D01*
G01X927953Y14369D02*
X928346Y14763D01*
G01X927953Y6495D02*
X926772D01*
G01X920079D02*
X918898D01*
G01X912205D02*
X911024D01*
G01X928346Y6889D02*
X926378D01*
G01X920472D02*
X918504D01*
G01X912598D02*
X910630D01*
G01X911024Y6495D02*
X910630Y6889D01*
G01X918898Y6495D02*
X918504Y6889D01*
G01X926772Y6495D02*
X926378Y6889D01*
G01X912205Y6495D02*
X912598Y6889D01*
G01X920079Y6495D02*
X920472Y6889D01*
G01X927953Y6495D02*
X928346Y6889D01*
G01X935155Y164321D02*
X937104D01*
X938078Y163599D01*
X939052Y162156D01*
G01D02*
X939539Y159990D01*
X939052Y157825D01*
X938078Y156382D01*
G01D02*
X937104Y155660D01*
X935155D01*
Y164321D01*
G01X923462Y155660D02*
X919564D01*
Y164321D01*
X923462D01*
G01X915666Y155660D02*
X911769D01*
Y164321D01*
X915666D01*
G01X911769Y159990D02*
X914205D01*
G01X919564D02*
X922000D01*
G01X936180Y285558D02*
X939624Y283799D01*
G01X939132Y283045D02*
X934457Y285558D01*
G01X939132Y288071D02*
X939624Y287317D01*
G01X934457Y285558D02*
X939132Y288071D01*
G01X939624Y287317D02*
X936180Y285558D01*
G01X939624Y283799D02*
X939132Y283045D01*
G01X932489Y291338D02*
Y279527D01*
G01X931012Y285055D02*
X924122D01*
G01Y286563D02*
X931012D01*
G01X922646Y291338D02*
X924122D01*
G01X931012D02*
X932489D01*
G01X924122D02*
Y286563D01*
G01X931012D02*
Y291338D01*
G01X932489Y279527D02*
X931012D01*
G01X924122D02*
X922646D01*
G01D02*
Y291338D01*
G01X924122Y285055D02*
Y279527D01*
G01X931012D02*
Y285055D01*
G01X932292Y630353D02*
Y642164D01*
G01X933768D02*
Y637390D01*
G01Y635882D02*
Y630353D01*
G01X942134D02*
X940658D01*
G01X933768D02*
X932292D01*
G01X940658Y635882D02*
X933768D01*
G01Y637390D02*
X940658D01*
G01X932292Y642164D02*
X933768D01*
G01X940658D02*
X942134D01*
G01X940658Y630353D02*
Y635882D01*
G01Y637390D02*
Y642164D01*
G01X926819Y645668D02*
X983748D01*
G01X926819D02*
X983748D01*
G01X921819Y650668D02*
G03X926819Y645668I5000J0D01*
G01X921819Y650668D02*
G03X926819Y645668I5000J0D01*
G01X921819Y650668D02*
Y820865D01*
G01Y650668D02*
Y840550D01*
G01Y844487D02*
Y891293D01*
G01X914602Y906829D02*
Y907803D01*
G01Y900982D02*
X916045Y899034D01*
X917489Y898059D01*
X919654Y897572D01*
Y901470D01*
G01X911714Y905855D02*
X910993Y906829D01*
Y907803D01*
X911714Y908778D01*
X912436Y909265D01*
X913158D01*
X913880Y908778D01*
X914602Y907803D01*
X915323Y908778D01*
X916767Y909752D01*
G01X918932Y908778D02*
X919654Y907803D01*
Y906829D01*
X918932Y905855D01*
X918210Y905368D01*
G01X916767Y909752D02*
X917489D01*
X918932Y908778D01*
G01X919654Y916573D02*
X910993D01*
X917489Y913162D01*
Y917547D01*
G01X912436Y897572D02*
X911714Y898059D01*
X910993Y899034D01*
Y900008D01*
X911714Y900982D01*
X912436Y901470D01*
X913880D01*
X914602Y900982D01*
G01X919654Y922906D02*
Y922419D01*
X918932D01*
X919654Y922906D01*
G01X910993Y930702D02*
X919654D01*
G01Y939959D02*
X910993D01*
X917489Y936548D01*
Y940933D01*
G01X935322Y1034427D02*
X935809Y1035871D01*
X937270Y1036593D01*
X938732Y1035871D01*
X939219Y1034427D01*
X938732Y1032984D01*
X938245Y1032262D01*
X937270Y1031540D01*
X936296Y1032262D01*
X935809Y1032984D01*
X935322Y1034427D01*
Y1037315D01*
X935809Y1038758D01*
X936296Y1039480D01*
X937270Y1040202D01*
X938245Y1039480D01*
X938732Y1038758D01*
G01X930937Y1036593D02*
X928988Y1035149D01*
X928014Y1033706D01*
X927526Y1031540D01*
X931424D01*
G01X927526Y1038758D02*
X928014Y1039480D01*
X928988Y1040202D01*
X929963D01*
X930937Y1039480D01*
X931424Y1038758D01*
Y1037315D01*
X930937Y1036593D01*
G01X921680Y1040202D02*
Y1031540D01*
G01X952476Y-1135820D02*
X952952Y-1131067D01*
X953427Y-1128215D01*
X953902Y-1126314D01*
X954378Y-1124413D01*
X950575D01*
G01X968440Y-611821D02*
Y-620483D01*
G01X973799Y-611821D02*
X974774Y-613265D01*
X975261Y-615431D01*
Y-616874D01*
X974774Y-619040D01*
X973799Y-620483D01*
G01X948952D02*
Y-611821D01*
X951388D01*
X952362Y-612544D01*
X952850Y-613265D01*
Y-614709D01*
X952362Y-615431D01*
X951388Y-616153D01*
X948952D01*
G01X958696Y-611821D02*
Y-620483D01*
G01X964543Y-611821D02*
Y-620483D01*
G01X943593Y-611821D02*
X942618Y-613265D01*
X942131Y-615431D01*
Y-616874D01*
X942618Y-619040D01*
X943593Y-620483D01*
G01X964543Y-616153D02*
X968440D01*
G01X956260Y-611821D02*
X961132D01*
G01X969333Y-522300D02*
Y-513638D01*
X971769D01*
X972743Y-514360D01*
X973230Y-515082D01*
Y-516525D01*
X972743Y-517247D01*
X971769Y-517969D01*
X969333D01*
G01X945947Y-515082D02*
X946434Y-514360D01*
X947409Y-513638D01*
X948383D01*
X949357Y-514360D01*
X949845Y-515082D01*
Y-516525D01*
X949357Y-517247D01*
G01X963974Y-513638D02*
X962999Y-515082D01*
X962512Y-517247D01*
Y-518691D01*
X962999Y-520856D01*
X963974Y-522300D01*
G01X949357Y-517247D02*
X947409Y-518691D01*
X946434Y-520134D01*
X945947Y-522300D01*
X949845D01*
G01X955691D02*
X954717Y-521578D01*
X954230Y-520856D01*
X953743Y-519413D01*
Y-516525D01*
X954230Y-515082D01*
X954717Y-514360D01*
X955691Y-513638D01*
X956666Y-514360D01*
X957153Y-515082D01*
X957640Y-516525D01*
Y-519413D01*
X957153Y-520856D01*
X956666Y-521578D01*
X955691Y-522300D01*
G01X968012Y-788D02*
Y-19292D01*
G01X944055Y-18610D02*
X957913D01*
G01X951969Y-18308D02*
X963484D01*
G01X959449Y-17718D02*
X958268D01*
G01X951575D02*
X950394D01*
G01X943701D02*
X942520D01*
G01X959803Y-17324D02*
X957913D01*
G01X944055D02*
X942165D01*
G01X950000D02*
X951969D01*
G01X963484D02*
X968012D01*
G01X959843Y-15942D02*
X957874D01*
G01X951969D02*
X950000D01*
G01X944094D02*
X942126D01*
G01X964469Y-11221D02*
X968012D01*
G01X944055Y-10434D02*
X957913D01*
G01X944055Y-10040D02*
X957913D01*
G01Y-9056D02*
X944055D01*
G01X954134Y-1D02*
X947835D01*
G01X955709D02*
X962008D01*
G01Y4213D02*
X955709D01*
G01X954134D02*
X947835D01*
G01X959820Y4297D02*
X957896D01*
G01X951946D02*
X950022D01*
G01X944072D02*
X942148D01*
G01X959843Y4379D02*
X957874D01*
G01X951969D02*
X950000D01*
G01X944094D02*
X942126D01*
G01X954134Y4920D02*
X947835D01*
G01X955709D02*
X962008D01*
G01X942520Y5314D02*
X943701D01*
G01X950394D02*
X951575D01*
G01X958268D02*
X959449D01*
G01X964764Y5905D02*
X962008D01*
G01X955709D02*
X954134D01*
G01X947835D02*
X946260D01*
G01X966437Y-19292D02*
X964469Y-17324D01*
G01X944094Y4920D02*
X943701Y5314D01*
G01X951969Y4920D02*
X951575Y5314D01*
G01X959843Y4920D02*
X959449Y5314D01*
G01X942126Y-15942D02*
X942520Y-17718D01*
G01X950000Y-15942D02*
X950394Y-17718D01*
G01X957874Y-15942D02*
X958268Y-17718D01*
G01X942126Y-15942D02*
Y-3544D01*
G01Y4379D02*
Y14763D01*
G01X942165Y-18308D02*
Y-3544D01*
G01X942520Y6495D02*
Y5314D01*
G01X943701D02*
Y6495D01*
G01X944055Y-3544D02*
Y-19292D01*
G01X944094Y14763D02*
Y4379D01*
G01Y-3544D02*
Y-15942D01*
G01X946260Y5905D02*
Y-1D01*
G01Y-788D02*
Y-9056D01*
G01X947835Y5905D02*
Y-1D01*
G01X950000Y-3544D02*
Y-18308D01*
G01Y4379D02*
Y14763D01*
G01X950394Y6495D02*
Y5314D01*
G01X951575D02*
Y6495D01*
G01X951969Y14763D02*
Y4379D01*
G01Y-3544D02*
Y-18308D01*
G01X954134Y5905D02*
Y-1D01*
G01X955709Y5905D02*
Y-1D01*
G01Y-9056D02*
Y-788D01*
G01X957874Y-15942D02*
Y-3544D01*
G01Y4379D02*
Y14763D01*
G01X957913Y-19292D02*
Y-3544D01*
G01X958268Y6495D02*
Y5314D01*
G01X959449D02*
Y6495D01*
G01X959803Y-3544D02*
Y-18308D01*
G01X959843Y14763D02*
Y4379D01*
G01Y-3544D02*
Y-15942D01*
G01X962008Y5905D02*
Y-1D01*
G01X963484Y-3544D02*
Y-18308D01*
G01X964469Y-3544D02*
Y-17324D01*
G01X964764Y5905D02*
Y-788D01*
G01X943701Y-17718D02*
X944094Y-15942D01*
G01X951575Y-17718D02*
X951969Y-15942D01*
G01X959449Y-17718D02*
X959843Y-15942D01*
G01X942520Y5314D02*
X942126Y4920D01*
G01X950394Y5314D02*
X950000Y4920D01*
G01X958268Y5314D02*
X957874Y4920D01*
G01X957896Y4297D02*
G03X957126Y4920I-770J-164D01*
G01X960591D02*
G03X959820Y4297I-1J-788D01*
G01X950022D02*
G03X949252Y4920I-770J-164D01*
G01X952717D02*
G03X951946Y4297I-1J-788D01*
G01X942148D02*
G03X941378Y4920I-770J-164D01*
G01X944843D02*
G03X944072Y4297I-1J-788D01*
G01X959843Y11810D02*
X957874D01*
G01X951969D02*
X950000D01*
G01X944094D02*
X942126D01*
G01X959843Y12794D02*
X957874D01*
G01X951969D02*
X950000D01*
G01X944094D02*
X942126D01*
G01X942520Y13188D02*
X943701D01*
G01X950394D02*
X951575D01*
G01X958268D02*
X959449D01*
G01Y14369D02*
X958268D01*
G01X951575D02*
X950394D01*
G01X943701D02*
X942520D01*
G01X959843Y14763D02*
X957874D01*
G01X951969D02*
X950000D01*
G01X944094D02*
X942126D01*
G01X959578Y16153D02*
X958982D01*
G01Y20916D02*
X959578D01*
G01X944094Y12794D02*
X943701Y13188D01*
G01X942520Y14369D02*
X942126Y14763D01*
G01X951969Y12794D02*
X951575Y13188D01*
G01X950394Y14369D02*
X950000Y14763D01*
G01X959843Y12794D02*
X959449Y13188D01*
G01X958268Y14369D02*
X957874Y14763D01*
G01X942520Y14369D02*
Y13188D01*
G01X943701D02*
Y14369D01*
G01X950394D02*
Y13188D01*
G01X951575D02*
Y14369D01*
G01X958268D02*
Y13188D01*
G01X958387Y19396D02*
Y20207D01*
G01X958982Y16153D02*
Y20105D01*
G01X959449Y13188D02*
Y14369D01*
G01X959578Y20916D02*
Y16153D01*
G01X958387Y20207D02*
X958982Y20916D01*
G01Y20105D02*
X958387Y19396D01*
G01X942520Y13188D02*
X942126Y12794D01*
G01X943701Y14369D02*
X944094Y14763D01*
G01X950394Y13188D02*
X950000Y12794D01*
G01X951575Y14369D02*
X951969Y14763D01*
G01X958268Y13188D02*
X957874Y12794D01*
G01X959449Y14369D02*
X959843Y14763D01*
G01X959449Y6495D02*
X958268D01*
G01X951575D02*
X950394D01*
G01X943701D02*
X942520D01*
G01X959843Y6889D02*
X957874D01*
G01X951969D02*
X950000D01*
G01X944094D02*
X942126D01*
G01X942520Y6495D02*
X942126Y6889D01*
G01X950394Y6495D02*
X950000Y6889D01*
G01X958268Y6495D02*
X957874Y6889D01*
G01X943701Y6495D02*
X944094Y6889D01*
G01X951575Y6495D02*
X951969Y6889D01*
G01X959449Y6495D02*
X959843Y6889D01*
G01X968284Y164321D02*
Y155660D01*
G01X974131Y164321D02*
Y155660D01*
X978029D01*
G01X946847D02*
X942950D01*
Y164321D01*
X946847D01*
G01X959028Y158547D02*
X961951D01*
G01X942950Y159990D02*
X945386D01*
G01X950258Y164321D02*
X955130D01*
G01X952694D02*
Y155660D01*
G01X958053D02*
X960489Y164321D01*
X962925Y155660D01*
G01X971367Y283799D02*
X972597Y284050D01*
G01X970136Y291338D02*
X968906Y291086D01*
G01X968168Y282291D02*
X966937D01*
G01X970136Y283799D02*
X971367D01*
G01X969890Y285055D02*
X971613D01*
G01Y290081D02*
X969890D01*
G01X971367Y291338D02*
X970136D01*
G01X968906Y284050D02*
X970136Y283799D01*
G01X972597Y291086D02*
X971367Y291338D01*
G01X969152Y285306D02*
X969890Y285055D01*
G01X972351Y289830D02*
X971613Y290081D01*
G01X967676Y284804D02*
X968906Y284050D01*
G01X973827Y290332D02*
X972597Y291086D01*
G01X968414Y285809D02*
X969152Y285306D01*
G01X973089Y289327D02*
X972351Y289830D01*
G01X966937Y285809D02*
X967676Y284804D01*
G01X974565Y289327D02*
X973827Y290332D01*
G01X968660Y281537D02*
X968168Y282291D01*
G01X967922Y286563D02*
X968414Y285809D01*
G01X973581Y288573D02*
X973089Y289327D01*
G01X969890Y290081D02*
X969152Y289830D01*
G01X971613Y285055D02*
X972351Y285306D01*
G01X966445Y287066D02*
X966937Y285809D01*
G01Y282291D02*
X967183Y281537D01*
G01X967676Y287317D02*
X967922Y286563D01*
G01X973827Y287819D02*
X973581Y288573D01*
G01X966445Y288071D02*
Y287066D01*
G01X967676Y287819D02*
Y287317D01*
G01X973827D02*
Y287819D01*
G01X974073Y285055D02*
Y284553D01*
G01D02*
X973827Y283045D01*
G01X967676Y290332D02*
X966937Y289327D01*
G01X969152Y289830D02*
X968414Y289327D01*
G01X972351Y285306D02*
X973089Y285809D01*
G01X972597Y284050D02*
X974073Y285055D01*
G01X968906Y291086D02*
X967676Y290332D01*
G01X967922Y288573D02*
X967676Y287819D01*
G01X973581Y286563D02*
X973827Y287317D01*
G01Y283045D02*
X973581Y282291D01*
G01X966937Y289327D02*
X966445Y288071D01*
G01X968414Y289327D02*
X967922Y288573D01*
G01X973089Y285809D02*
X973581Y286563D01*
G01Y282291D02*
X973089Y281537D01*
G01X971367Y279527D02*
X972597Y279778D01*
G01X970382Y279527D02*
X971367D01*
G01X971613Y280783D02*
X970136D01*
G01X969152Y279778D02*
X970382Y279527D01*
G01X970136Y280783D02*
X969398Y281034D01*
G01X967922Y280532D02*
X969152Y279778D01*
G01X969398Y281034D02*
X968660Y281537D01*
G01X967183D02*
X967922Y280532D01*
G01X972351Y281034D02*
X971613Y280783D01*
G01X973089Y281537D02*
X972351Y281034D01*
G01X972597Y279778D02*
X973827Y280532D01*
G01D02*
X974565Y281537D01*
G01X958325Y285558D02*
X959309Y285809D01*
G01Y287066D02*
X958079Y286814D01*
G01X946022Y290081D02*
X944792Y289830D01*
G01X946022Y291338D02*
X944546Y291086D01*
G01X957095Y282542D02*
X955619D01*
G01Y284804D02*
X957341D01*
G01X959309Y285809D02*
X960786D01*
G01Y287066D02*
X959309D01*
G01X956849Y290081D02*
X963985D01*
G01Y291338D02*
X955619D01*
G01X947498Y291086D02*
X946022Y291338D01*
G01X947252Y289830D02*
X946022Y290081D01*
G01X962016Y286814D02*
X960786Y287066D01*
G01Y285809D02*
X961770Y285558D01*
G01X948729Y290332D02*
X947498Y291086D01*
G01X963246Y286060D02*
X962016Y286814D01*
G01X947991Y289327D02*
X947252Y289830D01*
G01X961770Y285558D02*
X962508Y285055D01*
G01X949467Y289579D02*
X948729Y290332D01*
G01X963985Y285055D02*
X963246Y286060D01*
G01X943069Y283045D02*
X944054Y281537D01*
G01X948975Y287819D02*
X947991Y289327D01*
G01X962508Y285055D02*
X963000Y284301D01*
G01X949959Y288573D02*
X949467Y289579D01*
G01X955619Y282542D02*
X956111Y281537D01*
G01X957587D02*
X957095Y282542D01*
G01X964477Y283799D02*
X963985Y285055D01*
G01X941839Y283045D02*
X942085Y282291D01*
G01X950205Y287819D02*
X949959Y288573D01*
G01X963000Y284301D02*
X963246Y283547D01*
G01X941593Y284301D02*
X941839Y283045D01*
G01X950451Y286563D02*
X950205Y287819D01*
G01X942823Y284553D02*
X943069Y283045D01*
G01X949221Y286312D02*
X948975Y287819D01*
G01X941593Y286563D02*
Y284301D01*
G01X942823Y286312D02*
Y284553D01*
G01X949221D02*
Y286312D01*
G01X950451Y284301D02*
Y286563D01*
G01X955619Y291338D02*
Y284804D01*
G01X956849Y286060D02*
Y290081D01*
G01X963246Y283547D02*
Y283045D01*
G01X963985Y290081D02*
Y291338D01*
G01X964477Y282793D02*
Y283799D01*
G01X943069Y287819D02*
X942823Y286312D01*
G01X948975Y283045D02*
X949221Y284553D01*
G01X941839Y287819D02*
X941593Y286563D01*
G01X950205Y283045D02*
X950451Y284301D01*
G01X942085Y288573D02*
X941839Y287819D01*
G01X949959Y282291D02*
X950205Y283045D01*
G01X963246D02*
X963000Y282291D01*
G01X942577Y289579D02*
X942085Y288573D01*
G01X944054Y289327D02*
X943069Y287819D01*
G01X947991Y281537D02*
X948975Y283045D01*
G01X943315Y290332D02*
X942577Y289579D01*
G01X957341Y284804D02*
X958325Y285558D01*
G01X944792Y289830D02*
X944054Y289327D01*
G01X944546Y291086D02*
X943315Y290332D01*
G01X958079Y286814D02*
X956849Y286060D01*
G01X963985Y281537D02*
X964477Y282793D01*
G01X963000Y282291D02*
X962508Y281537D01*
G01X961770Y281034D02*
X960786Y280783D01*
G01Y279527D02*
X962016Y279778D01*
G01X946022Y280783D02*
X947252Y281034D01*
G01X946022Y279527D02*
X947498Y279778D01*
G01X953650Y279527D02*
X952420D01*
G01X959309D02*
X960786D01*
G01Y280783D02*
X959309D01*
G01X952420D02*
X953650D01*
G01X944546Y279778D02*
X946022Y279527D01*
G01X944792Y281034D02*
X946022Y280783D01*
G01X958079Y279778D02*
X959309Y279527D01*
G01Y280783D02*
X958325Y281034D01*
G01X943315Y280532D02*
X944546Y279778D01*
G01X956849Y280532D02*
X958079Y279778D01*
G01X944054Y281537D02*
X944792Y281034D01*
G01X958325D02*
X957587Y281537D01*
G01X942577Y281286D02*
X943315Y280532D01*
G01X956111Y281537D02*
X956849Y280532D01*
G01X942085Y282291D02*
X942577Y281286D01*
G01X952420Y279527D02*
Y280783D01*
G01X953650D02*
Y279527D01*
G01X949467Y281286D02*
X949959Y282291D01*
G01X948729Y280532D02*
X949467Y281286D01*
G01X947252Y281034D02*
X947991Y281537D01*
G01X962508D02*
X961770Y281034D01*
G01X947498Y279778D02*
X948729Y280532D01*
G01X962016Y279778D02*
X963246Y280532D01*
G01D02*
X963985Y281537D01*
G01X966494Y638143D02*
X967233Y638395D01*
G01X973630Y638143D02*
X974369Y638395D01*
G01Y637390D02*
X973630Y637138D01*
G01X966987Y637390D02*
X966494Y637138D01*
G01X965756Y637390D02*
X966494Y638143D01*
G01Y637138D02*
X966248Y636887D01*
G01X973138Y637641D02*
X973630Y638143D01*
G01Y637138D02*
X973138Y636636D01*
G01X966248Y636887D02*
X966002Y636384D01*
G01X969939Y630353D02*
X968709D01*
G01X973138D02*
X971908D01*
G01X974861Y637390D02*
X974369D01*
G01X967725D02*
X966987D01*
G01X967233Y638395D02*
X968217D01*
G01X971908D02*
X973138D01*
G01X974369D02*
X975353D01*
G01X966002Y636384D02*
Y630353D01*
G01X968709D02*
Y636384D01*
G01X969939D02*
Y630353D01*
G01X971908D02*
Y638395D01*
G01X973138D02*
Y637641D01*
G01Y636636D02*
Y630353D01*
G01X968217Y638395D02*
X968955Y638143D01*
G01X968217Y637138D02*
X967725Y637390D01*
G01X965018Y638143D02*
X965756Y637390D01*
G01X968463Y636887D02*
X968217Y637138D01*
G01X968955Y638143D02*
X969447Y637641D01*
G01X968709Y636384D02*
X968463Y636887D01*
G01X969447Y637641D02*
X969939Y636384D01*
G01X962557Y638143D02*
X963296Y638395D01*
G01Y637390D02*
X962557Y637138D01*
G01X953207Y640656D02*
X952469Y640154D01*
G01X955668Y631861D02*
X956406Y632364D01*
G01X952961Y641913D02*
X951731Y641159D01*
G01X955914Y630605D02*
X957144Y631358D01*
G01X951731Y641159D02*
X950993Y640405D01*
G01X962065Y637641D02*
X962557Y638143D01*
G01Y637138D02*
X962065Y636636D01*
G01X957144Y631358D02*
X957882Y632112D01*
G01X952469Y640154D02*
X951485Y638646D01*
G01X956406Y632364D02*
X957390Y633871D01*
G01X950500Y639400D02*
X950254Y638646D01*
G01X950993Y640405D02*
X950500Y639400D01*
G01X957882Y632112D02*
X958374Y633118D01*
G01X954437Y631610D02*
X955668Y631861D01*
G01X954437Y640908D02*
X953207Y640656D01*
G01X954437Y630353D02*
X955914Y630605D01*
G01X954437Y642164D02*
X952961Y641913D01*
G01X951485Y638646D02*
X951239Y637138D01*
G01X957390Y633871D02*
X957636Y635379D01*
G01X950254Y638646D02*
X950008Y637390D01*
G01X958620Y633871D02*
X958867Y635128D01*
G01X958374Y633118D02*
X958620Y633871D01*
G01X966002Y630353D02*
X964772D01*
G01X962065D02*
X960835D01*
G01X948040Y634374D02*
X944103D01*
G01Y635379D02*
X948040D01*
G01X963788Y637390D02*
X963296D01*
G01X948040D02*
X944103D01*
G01Y638395D02*
X948040D01*
G01X960835D02*
X962065D01*
G01X963296D02*
X964280D01*
G01X942134Y642164D02*
Y630353D01*
G01X944103Y634374D02*
Y635379D01*
G01Y637390D02*
Y638395D01*
G01X948040D02*
Y637390D01*
G01Y635379D02*
Y634374D01*
G01X950008Y637390D02*
Y635128D01*
G01X951239Y637138D02*
Y635379D01*
G01X957636D02*
Y637138D01*
G01X958867Y635128D02*
Y637390D01*
G01X960835Y630353D02*
Y638395D01*
G01X962065D02*
Y637641D01*
G01Y636636D02*
Y630353D01*
G01X964772D02*
Y636384D01*
G01X952961Y630605D02*
X954437Y630353D01*
G01X955914Y641913D02*
X954437Y642164D01*
G01X953207Y631861D02*
X954437Y631610D01*
G01X955668Y640656D02*
X954437Y640908D01*
G01X964280Y638395D02*
X965018Y638143D01*
G01X950008Y635128D02*
X950254Y633871D01*
G01X958867Y637390D02*
X958620Y638646D01*
G01X951239Y635379D02*
X951485Y633871D01*
G01X957636Y637138D02*
X957390Y638646D01*
G01X964280Y637138D02*
X963788Y637390D01*
G01X951731Y631358D02*
X952961Y630605D01*
G01X957144Y641159D02*
X955914Y641913D01*
G01X952469Y632364D02*
X953207Y631861D01*
G01X956406Y640154D02*
X955668Y640656D01*
G01X950993Y632112D02*
X951731Y631358D01*
G01X957882Y640405D02*
X957144Y641159D01*
G01X964526Y636887D02*
X964280Y637138D01*
G01X951485Y633871D02*
X952469Y632364D01*
G01X957390Y638646D02*
X956406Y640154D01*
G01X950500Y633118D02*
X950993Y632112D01*
G01X958374Y639400D02*
X957882Y640405D01*
G01X964772Y636384D02*
X964526Y636887D01*
G01X950254Y633871D02*
X950500Y633118D01*
G01X958620Y638646D02*
X958374Y639400D01*
G01X968885Y1040202D02*
Y1031540D01*
G01X1209843Y1029375D02*
X961811D01*
G01X945066Y1031540D02*
X944579D01*
Y1032262D01*
X945066Y1031540D01*
G01X964554D02*
X973215D01*
G01X964554Y1035871D02*
X973215D01*
G01X952861Y1031540D02*
X951887Y1032262D01*
X951399Y1032984D01*
X950912Y1034427D01*
Y1037315D01*
X951399Y1038758D01*
X951887Y1039480D01*
X952861Y1040202D01*
X953835Y1039480D01*
X954323Y1038758D01*
X954810Y1037315D01*
Y1034427D01*
X954323Y1032984D01*
X953835Y1032262D01*
X952861Y1031540D01*
G01X960656D02*
X959682Y1032262D01*
X959195Y1032984D01*
X958707Y1034427D01*
Y1037315D01*
X959195Y1038758D01*
X959682Y1039480D01*
X960656Y1040202D01*
X961631Y1039480D01*
X962118Y1038758D01*
X962605Y1037315D01*
Y1034427D01*
X962118Y1032984D01*
X961631Y1032262D01*
X960656Y1031540D01*
G01X952476Y2155892D02*
X952952Y2160645D01*
X953427Y2163497D01*
X953902Y2165399D01*
X954378Y2167300D01*
X950575D01*
G01X1140607Y-641170D02*
X989995Y-622649D01*
G01D02*
X986846D01*
G01X1010376Y-524465D02*
X1007227D01*
G01X979077Y-513638D02*
Y-522300D01*
G01X984924Y-513638D02*
Y-522300D01*
G01X988821Y-513638D02*
Y-522300D01*
G01X994180Y-513638D02*
X995155Y-515082D01*
X995642Y-517247D01*
Y-518691D01*
X995155Y-520856D01*
X994180Y-522300D01*
G01X984924Y-517969D02*
X988821D01*
G01X976641Y-513638D02*
X981513D01*
G01X997030Y160712D02*
X1000440D01*
G01X1001415Y159269D02*
X1000440Y160712D01*
X1000927Y161434D01*
Y163599D01*
X1000440Y164321D01*
X997030D01*
G01D02*
Y155660D01*
X1000440D01*
X1000927Y156382D01*
X1001415Y157103D01*
Y159269D01*
G01X995235Y286563D02*
X994496D01*
G01X991298D02*
X990806D01*
G01X984162D02*
X983424D01*
G01X980225D02*
X979733D01*
G01Y287568D02*
X980717D01*
G01X977272D02*
X978502D01*
G01X983670D02*
X984654D01*
G01X990806D02*
X991790D01*
G01X988345D02*
X989575D01*
G01X994743D02*
X995727D01*
G01X980717D02*
X981455Y287317D01*
G01X984654Y287568D02*
X985392Y287317D01*
G01X991790Y287568D02*
X992528Y287317D01*
G01X995727Y287568D02*
X996465Y287317D01*
G01X980717Y286312D02*
X980225Y286563D01*
G01X984654Y286312D02*
X984162Y286563D01*
G01X991790Y286312D02*
X991298Y286563D01*
G01X995727Y286312D02*
X995235Y286563D01*
G01X980963Y286060D02*
X980717Y286312D01*
G01X981455Y287317D02*
X982193Y286563D01*
G01X984900Y286060D02*
X984654Y286312D01*
G01X985392Y287317D02*
X985884Y286814D01*
G01X992036Y286060D02*
X991790Y286312D01*
G01X992528Y287317D02*
X993266Y286563D01*
G01X995973Y286060D02*
X995727Y286312D01*
G01X996465Y287317D02*
X996957Y286814D01*
G01X978994Y287317D02*
X979733Y287568D01*
G01Y286563D02*
X978994Y286312D01*
G01X982931Y287317D02*
X983670Y287568D01*
G01X990067Y287317D02*
X990806Y287568D01*
G01Y286563D02*
X990067Y286312D01*
G01X994004Y287317D02*
X994743Y287568D01*
G01X981209Y285558D02*
X980963Y286060D01*
G01X985146Y285558D02*
X984900Y286060D01*
G01X992282Y285558D02*
X992036Y286060D01*
G01X996219Y285558D02*
X995973Y286060D01*
G01X975057Y288071D02*
X974565Y289327D01*
G01X985884Y286814D02*
X986376Y285558D01*
G01X996957Y286814D02*
X997449Y285558D01*
G01X975304Y284553D02*
Y286312D01*
G01X978502Y287568D02*
Y286814D01*
G01X989575Y287568D02*
Y286814D01*
G01X975057Y282793D02*
X975304Y284553D01*
G01X978502Y286814D02*
X978994Y287317D01*
G01X983424Y286563D02*
X982931Y286312D01*
G01X994496Y286563D02*
X994004Y286312D01*
G01X975304D02*
X975057Y288071D01*
G01X974565Y281537D02*
X975057Y282793D01*
G01X982685Y286060D02*
X982439Y285558D01*
G01X993758Y286060D02*
X993512Y285558D01*
G01X978994Y286312D02*
X978502Y285809D01*
G01X982193Y286563D02*
X982931Y287317D01*
G01Y286312D02*
X982685Y286060D01*
G01X989575Y286814D02*
X990067Y287317D01*
G01Y286312D02*
X989575Y285809D01*
G01X993266Y286563D02*
X994004Y287317D01*
G01Y286312D02*
X993758Y286060D01*
G01X997449Y279527D02*
X996219D01*
G01X993512D02*
X992282D01*
G01X989575D02*
X988345D01*
G01X986376D02*
X985146D01*
G01X982439D02*
X981209D01*
G01X978502D02*
X977272D01*
G01D02*
Y287568D01*
G01X978502Y285809D02*
Y279527D01*
G01X981209D02*
Y285558D01*
G01X982439D02*
Y279527D01*
G01X985146D02*
Y285558D01*
G01X986376D02*
Y279527D01*
G01X988345D02*
Y287568D01*
G01X989575Y285809D02*
Y279527D01*
G01X992282D02*
Y285558D01*
G01X993512D02*
Y279527D01*
G01X996219D02*
Y285558D01*
G01X997449D02*
Y279527D01*
G01X987685Y645668D02*
X1146349D01*
G01X978059Y637390D02*
X977567Y637138D01*
G01Y638143D02*
X978306Y638395D01*
G01X976829Y637390D02*
X977567Y638143D01*
G01Y637138D02*
X977321Y636887D01*
G01D02*
X977075Y636384D01*
G01X981012Y630353D02*
X979782D01*
G01X977075D02*
X975845D01*
G01X978798Y637390D02*
X978059D01*
G01X978306Y638395D02*
X979290D01*
G01X975845Y630353D02*
Y636384D01*
G01X977075D02*
Y630353D01*
G01X979782D02*
Y636384D01*
G01X981012D02*
Y630353D01*
G01X975353Y638395D02*
X976091Y638143D01*
G01X979290Y638395D02*
X980028Y638143D01*
G01X975353Y637138D02*
X974861Y637390D01*
G01X979290Y637138D02*
X978798Y637390D01*
G01X975599Y636887D02*
X975353Y637138D01*
G01X976091Y638143D02*
X976829Y637390D01*
G01X979536Y636887D02*
X979290Y637138D01*
G01X980028Y638143D02*
X980520Y637641D01*
G01X975845Y636384D02*
X975599Y636887D01*
G01X979782Y636384D02*
X979536Y636887D01*
G01X980520Y637641D02*
X981012Y636384D01*
G01X983748Y645668D02*
G03X988748Y650668I0J5000D01*
G01X983748Y645668D02*
G03X988748Y650668I0J5000D01*
G01D02*
Y820865D01*
G01Y650668D02*
Y840550D01*
G01Y844487D02*
Y894596D01*
G01X1008433Y840550D02*
X988748D01*
G01X1008433D02*
G03X988748Y820865I0J-19685D01*
G01X977922Y912569D02*
Y909645D01*
X981531Y909158D01*
X980809Y910132D01*
Y911107D01*
X981531Y912081D01*
X982252Y912569D01*
X983696Y913056D01*
X985139Y912569D01*
X985861Y912081D01*
X986583Y911107D01*
Y910132D01*
X985861Y909158D01*
X985139Y908671D01*
G01X981531Y904286D02*
X982974Y902338D01*
X984418Y901363D01*
X986583Y900876D01*
Y904773D01*
G01X979365Y900876D02*
X978643Y901363D01*
X977922Y902338D01*
Y903312D01*
X978643Y904286D01*
X979365Y904773D01*
X980809D01*
X981531Y904286D01*
G01X986583Y926210D02*
Y925723D01*
X985861D01*
X986583Y926210D01*
G01X977922Y934006D02*
X986583D01*
G01Y943263D02*
X977922D01*
X984418Y939852D01*
Y944237D01*
G01X977922Y918415D02*
X986583D01*
G01X1003891Y1040202D02*
X1000968D01*
X1000481Y1036593D01*
X1001455Y1037315D01*
X1002430D01*
X1003404Y1036593D01*
X1003891Y1035871D01*
X1004378Y1034427D01*
X1003891Y1032984D01*
X1003404Y1032262D01*
X1002430Y1031540D01*
X1001455D01*
X1000481Y1032262D01*
X999994Y1032984D01*
G01X994147Y1040202D02*
Y1031540D01*
G01X986352D02*
X985865D01*
Y1032262D01*
X986352Y1031540D01*
G01X978557D02*
X977582Y1032262D01*
X977095Y1032984D01*
X976608Y1034427D01*
Y1037315D01*
X977095Y1038758D01*
X977582Y1039480D01*
X978557Y1040202D01*
X979531Y1039480D01*
X980018Y1038758D01*
X980506Y1037315D01*
Y1034427D01*
X980018Y1032984D01*
X979531Y1032262D01*
X978557Y1031540D01*
G01X1039557Y-659032D02*
X1032433Y-622203D01*
G01X1054044Y-690909D02*
X1039557Y-659032D01*
G01X1032433Y-622203D02*
X1029811Y-591401D01*
G01D02*
X1030912Y-562648D01*
G01X1036576Y-534381D02*
X1045950Y-509324D01*
G01X1030912Y-562648D02*
X1036576Y-534381D01*
G01X1140683Y-546151D02*
X1010376Y-524465D01*
G01X1044291Y67322D02*
X1041142D01*
G01Y70471D02*
X1044291D01*
G01X1041142Y67322D02*
Y70471D01*
G01X1021063Y115156D02*
Y262794D01*
G01X1015787Y257434D02*
X1015472D01*
G01X1016837D02*
X1016522D01*
G01X1014002D02*
X1013687D01*
G01X1015262Y258077D02*
X1014212D01*
G01X1015209Y258292D02*
X1014265D01*
G01X1014527Y259954D02*
X1014947D01*
G01X1016522D02*
X1016837D01*
G01X1009252Y260826D02*
X1019094D01*
G01X1009252D02*
X1019094Y250983D01*
G01X1014947Y259954D02*
X1015787Y257434D01*
G01X1015472D02*
X1015262Y258077D01*
G01X1014737Y259739D02*
X1015209Y258292D01*
G01X1016207Y259149D02*
Y259579D01*
G01X1016522Y257434D02*
Y259525D01*
G01X1016837Y259954D02*
Y257434D01*
G01X1019094Y260826D02*
Y250983D01*
G01X1014265Y258292D02*
X1014737Y259739D01*
G01X1014212Y258077D02*
X1014002Y257434D01*
G01X1013687D02*
X1014527Y259954D01*
G01X1016207Y259579D02*
X1016522Y259954D01*
G01Y259525D02*
X1016207Y259149D01*
G01X1008433Y840550D02*
Y625983D01*
G01X1018504Y871653D02*
Y845668D01*
G01Y871653D02*
Y845668D01*
G01X1013386Y840550D02*
X1008433D01*
G01X1013386D02*
X1396063D01*
G01X1013386D02*
G03X1018504Y845668I0J5118D01*
G01X1013386Y840550D02*
G03X1018504Y845668I0J5118D01*
G01X1032972Y892519D02*
Y883464D01*
G01X1033957D02*
Y892519D01*
G01X1036122D02*
Y883464D01*
G01X1037106D02*
Y892519D01*
G01X1039272D02*
Y883464D01*
G01X1040256D02*
Y892519D01*
G01X1042421Y883464D02*
X1040256D01*
G01X1039272D02*
X1037106D01*
G01X1036122D02*
X1033957D01*
G01X1027491Y882912D02*
X1027346Y882870D01*
G01X1028553Y882912D02*
X1028408Y882870D01*
G01X1027491Y880944D02*
X1027636Y880986D01*
G01X1028553Y880944D02*
X1028698Y880986D01*
G01X1027491Y882703D02*
X1027370Y882661D01*
G01X1028553Y882703D02*
X1028433Y882661D01*
G01X1027491Y881153D02*
X1027611Y881195D01*
G01X1028553Y881153D02*
X1028674Y881195D01*
G01X1027346Y882870D02*
X1027225Y882745D01*
G01X1028408Y882870D02*
X1028288Y882745D01*
G01X1027636Y880986D02*
X1027756Y881111D01*
G01X1028698Y880986D02*
X1028819Y881111D01*
G01X1027370Y882661D02*
X1027298Y882577D01*
G01X1028433Y882661D02*
X1028360Y882577D01*
G01X1027611Y881195D02*
X1027684Y881279D01*
G01X1028674Y881195D02*
X1028746Y881279D01*
G01X1027225Y882745D02*
X1027153Y882619D01*
G01X1028288Y882745D02*
X1028215Y882619D01*
G01X1027756Y881111D02*
X1027829Y881237D01*
G01X1028819Y881111D02*
X1028891Y881237D01*
G01X1029326Y881279D02*
X1029471Y881572D01*
G01Y881237D02*
X1029326Y880944D01*
G01X1027298Y882577D02*
X1027201Y882326D01*
G01X1027684Y881279D02*
X1027781Y881530D01*
G01X1028360Y882577D02*
X1028263Y882326D01*
G01X1028746Y881279D02*
X1028843Y881530D01*
G01X1027104Y882451D02*
X1027080Y882326D01*
G01X1027877Y881405D02*
X1027901Y881530D01*
G01X1028167Y882451D02*
X1028143Y882326D01*
G01X1028940Y881405D02*
X1028964Y881530D01*
G01X1030389Y882410D02*
X1030485Y882912D01*
G01X1030365Y882242D02*
X1030147Y881111D01*
G01X1030630Y882912D02*
X1030244Y880944D01*
G01X1027153Y882619D02*
X1027104Y882451D01*
G01X1028215Y882619D02*
X1028167Y882451D01*
G01X1027829Y881237D02*
X1027877Y881405D01*
G01X1028891Y881237D02*
X1028940Y881405D01*
G01X1027201Y882326D02*
X1027177Y882075D01*
G01X1027781Y881530D02*
X1027805Y881781D01*
G01X1028263Y882326D02*
X1028239Y882075D01*
G01X1028843Y881530D02*
X1028867Y881781D01*
G01X1027080Y882326D02*
X1027056Y882116D01*
G01X1027901Y881530D02*
X1027926Y881740D01*
G01X1028143Y882326D02*
X1028119Y882116D01*
G01X1028964Y881530D02*
X1028988Y881740D01*
G01X1025591Y892519D02*
Y875590D01*
G01Y892519D02*
Y875590D01*
G01X1027056Y882116D02*
Y881740D01*
G01X1027177Y882075D02*
Y881781D01*
G01X1027657Y883464D02*
Y890845D01*
G01X1027805Y881781D02*
Y882075D01*
G01X1027926Y881740D02*
Y882116D01*
G01X1028119D02*
Y881740D01*
G01X1028239Y882075D02*
Y881781D01*
G01X1028867D02*
Y882075D01*
G01X1028988Y881740D02*
Y882116D01*
G01X1029181Y880944D02*
Y882912D01*
G01X1029326D02*
Y881279D01*
G01X1029471Y881572D02*
Y881237D01*
G01X1029823Y890845D02*
Y883464D01*
G01X1030807D02*
Y892519D01*
G01X1027177Y881781D02*
X1027201Y881530D01*
G01X1027805Y882075D02*
X1027781Y882326D01*
G01X1028239Y881781D02*
X1028263Y881530D01*
G01X1028867Y882075D02*
X1028843Y882326D01*
G01X1030050Y880944D02*
X1029664Y882912D01*
G01X1027080Y881530D02*
X1027104Y881405D01*
G01X1027901Y882326D02*
X1027877Y882451D01*
G01X1028143Y881530D02*
X1028167Y881405D01*
G01X1028964Y882326D02*
X1028940Y882451D01*
G01X1030147Y881111D02*
X1029930Y882242D01*
G01X1029809Y882912D02*
X1029906Y882410D01*
G01X1027056Y881740D02*
X1027080Y881530D01*
G01X1027926Y882116D02*
X1027901Y882326D01*
G01X1028119Y881740D02*
X1028143Y881530D01*
G01X1028988Y882116D02*
X1028964Y882326D01*
G01X1023622Y873621D02*
X1020472D01*
G01X1023622D02*
X1020472D01*
G01X1030244Y880944D02*
X1030050D01*
G01X1029326D02*
X1029181D01*
G01X1029930Y882242D02*
X1030365D01*
G01X1029906Y882410D02*
X1030389D01*
G01X1030485Y882912D02*
X1030630D01*
G01X1029664D02*
X1029809D01*
G01X1029181D02*
X1029326D01*
G01X1032972Y883464D02*
X1030807D01*
G01X1029823D02*
X1027657D01*
G01X1027201Y881530D02*
X1027298Y881279D01*
G01X1027781Y882326D02*
X1027684Y882577D01*
G01X1028263Y881530D02*
X1028360Y881279D01*
G01X1028843Y882326D02*
X1028746Y882577D01*
G01X1027104Y881405D02*
X1027153Y881237D01*
G01X1028167Y881405D02*
X1028215Y881237D01*
G01X1027877Y882451D02*
X1027829Y882619D01*
G01X1028940Y882451D02*
X1028891Y882619D01*
G01X1027346Y880986D02*
X1027491Y880944D01*
G01X1028408Y880986D02*
X1028553Y880944D01*
G01X1027636Y882870D02*
X1027491Y882912D01*
G01X1028698Y882870D02*
X1028553Y882912D01*
G01X1027153Y881237D02*
X1027225Y881111D01*
G01X1028215Y881237D02*
X1028288Y881111D01*
G01X1027829Y882619D02*
X1027756Y882745D01*
G01X1028891Y882619D02*
X1028819Y882745D01*
G01X1027370Y881195D02*
X1027491Y881153D01*
G01X1028433Y881195D02*
X1028553Y881153D01*
G01X1027611Y882661D02*
X1027491Y882703D01*
G01X1028674Y882661D02*
X1028553Y882703D01*
G01X1027225Y881111D02*
X1027346Y880986D01*
G01X1028288Y881111D02*
X1028408Y880986D01*
G01X1027756Y882745D02*
X1027636Y882870D01*
G01X1028819Y882745D02*
X1028698Y882870D01*
G01X1027298Y881279D02*
X1027370Y881195D01*
G01X1028360Y881279D02*
X1028433Y881195D01*
G01X1027684Y882577D02*
X1027611Y882661D01*
G01X1028746Y882577D02*
X1028674Y882661D01*
G01X1023622Y873621D02*
G03X1025591Y875590I0J1969D01*
G01X1020472Y873621D02*
G03X1018504Y871653I1J-1969D01*
G01X1023622Y873621D02*
G03X1025591Y875590I0J1969D01*
G01X1020472Y873621D02*
G03X1018504Y871653I1J-1969D01*
G01X1037106Y892519D02*
X1039272D01*
G01X1033957D02*
X1036122D01*
G01X1040256D02*
X1042421D01*
G01X1029528Y897637D02*
X1025591Y892519D01*
G01D02*
X1029528Y897637D01*
G01X1027657Y890845D02*
X1029823D01*
G01X1025591Y892519D02*
X1205512D01*
G01X1030807D02*
X1032972D01*
G01X1029528Y897637D02*
X1201575D01*
G01X1029528D02*
X1201575D01*
G01X1062747Y-1120610D02*
Y-1139623D01*
G01X1071091Y-776849D02*
X1074014D01*
G01X1070116Y-779736D02*
X1072552Y-771075D01*
X1074988Y-779736D01*
G01X1055500Y-773962D02*
X1058423Y-776127D01*
X1058911Y-776849D01*
Y-778292D01*
X1058423Y-779014D01*
X1057449Y-779736D01*
X1056474D01*
X1055500Y-779014D01*
X1054526Y-777571D01*
G01X1058911Y-772518D02*
X1058423Y-771796D01*
X1057449Y-771075D01*
X1056474D01*
X1055500Y-771796D01*
X1055013Y-772518D01*
Y-773240D01*
X1055500Y-773962D01*
G01X1063295Y-779014D02*
X1062321Y-777571D01*
X1061834Y-775405D01*
X1062321Y-773240D01*
G01D02*
X1063295Y-771796D01*
X1064270Y-771075D01*
X1065244D01*
X1066219Y-771796D01*
X1066706Y-772518D01*
G01Y-778292D02*
X1066219Y-779014D01*
X1065244Y-779736D01*
X1064270D01*
X1063295Y-779014D01*
G01X1079658Y-708368D02*
X1054044Y-690909D01*
G01X1045950Y-509324D02*
X1059698Y-486488D01*
G01X1046236Y-508849D02*
X1250544D01*
G01X1046236D02*
X1250544D01*
G01X1059698Y-486488D02*
X1078001Y-468929D01*
G01X1066732Y67322D02*
X1069882D01*
G01X1068238Y68562D02*
X1068140D01*
G01X1068583D02*
X1068509D01*
G01X1066339Y68660D02*
X1066250D01*
G01X1066147D02*
X1066132D01*
G01X1066230D02*
X1066216D01*
G01X1066250Y68675D02*
X1066324D01*
G01Y68708D02*
X1066260D01*
G01Y68723D02*
X1066324D01*
G01Y68763D02*
X1066250D01*
G01Y68779D02*
X1066339D01*
G01X1066171D02*
X1066191D01*
G01X1068140Y69153D02*
X1068238D01*
G01X1068509D02*
X1068583D01*
G01X1069882Y70471D02*
X1066732D01*
G01X1068238Y69153D02*
X1068423Y68864D01*
G01X1068361Y68801D02*
X1068140Y69153D01*
G01X1066216Y68660D02*
X1066181Y68763D01*
G01X1066191Y68779D02*
X1066230Y68660D01*
G01X1066112Y68779D02*
Y68660D01*
G01X1066250D02*
Y68675D01*
G01Y68763D02*
Y68779D01*
G01X1066260Y68708D02*
Y68723D01*
G01X1066324D02*
Y68763D01*
G01Y68675D02*
Y68708D01*
G01X1066339Y68779D02*
Y68660D01*
G01X1066732Y70471D02*
Y67322D01*
G01X1067553D02*
Y70471D01*
G01X1067717D02*
Y67322D01*
G01X1068504D02*
Y70471D01*
G01X1068509Y68951D02*
Y69153D01*
G01Y68562D02*
Y68851D01*
G01X1068583Y69153D02*
Y68562D01*
G01X1069882Y67322D02*
Y70471D01*
G01X1066132Y68660D02*
X1066171Y68779D01*
G01X1066181Y68763D02*
X1066147Y68660D01*
G01X1068140Y68562D02*
X1068361Y68801D01*
G01X1068509Y68851D02*
X1068238Y68562D01*
G01X1068423Y68864D02*
X1068509Y68951D01*
G01X1065709Y68675D02*
X1065719Y68678D01*
G01X1065687Y68763D02*
X1065677Y68761D01*
G01X1064816Y68675D02*
X1064826Y68678D01*
G01X1064592Y68675D02*
X1064602Y68678D01*
G01X1064793Y68763D02*
X1064783Y68761D01*
G01X1064570Y68763D02*
X1064560Y68761D01*
G01X1063711Y68776D02*
X1063720Y68779D01*
G01X1046024Y68675D02*
X1046033Y68678D01*
G01X1046002Y68763D02*
X1045992Y68761D01*
G01X1045131Y68675D02*
X1045141Y68678D01*
G01X1044907Y68675D02*
X1044917Y68678D01*
G01X1045108Y68763D02*
X1045098Y68761D01*
G01X1044885Y68763D02*
X1044875Y68761D01*
G01X1044026Y68776D02*
X1044035Y68779D01*
G01X1065721Y68663D02*
X1065709Y68660D01*
G01X1065197D02*
X1065209Y68663D01*
G01X1065674Y68776D02*
X1065687Y68779D01*
G01X1065032Y68673D02*
X1065044Y68675D01*
G01X1064828Y68663D02*
X1064816Y68660D01*
G01X1065185Y68736D02*
X1065172Y68733D01*
G01X1064700Y68660D02*
X1064712Y68663D01*
G01X1065185Y68779D02*
X1065172Y68776D01*
G01X1064604Y68663D02*
X1064592Y68660D01*
G01X1064700Y68703D02*
X1064712Y68706D01*
G01X1064781Y68776D02*
X1064793Y68779D01*
G01X1064688D02*
X1064675Y68776D01*
G01X1064173Y68673D02*
X1064186Y68675D01*
G01X1064557Y68776D02*
X1064570Y68779D01*
G01X1064390Y68776D02*
X1064402Y68779D01*
G01X1064033Y68723D02*
X1064045Y68726D01*
G01X1063735Y68673D02*
X1063748Y68675D01*
G01X1063873Y68776D02*
X1063885Y68779D01*
G01X1063723Y68766D02*
X1063711Y68763D01*
G01X1046036Y68663D02*
X1046024Y68660D01*
G01X1045512D02*
X1045524Y68663D01*
G01X1045989Y68776D02*
X1046002Y68779D01*
G01X1045347Y68673D02*
X1045359Y68675D01*
G01X1045143Y68663D02*
X1045131Y68660D01*
G01X1045500Y68736D02*
X1045487Y68733D01*
G01X1045015Y68660D02*
X1045027Y68663D01*
G01X1045500Y68779D02*
X1045487Y68776D01*
G01X1044919Y68663D02*
X1044907Y68660D01*
G01X1045015Y68703D02*
X1045027Y68706D01*
G01X1045096Y68776D02*
X1045108Y68779D01*
G01X1045003D02*
X1044990Y68776D01*
G01X1044488Y68673D02*
X1044501Y68675D01*
G01X1044872Y68776D02*
X1044885Y68779D01*
G01X1044705Y68776D02*
X1044717Y68779D01*
G01X1044348Y68723D02*
X1044360Y68726D01*
G01X1044050Y68673D02*
X1044063Y68675D01*
G01X1044188Y68776D02*
X1044200Y68779D01*
G01X1044038Y68766D02*
X1044026Y68763D01*
G01X1065047Y68663D02*
X1065030Y68660D01*
G01X1064188Y68663D02*
X1064171Y68660D01*
G01X1063750Y68663D02*
X1063733Y68660D01*
G01X1045362Y68663D02*
X1045344Y68660D01*
G01X1044503Y68663D02*
X1044486Y68660D01*
G01X1044065Y68663D02*
X1044048Y68660D01*
G01X1063976Y67322D02*
X1060827D01*
G01X1042520D02*
X1048819D01*
G01X1047047D02*
X1050197D01*
G01X1062205D02*
X1068504D01*
G01X1062362Y68562D02*
X1062264D01*
G01X1048553D02*
X1048455D01*
G01X1048898D02*
X1048824D01*
G01X1042677D02*
X1042579D01*
G01X1066112Y68660D02*
X1066024D01*
G01X1065891D02*
X1065876D01*
G01X1065783D02*
X1065768D01*
G01X1065709D02*
X1065687D01*
G01X1065549D02*
X1065534D01*
G01X1065633D02*
X1065618D01*
G01X1065515D02*
X1065421D01*
G01X1065269D02*
X1065254D01*
G01X1065030D02*
X1065020D01*
G01X1064948D02*
X1064934D01*
G01X1064816D02*
X1064793D01*
G01X1064592D02*
X1064570D01*
G01X1064461D02*
X1064402D01*
G01X1064255D02*
X1064232D01*
G01X1064350D02*
X1064328D01*
G01X1064171D02*
X1064161D01*
G01X1064104D02*
X1064045D01*
G01X1063979D02*
X1063964D01*
G01X1063944D02*
X1063885D01*
G01X1063733D02*
X1063728D01*
G01X1063667D02*
X1063573D01*
G01X1046654D02*
X1046565D01*
G01X1046462D02*
X1046447D01*
G01X1046545D02*
X1046531D01*
G01X1046427D02*
X1046339D01*
G01X1046206D02*
X1046191D01*
G01X1046098D02*
X1046083D01*
G01X1046024D02*
X1046002D01*
G01X1045864D02*
X1045849D01*
G01X1045948D02*
X1045933D01*
G01X1045830D02*
X1045736D01*
G01X1045583D02*
X1045569D01*
G01X1045344D02*
X1045335D01*
G01X1045263D02*
X1045249D01*
G01X1045131D02*
X1045108D01*
G01X1044907D02*
X1044885D01*
G01X1044776D02*
X1044717D01*
G01X1044570D02*
X1044547D01*
G01X1044665D02*
X1044643D01*
G01X1044486D02*
X1044476D01*
G01X1044419D02*
X1044360D01*
G01X1044294D02*
X1044279D01*
G01X1044259D02*
X1044200D01*
G01X1044048D02*
X1044043D01*
G01X1043981D02*
X1043888D01*
G01X1046260D02*
X1046319D01*
G01X1045500D02*
X1045512D01*
G01X1045005D02*
X1045015D01*
G01X1065185D02*
X1065197D01*
G01X1064690D02*
X1064700D01*
G01X1065945D02*
X1066004D01*
G01X1064702Y68673D02*
X1064688D01*
G01X1045017D02*
X1045003D01*
G01X1046257D02*
X1046304D01*
G01X1045790D02*
X1045830D01*
G01X1045736D02*
X1045775D01*
G01X1045497D02*
X1045515D01*
G01X1045337D02*
X1045347D01*
G01X1044478D02*
X1044488D01*
G01X1044358D02*
X1044405D01*
G01X1044041D02*
X1044050D01*
G01X1043942D02*
X1043981D01*
G01X1043888D02*
X1043927D01*
G01X1065475D02*
X1065515D01*
G01X1065421D02*
X1065460D01*
G01X1065182D02*
X1065200D01*
G01X1065022D02*
X1065032D01*
G01X1064163D02*
X1064173D01*
G01X1064043D02*
X1064090D01*
G01X1063726D02*
X1063735D01*
G01X1063627D02*
X1063667D01*
G01X1063573D02*
X1063612D01*
G01X1065943D02*
X1065989D01*
G01X1046565Y68675D02*
X1046639D01*
G01X1046339D02*
X1046413D01*
G01X1046002D02*
X1046024D01*
G01X1045108D02*
X1045131D01*
G01X1044885D02*
X1044907D01*
G01X1044715D02*
X1044761D01*
G01X1044198D02*
X1044245D01*
G01X1065687D02*
X1065709D01*
G01X1064793D02*
X1064816D01*
G01X1064570D02*
X1064592D01*
G01X1064400D02*
X1064446D01*
G01X1063883D02*
X1063930D01*
G01X1066024D02*
X1066098D01*
G01X1064668Y68688D02*
X1064656D01*
G01X1044983D02*
X1044970D01*
G01X1045372D02*
X1045384D01*
G01X1044513D02*
X1044525D01*
G01X1044075D02*
X1044087D01*
G01X1065057D02*
X1065069D01*
G01X1064198D02*
X1064210D01*
G01X1063760D02*
X1063772D01*
G01X1045967Y68690D02*
X1045982D01*
G01X1045074D02*
X1045089D01*
G01X1044850D02*
X1044865D01*
G01X1065652D02*
X1065667D01*
G01X1064759D02*
X1064774D01*
G01X1064535D02*
X1064550D01*
G01X1045003Y68703D02*
X1045015D01*
G01X1064688D02*
X1064700D01*
G01X1066098Y68708D02*
X1066033D01*
G01X1065618D02*
X1065549D01*
G01X1046639D02*
X1046575D01*
G01X1046413D02*
X1046348D01*
G01X1045933D02*
X1045864D01*
G01X1065989Y68710D02*
X1065943D01*
G01X1064446D02*
X1064400D01*
G01X1064090D02*
X1064043D01*
G01X1063930D02*
X1063883D01*
G01X1046304D02*
X1046257D01*
G01X1044761D02*
X1044715D01*
G01X1044405D02*
X1044358D01*
G01X1044245D02*
X1044198D01*
G01X1065689Y68713D02*
X1065652D01*
G01X1064796D02*
X1064759D01*
G01X1063735D02*
X1063726D01*
G01X1046004D02*
X1045967D01*
G01X1045111D02*
X1045074D01*
G01X1044050D02*
X1044041D01*
G01X1045000Y68716D02*
X1045017D01*
G01X1064685D02*
X1064702D01*
G01X1065200Y68723D02*
X1065182D01*
G01X1065126D02*
X1065091D01*
G01X1064515D02*
X1064481D01*
G01X1045515D02*
X1045497D01*
G01X1045441D02*
X1045406D01*
G01X1044830D02*
X1044796D01*
G01X1046575D02*
X1046639D01*
G01X1046348D02*
X1046413D01*
G01X1045864D02*
X1045933D01*
G01X1044041D02*
X1044050D01*
G01X1065549D02*
X1065618D01*
G01X1063726D02*
X1063735D01*
G01X1066033D02*
X1066098D01*
G01X1065989Y68726D02*
X1065948D01*
G01X1064446D02*
X1064400D01*
G01X1063930D02*
X1063883D01*
G01X1046304D02*
X1046263D01*
G01X1044761D02*
X1044715D01*
G01X1044245D02*
X1044198D01*
G01X1044360D02*
X1044405D01*
G01X1064045D02*
X1064090D01*
G01X1045982Y68728D02*
X1046004D01*
G01X1045089D02*
X1045111D01*
G01X1065667D02*
X1065689D01*
G01X1064774D02*
X1064796D01*
G01X1065197Y68736D02*
X1065185D01*
G01X1045512D02*
X1045500D01*
G01X1045406D02*
X1045441D01*
G01X1044796D02*
X1044830D01*
G01X1065091D02*
X1065126D01*
G01X1064481D02*
X1064515D01*
G01X1064550Y68748D02*
X1064535D01*
G01X1044865D02*
X1044850D01*
G01X1063775Y68751D02*
X1063763D01*
G01X1044090D02*
X1044078D01*
G01X1045531D02*
X1045544D01*
G01X1065217D02*
X1065229D01*
G01X1066098Y68763D02*
X1066024D01*
G01X1065876D02*
X1065802D01*
G01X1065709D02*
X1065687D01*
G01X1064816D02*
X1064793D01*
G01X1064592D02*
X1064570D01*
G01X1046639D02*
X1046565D01*
G01X1046413D02*
X1046339D01*
G01X1046191D02*
X1046117D01*
G01X1046024D02*
X1046002D01*
G01X1045131D02*
X1045108D01*
G01X1044907D02*
X1044885D01*
G01X1044715D02*
X1044761D01*
G01X1044198D02*
X1044245D01*
G01X1064400D02*
X1064446D01*
G01X1063883D02*
X1063930D01*
G01X1065052Y68766D02*
X1064983D01*
G01X1064702D02*
X1064685D01*
G01X1064193D02*
X1064124D01*
G01X1063738D02*
X1063723D01*
G01X1045367D02*
X1045298D01*
G01X1045017D02*
X1045000D01*
G01X1044508D02*
X1044439D01*
G01X1044053D02*
X1044038D01*
G01X1045497D02*
X1045512D01*
G01X1065182D02*
X1065197D01*
G01X1065928Y68779D02*
X1065911D01*
G01X1066004D02*
X1065989D01*
G01X1065194D02*
X1065185D01*
G01X1064700D02*
X1064688D01*
G01X1046243D02*
X1046226D01*
G01X1046319D02*
X1046304D01*
G01X1045509D02*
X1045500D01*
G01X1045015D02*
X1045003D01*
G01X1046565D02*
X1046654D01*
G01X1046486D02*
X1046506D01*
G01X1046339D02*
X1046427D01*
G01X1046117D02*
X1046206D01*
G01X1046083D02*
X1046098D01*
G01X1046002D02*
X1046024D01*
G01X1045849D02*
X1045864D01*
G01X1045933D02*
X1045948D01*
G01X1045775D02*
X1045790D01*
G01X1045569D02*
X1045583D01*
G01X1045298D02*
X1045387D01*
G01X1045249D02*
X1045263D01*
G01X1045108D02*
X1045131D01*
G01X1044885D02*
X1044907D01*
G01X1044717D02*
X1044776D01*
G01X1044547D02*
X1044562D01*
G01X1044651D02*
X1044665D01*
G01X1044596D02*
X1044616D01*
G01X1044439D02*
X1044528D01*
G01X1044405D02*
X1044419D01*
G01X1044279D02*
X1044294D01*
G01X1044200D02*
X1044259D01*
G01X1044035D02*
X1044055D01*
G01X1043927D02*
X1043942D01*
G01X1065802D02*
X1065891D01*
G01X1065768D02*
X1065783D01*
G01X1065687D02*
X1065709D01*
G01X1065534D02*
X1065549D01*
G01X1065618D02*
X1065633D01*
G01X1065460D02*
X1065475D01*
G01X1065254D02*
X1065269D01*
G01X1064983D02*
X1065072D01*
G01X1064934D02*
X1064948D01*
G01X1064793D02*
X1064816D01*
G01X1064570D02*
X1064592D01*
G01X1064402D02*
X1064461D01*
G01X1064232D02*
X1064247D01*
G01X1064336D02*
X1064350D01*
G01X1064281D02*
X1064301D01*
G01X1064124D02*
X1064213D01*
G01X1064090D02*
X1064104D01*
G01X1063964D02*
X1063979D01*
G01X1063885D02*
X1063944D01*
G01X1063720D02*
X1063740D01*
G01X1063612D02*
X1063627D01*
G01X1066024D02*
X1066112D01*
G01X1042517Y68951D02*
X1042739D01*
G01X1062202D02*
X1062424D01*
G01X1042505Y69002D02*
X1042751D01*
G01X1062190D02*
X1062436D01*
G01X1042382Y69153D02*
X1042456D01*
G01X1042800D02*
X1042874D01*
G01X1048455D02*
X1048553D01*
G01X1048824D02*
X1048898D01*
G01X1062485D02*
X1062559D01*
G01X1062067D02*
X1062141D01*
G01X1068504Y70471D02*
X1062205D01*
G01X1048819D02*
X1042520D01*
G01X1050197D02*
X1047047D01*
G01X1060827D02*
X1063976D01*
G01X1044043Y68660D02*
X1044026Y68663D01*
G01X1063728Y68660D02*
X1063711Y68663D01*
G01X1044026Y68726D02*
X1044041Y68723D01*
G01X1044476Y68660D02*
X1044461Y68663D01*
G01X1045335Y68660D02*
X1045320Y68663D01*
G01X1063711Y68726D02*
X1063726Y68723D01*
G01X1064161Y68660D02*
X1064146Y68663D01*
G01X1065020Y68660D02*
X1065005Y68663D01*
G01X1044028Y68675D02*
X1044041Y68673D01*
G01X1044200Y68660D02*
X1044188Y68663D01*
G01X1044360Y68660D02*
X1044348Y68663D01*
G01X1044466Y68675D02*
X1044478Y68673D01*
G01X1044065Y68763D02*
X1044053Y68766D01*
G01X1044717Y68660D02*
X1044705Y68663D01*
G01X1044885Y68660D02*
X1044872Y68663D01*
G01X1044993D02*
X1045005Y68660D01*
G01X1045108D02*
X1045096Y68663D01*
G01X1044990Y68706D02*
X1045003Y68703D01*
G01X1045325Y68675D02*
X1045337Y68673D01*
G01X1044907Y68779D02*
X1044919Y68776D01*
G01X1045487Y68663D02*
X1045500Y68660D01*
G01X1045027Y68776D02*
X1045015Y68779D01*
G01X1045131D02*
X1045143Y68776D01*
G01X1045524Y68733D02*
X1045512Y68736D01*
G01X1046002Y68660D02*
X1045989Y68663D01*
G01X1045522Y68776D02*
X1045509Y68779D01*
G01X1046248Y68663D02*
X1046260Y68660D01*
G01X1046024Y68779D02*
X1046036Y68776D01*
G01X1063713Y68675D02*
X1063726Y68673D01*
G01X1063885Y68660D02*
X1063873Y68663D01*
G01X1064045Y68660D02*
X1064033Y68663D01*
G01X1064151Y68675D02*
X1064163Y68673D01*
G01X1063750Y68763D02*
X1063738Y68766D01*
G01X1064402Y68660D02*
X1064390Y68663D01*
G01X1064570Y68660D02*
X1064557Y68663D01*
G01X1064678D02*
X1064690Y68660D01*
G01X1064793D02*
X1064781Y68663D01*
G01X1064675Y68706D02*
X1064688Y68703D01*
G01X1065010Y68675D02*
X1065022Y68673D01*
G01X1064592Y68779D02*
X1064604Y68776D01*
G01X1065172Y68663D02*
X1065185Y68660D01*
G01X1064712Y68776D02*
X1064700Y68779D01*
G01X1064816D02*
X1064828Y68776D01*
G01X1065209Y68733D02*
X1065197Y68736D01*
G01X1065687Y68660D02*
X1065674Y68663D01*
G01X1065207Y68776D02*
X1065194Y68779D01*
G01X1065933Y68663D02*
X1065945Y68660D01*
G01X1065709Y68779D02*
X1065721Y68776D01*
G01X1044055Y68779D02*
X1044065Y68776D01*
G01X1045098Y68678D02*
X1045108Y68675D01*
G01X1044917Y68761D02*
X1044907Y68763D01*
G01X1063740Y68779D02*
X1063750Y68776D01*
G01X1064783Y68678D02*
X1064793Y68675D01*
G01X1064602Y68761D02*
X1064592Y68763D01*
G01X1044875Y68678D02*
X1044885Y68675D01*
G01X1045141Y68761D02*
X1045131Y68763D01*
G01X1045992Y68678D02*
X1046002Y68675D01*
G01X1046033Y68761D02*
X1046024Y68763D01*
G01X1064560Y68678D02*
X1064570Y68675D01*
G01X1064826Y68761D02*
X1064816Y68763D01*
G01X1065677Y68678D02*
X1065687Y68675D01*
G01X1065719Y68761D02*
X1065709Y68763D01*
G01X1044191Y68678D02*
X1044198Y68675D01*
G01Y68726D02*
X1044191Y68728D01*
G01X1044350Y68675D02*
X1044358Y68673D01*
G01X1044707Y68678D02*
X1044715Y68675D01*
G01Y68726D02*
X1044707Y68728D01*
G01X1045003Y68673D02*
X1044995Y68675D01*
G01X1044993Y68718D02*
X1045000Y68716D01*
G01X1045025Y68763D02*
X1045017Y68766D01*
G01X1045490Y68675D02*
X1045497Y68673D01*
G01X1045522Y68721D02*
X1045515Y68723D01*
G01X1045512Y68766D02*
X1045519Y68763D01*
G01X1046250Y68675D02*
X1046257Y68673D01*
G01X1063876Y68678D02*
X1063883Y68675D01*
G01Y68726D02*
X1063876Y68728D01*
G01X1064035Y68675D02*
X1064043Y68673D01*
G01X1064393Y68678D02*
X1064400Y68675D01*
G01Y68726D02*
X1064393Y68728D01*
G01X1064688Y68673D02*
X1064680Y68675D01*
G01X1064678Y68718D02*
X1064685Y68716D01*
G01X1064710Y68763D02*
X1064702Y68766D01*
G01X1065175Y68675D02*
X1065182Y68673D01*
G01X1065207Y68721D02*
X1065200Y68723D01*
G01X1065197Y68766D02*
X1065204Y68763D01*
G01X1065935Y68675D02*
X1065943Y68673D01*
G01X1044021Y68718D02*
X1044009Y68723D01*
G01X1063706Y68718D02*
X1063694Y68723D01*
G01X1044026Y68663D02*
X1044016Y68668D01*
G01X1044070Y68761D02*
X1044065Y68763D01*
G01X1044183Y68718D02*
X1044178Y68721D01*
G01X1044065Y68776D02*
X1044075Y68771D01*
G01X1044461Y68663D02*
X1044452Y68668D01*
G01X1044700Y68718D02*
X1044695Y68721D01*
G01X1044872Y68663D02*
X1044862Y68668D01*
G01X1045096Y68663D02*
X1045086Y68668D01*
G01X1044919Y68776D02*
X1044929Y68771D01*
G01X1045320Y68663D02*
X1045310Y68668D01*
G01X1045143Y68776D02*
X1045153Y68771D01*
G01X1045989Y68663D02*
X1045980Y68668D01*
G01X1046036Y68776D02*
X1046046Y68771D01*
G01X1063711Y68663D02*
X1063701Y68668D01*
G01X1063755Y68761D02*
X1063750Y68763D01*
G01X1063868Y68718D02*
X1063863Y68721D01*
G01X1063750Y68776D02*
X1063760Y68771D01*
G01X1064146Y68663D02*
X1064137Y68668D01*
G01X1064385Y68718D02*
X1064380Y68721D01*
G01X1064557Y68663D02*
X1064547Y68668D01*
G01X1064781Y68663D02*
X1064771Y68668D01*
G01X1064604Y68776D02*
X1064614Y68771D01*
G01X1065005Y68663D02*
X1064995Y68668D01*
G01X1064828Y68776D02*
X1064838Y68771D01*
G01X1065674Y68663D02*
X1065665Y68668D01*
G01X1065721Y68776D02*
X1065731Y68771D01*
G01X1044980Y68670D02*
X1044993Y68663D01*
G01X1044978Y68713D02*
X1044990Y68706D01*
G01X1045039Y68768D02*
X1045027Y68776D01*
G01X1045475Y68670D02*
X1045487Y68663D01*
G01X1045537Y68726D02*
X1045524Y68733D01*
G01X1045534Y68768D02*
X1045522Y68776D01*
G01X1064665Y68670D02*
X1064678Y68663D01*
G01X1064663Y68713D02*
X1064675Y68706D01*
G01X1064724Y68768D02*
X1064712Y68776D01*
G01X1065160Y68670D02*
X1065172Y68663D01*
G01X1065222Y68726D02*
X1065209Y68733D01*
G01X1065219Y68768D02*
X1065207Y68776D01*
G01X1044021Y68680D02*
X1044028Y68675D01*
G01X1044019Y68730D02*
X1044026Y68726D01*
G01X1044117Y68686D02*
X1044109Y68690D01*
G01X1044075Y68771D02*
X1044082Y68766D01*
G01X1044141Y68753D02*
X1044149Y68748D01*
G01X1044459Y68680D02*
X1044466Y68675D01*
G01X1044867Y68683D02*
X1044875Y68678D01*
G01X1044995Y68675D02*
X1044988Y68680D01*
G01X1044924Y68756D02*
X1044917Y68761D01*
G01X1044985Y68723D02*
X1044993Y68718D01*
G01X1045091Y68683D02*
X1045098Y68678D01*
G01X1045032Y68758D02*
X1045025Y68763D01*
G01X1045197Y68686D02*
X1045190Y68690D01*
G01X1045148Y68756D02*
X1045141Y68761D01*
G01X1045318Y68680D02*
X1045325Y68675D01*
G01X1045222Y68753D02*
X1045229Y68748D01*
G01X1045482Y68680D02*
X1045490Y68675D01*
G01X1045529Y68716D02*
X1045522Y68721D01*
G01X1045519Y68763D02*
X1045527Y68758D01*
G01X1045984Y68683D02*
X1045992Y68678D01*
G01X1046041Y68756D02*
X1046033Y68761D01*
G01X1063706Y68680D02*
X1063713Y68675D01*
G01X1063704Y68730D02*
X1063711Y68726D01*
G01X1063802Y68686D02*
X1063794Y68690D01*
G01X1063760Y68771D02*
X1063767Y68766D01*
G01X1063826Y68753D02*
X1063834Y68748D01*
G01X1064144Y68680D02*
X1064151Y68675D01*
G01X1064552Y68683D02*
X1064560Y68678D01*
G01X1064680Y68675D02*
X1064673Y68680D01*
G01X1064609Y68756D02*
X1064602Y68761D01*
G01X1064670Y68723D02*
X1064678Y68718D01*
G01X1064776Y68683D02*
X1064783Y68678D01*
G01X1064717Y68758D02*
X1064710Y68763D01*
G01X1064882Y68686D02*
X1064875Y68690D01*
G01X1064833Y68756D02*
X1064826Y68761D01*
G01X1065003Y68680D02*
X1065010Y68675D01*
G01X1064907Y68753D02*
X1064914Y68748D01*
G01X1065167Y68680D02*
X1065175Y68675D01*
G01X1065214Y68716D02*
X1065207Y68721D01*
G01X1065204Y68763D02*
X1065212Y68758D01*
G01X1065669Y68683D02*
X1065677Y68678D01*
G01X1065726Y68756D02*
X1065719Y68761D01*
G01X1044188Y68663D02*
X1044178Y68670D01*
G01X1044348Y68663D02*
X1044338Y68670D01*
G01X1044705Y68663D02*
X1044695Y68670D01*
G01X1046238D02*
X1046248Y68663D01*
G01X1063873D02*
X1063863Y68670D01*
G01X1064033Y68663D02*
X1064023Y68670D01*
G01X1064390Y68663D02*
X1064380Y68670D01*
G01X1065923D02*
X1065933Y68663D01*
G01X1044186Y68683D02*
X1044191Y68678D01*
G01Y68728D02*
X1044186Y68733D01*
G01X1044702Y68683D02*
X1044707Y68678D01*
G01Y68728D02*
X1044702Y68733D01*
G01X1044016Y68668D02*
X1044006Y68678D01*
G01X1044075Y68756D02*
X1044070Y68761D01*
G01X1044346Y68680D02*
X1044350Y68675D01*
G01X1044452Y68668D02*
X1044442Y68678D01*
G01X1044862Y68668D02*
X1044852Y68678D01*
G01X1044970Y68721D02*
X1044978Y68713D01*
G01X1044929Y68771D02*
X1044939Y68761D01*
G01X1044980Y68728D02*
X1044985Y68723D01*
G01X1045086Y68668D02*
X1045076Y68678D01*
G01X1045153Y68771D02*
X1045163Y68761D01*
G01X1045310Y68668D02*
X1045300Y68678D01*
G01X1045980Y68668D02*
X1045970Y68678D01*
G01X1046046Y68771D02*
X1046056Y68761D01*
G01X1046245Y68680D02*
X1046250Y68675D01*
G01X1063871Y68683D02*
X1063876Y68678D01*
G01Y68728D02*
X1063871Y68733D01*
G01X1064387Y68683D02*
X1064393Y68678D01*
G01Y68728D02*
X1064387Y68733D01*
G01X1063701Y68668D02*
X1063691Y68678D01*
G01X1063760Y68756D02*
X1063755Y68761D01*
G01X1064031Y68680D02*
X1064035Y68675D01*
G01X1064137Y68668D02*
X1064127Y68678D01*
G01X1064547Y68668D02*
X1064537Y68678D01*
G01X1064656Y68721D02*
X1064663Y68713D01*
G01X1064614Y68771D02*
X1064624Y68761D01*
G01X1064665Y68728D02*
X1064670Y68723D01*
G01X1064771Y68668D02*
X1064761Y68678D01*
G01X1064838Y68771D02*
X1064848Y68761D01*
G01X1064995Y68668D02*
X1064985Y68678D01*
G01X1065665Y68668D02*
X1065655Y68678D01*
G01X1065731Y68771D02*
X1065741Y68761D01*
G01X1065930Y68680D02*
X1065935Y68675D01*
G01X1044178Y68670D02*
X1044171Y68680D01*
G01X1044178Y68721D02*
X1044171Y68730D01*
G01X1044338Y68670D02*
X1044331Y68680D01*
G01X1044695Y68670D02*
X1044688Y68680D01*
G01X1044695Y68721D02*
X1044688Y68730D01*
G01X1044973Y68680D02*
X1044980Y68670D01*
G01X1045047Y68758D02*
X1045039Y68768D01*
G01X1045468Y68680D02*
X1045475Y68670D01*
G01X1045544Y68716D02*
X1045537Y68726D01*
G01X1045541Y68758D02*
X1045534Y68768D01*
G01X1046230Y68680D02*
X1046238Y68670D01*
G01X1063863D02*
X1063856Y68680D01*
G01X1063863Y68721D02*
X1063856Y68730D01*
G01X1064023Y68670D02*
X1064016Y68680D01*
G01X1064380Y68670D02*
X1064373Y68680D01*
G01X1064380Y68721D02*
X1064373Y68730D01*
G01X1064658Y68680D02*
X1064665Y68670D01*
G01X1064732Y68758D02*
X1064724Y68768D01*
G01X1065153Y68680D02*
X1065160Y68670D01*
G01X1065229Y68716D02*
X1065222Y68726D01*
G01X1065226Y68758D02*
X1065219Y68768D01*
G01X1065915Y68680D02*
X1065923Y68670D01*
G01X1044016Y68688D02*
X1044021Y68680D01*
G01X1044009Y68723D02*
X1044004Y68730D01*
G01X1044082Y68766D02*
X1044087Y68758D01*
G01X1044454Y68688D02*
X1044459Y68680D01*
G01X1044929Y68748D02*
X1044924Y68756D01*
G01X1044988Y68680D02*
X1044983Y68688D01*
G01X1045037Y68751D02*
X1045032Y68758D01*
G01X1045153Y68748D02*
X1045148Y68756D01*
G01X1045313Y68688D02*
X1045318Y68680D01*
G01X1045478Y68688D02*
X1045482Y68680D01*
G01X1045534Y68708D02*
X1045529Y68716D01*
G01X1045527Y68758D02*
X1045531Y68751D01*
G01X1046046Y68748D02*
X1046041Y68756D01*
G01X1063701Y68688D02*
X1063706Y68680D01*
G01X1063694Y68723D02*
X1063689Y68730D01*
G01X1063767Y68766D02*
X1063772Y68758D01*
G01X1064139Y68688D02*
X1064144Y68680D01*
G01X1064614Y68748D02*
X1064609Y68756D01*
G01X1064673Y68680D02*
X1064668Y68688D01*
G01X1064722Y68751D02*
X1064717Y68758D01*
G01X1064838Y68748D02*
X1064833Y68756D01*
G01X1064998Y68688D02*
X1065003Y68680D01*
G01X1065163Y68688D02*
X1065167Y68680D01*
G01X1065219Y68708D02*
X1065214Y68716D01*
G01X1065212Y68758D02*
X1065217Y68751D01*
G01X1065731Y68748D02*
X1065726Y68756D01*
G01X1048553Y69153D02*
X1048738Y68864D01*
G01X1048676Y68801D02*
X1048455Y69153D01*
G01X1044013Y68741D02*
X1044019Y68730D01*
G01X1044078Y68751D02*
X1044075Y68756D01*
G01X1044939Y68761D02*
X1044944Y68751D01*
G01X1045163Y68761D02*
X1045167Y68751D01*
G01X1046056Y68761D02*
X1046061Y68751D01*
G01X1063698Y68741D02*
X1063704Y68730D01*
G01X1063763Y68751D02*
X1063760Y68756D01*
G01X1064624Y68761D02*
X1064629Y68751D01*
G01X1064848Y68761D02*
X1064852Y68751D01*
G01X1065741Y68761D02*
X1065746Y68751D01*
G01X1044966Y68733D02*
X1044970Y68721D01*
G01X1045052Y68746D02*
X1045047Y68758D01*
G01X1045463Y68693D02*
X1045468Y68680D01*
G01X1045549Y68703D02*
X1045544Y68716D01*
G01X1064651Y68733D02*
X1064656Y68721D01*
G01X1064737Y68746D02*
X1064732Y68758D01*
G01X1065148Y68693D02*
X1065153Y68680D01*
G01X1065234Y68703D02*
X1065229Y68716D01*
G01X1046226Y68779D02*
X1046248Y68721D01*
G01X1065911Y68779D02*
X1065933Y68721D01*
G01X1046263Y68726D02*
X1046243Y68779D01*
G01X1065948Y68726D02*
X1065928Y68779D01*
G01X1044616D02*
X1044651Y68686D01*
G01X1064301Y68779D02*
X1064336Y68686D01*
G01X1044643Y68660D02*
X1044606Y68766D01*
G01X1064328Y68660D02*
X1064291Y68766D01*
G01X1046531Y68660D02*
X1046496Y68763D01*
G01X1042579Y68562D02*
X1042382Y69153D01*
G01X1046506Y68779D02*
X1046545Y68660D01*
G01X1062264Y68562D02*
X1062067Y69153D01*
G01X1042628Y68612D02*
X1042517Y68951D01*
G01X1042456Y69153D02*
X1042505Y69002D01*
G01X1044087Y68758D02*
X1044090Y68751D01*
G01X1044171Y68680D02*
X1044169Y68688D01*
G01X1044183Y68690D02*
X1044186Y68683D01*
G01X1044171Y68730D02*
X1044169Y68738D01*
G01X1044186Y68733D02*
X1044183Y68741D01*
G01X1044331Y68680D02*
X1044328Y68688D01*
G01X1044343D02*
X1044346Y68680D01*
G01X1044688D02*
X1044685Y68688D01*
G01X1044700Y68690D02*
X1044702Y68683D01*
G01X1044688Y68730D02*
X1044685Y68738D01*
G01X1044702Y68733D02*
X1044700Y68741D01*
G01X1044865Y68690D02*
X1044867Y68683D01*
G01X1044970Y68688D02*
X1044973Y68680D01*
G01X1044978Y68736D02*
X1044980Y68728D01*
G01X1045039Y68743D02*
X1045037Y68751D01*
G01X1045089Y68690D02*
X1045091Y68683D01*
G01X1045475Y68695D02*
X1045478Y68688D01*
G01X1045537Y68701D02*
X1045534Y68708D01*
G01X1045544Y68751D02*
X1045541Y68758D01*
G01X1045982Y68690D02*
X1045984Y68683D01*
G01X1046228Y68688D02*
X1046230Y68680D01*
G01X1046243Y68688D02*
X1046245Y68680D01*
G01X1062313Y68612D02*
X1062202Y68951D01*
G01X1062141Y69153D02*
X1062190Y69002D01*
G01X1063772Y68758D02*
X1063775Y68751D01*
G01X1063856Y68680D02*
X1063854Y68688D01*
G01X1063868Y68690D02*
X1063871Y68683D01*
G01X1063856Y68730D02*
X1063854Y68738D01*
G01X1063871Y68733D02*
X1063868Y68741D01*
G01X1064016Y68680D02*
X1064013Y68688D01*
G01X1064028D02*
X1064031Y68680D01*
G01X1064373D02*
X1064370Y68688D01*
G01X1064385Y68690D02*
X1064387Y68683D01*
G01X1064373Y68730D02*
X1064370Y68738D01*
G01X1064387Y68733D02*
X1064385Y68741D01*
G01X1064550Y68690D02*
X1064552Y68683D01*
G01X1064656Y68688D02*
X1064658Y68680D01*
G01X1064663Y68736D02*
X1064665Y68728D01*
G01X1064724Y68743D02*
X1064722Y68751D01*
G01X1064774Y68690D02*
X1064776Y68683D01*
G01X1065160Y68695D02*
X1065163Y68688D01*
G01X1065222Y68701D02*
X1065219Y68708D01*
G01X1065229Y68751D02*
X1065226Y68758D01*
G01X1065667Y68690D02*
X1065669Y68683D01*
G01X1065913Y68688D02*
X1065915Y68680D01*
G01X1065928Y68688D02*
X1065930Y68680D01*
G01X1044006Y68678D02*
X1044004Y68688D01*
G01Y68730D02*
X1044001Y68741D01*
G01X1044442Y68678D02*
X1044439Y68688D01*
G01X1044931Y68738D02*
X1044929Y68748D01*
G01X1045155Y68738D02*
X1045153Y68748D01*
G01X1045300Y68678D02*
X1045298Y68688D01*
G01X1046048Y68738D02*
X1046046Y68748D01*
G01X1063691Y68678D02*
X1063689Y68688D01*
G01Y68730D02*
X1063686Y68741D01*
G01X1064127Y68678D02*
X1064124Y68688D01*
G01X1064616Y68738D02*
X1064614Y68748D01*
G01X1064840Y68738D02*
X1064838Y68748D01*
G01X1064985Y68678D02*
X1064983Y68688D01*
G01X1065733Y68738D02*
X1065731Y68748D01*
G01X1044852Y68678D02*
X1044850Y68690D01*
G01X1044944Y68751D02*
X1044946Y68738D01*
G01X1045076Y68678D02*
X1045074Y68690D01*
G01X1045167Y68751D02*
X1045170Y68738D01*
G01X1045970Y68678D02*
X1045967Y68690D01*
G01X1046061Y68751D02*
X1046063Y68738D01*
G01X1064537Y68678D02*
X1064535Y68690D01*
G01X1064629Y68751D02*
X1064631Y68738D01*
G01X1064761Y68678D02*
X1064759Y68690D01*
G01X1064852Y68751D02*
X1064855Y68738D01*
G01X1065655Y68678D02*
X1065652Y68690D01*
G01X1065746Y68751D02*
X1065748Y68738D01*
G01X1045054Y68728D02*
X1045052Y68746D01*
G01X1045460Y68710D02*
X1045463Y68693D01*
G01X1042520Y70471D02*
Y67322D01*
G01X1043307Y70471D02*
Y67322D01*
G01X1043471Y70471D02*
Y67322D01*
G01X1043888Y68660D02*
Y68673D01*
G01X1043927D02*
Y68779D01*
G01X1043942D02*
Y68673D01*
G01X1043981D02*
Y68660D01*
G01X1044001Y68741D02*
Y68751D01*
G01X1044004Y68688D02*
Y68693D01*
G01X1044013Y68751D02*
Y68741D01*
G01X1044016Y68693D02*
Y68688D01*
G01X1044050Y68723D02*
Y68713D01*
G01X1044169Y68688D02*
Y68698D01*
G01Y68738D02*
Y68751D01*
G01X1044183Y68695D02*
Y68690D01*
G01Y68741D02*
Y68748D01*
G01X1044245Y68763D02*
Y68726D01*
G01Y68675D02*
Y68710D01*
G01X1044259Y68779D02*
Y68660D01*
G01X1044279D02*
Y68779D01*
G01X1044291Y70471D02*
Y67322D01*
G01X1044294Y68779D02*
Y68680D01*
G01X1044309Y68698D02*
Y68678D01*
G01X1044328Y68688D02*
Y68698D01*
G01X1044343Y68695D02*
Y68688D01*
G01X1044405Y68726D02*
Y68779D01*
G01Y68673D02*
Y68710D01*
G01X1044419Y68779D02*
Y68660D01*
G01X1044439Y68766D02*
Y68779D01*
G01Y68688D02*
Y68693D01*
G01X1044454D02*
Y68688D01*
G01X1044528Y68779D02*
Y68766D01*
G01X1044547Y68660D02*
Y68779D01*
G01X1044562D02*
Y68686D01*
G01X1044651D02*
Y68779D01*
G01X1044665D02*
Y68660D01*
G01X1044685Y68688D02*
Y68698D01*
G01Y68738D02*
Y68751D01*
G01X1044700Y68695D02*
Y68690D01*
G01Y68741D02*
Y68748D01*
G01X1044761Y68763D02*
Y68726D01*
G01Y68675D02*
Y68710D01*
G01X1044776Y68779D02*
Y68660D01*
G01X1044796Y68723D02*
Y68736D01*
G01X1044830D02*
Y68723D01*
G01X1044931Y68701D02*
Y68738D01*
G01X1044946D02*
Y68701D01*
G01X1044966Y68746D02*
Y68733D01*
G01X1044978Y68743D02*
Y68736D01*
G01X1045039D02*
Y68743D01*
G01X1045042Y68716D02*
Y68710D01*
G01X1045054D02*
Y68728D01*
G01X1045074Y68713D02*
Y68751D01*
G01X1045089Y68748D02*
Y68728D01*
G01X1045111D02*
Y68713D01*
G01X1045155Y68701D02*
Y68738D01*
G01X1045170D02*
Y68701D01*
G01X1045249Y68660D02*
Y68779D01*
G01X1045263D02*
Y68680D01*
G01X1045278Y68698D02*
Y68678D01*
G01X1045298Y68766D02*
Y68779D01*
G01Y68688D02*
Y68693D01*
G01X1045313D02*
Y68688D01*
G01X1045387Y68779D02*
Y68766D01*
G01X1045406Y68723D02*
Y68736D01*
G01X1045441D02*
Y68723D01*
G01X1045460Y68728D02*
Y68710D01*
G01X1045472Y68723D02*
Y68728D01*
G01X1045475Y68701D02*
Y68695D01*
G01X1045537D02*
Y68701D01*
G01X1045549Y68693D02*
Y68703D01*
G01X1045569Y68660D02*
Y68779D01*
G01X1045583D02*
Y68680D01*
G01X1045598Y68698D02*
Y68678D01*
G01X1045736Y68660D02*
Y68673D01*
G01X1045775D02*
Y68779D01*
G01X1045790D02*
Y68673D01*
G01X1045830D02*
Y68660D01*
G01X1045849D02*
Y68779D01*
G01X1045864D02*
Y68723D01*
G01Y68708D02*
Y68660D01*
G01X1045933Y68723D02*
Y68779D01*
G01Y68660D02*
Y68708D01*
G01X1045948Y68779D02*
Y68660D01*
G01X1045967Y68713D02*
Y68751D01*
G01X1045982Y68748D02*
Y68728D01*
G01X1046004D02*
Y68713D01*
G01X1046048Y68701D02*
Y68738D01*
G01X1046063D02*
Y68701D01*
G01X1046083Y68660D02*
Y68779D01*
G01X1046098D02*
Y68660D01*
G01X1046117Y68763D02*
Y68779D01*
G01X1046191Y68660D02*
Y68763D01*
G01X1046206Y68779D02*
Y68660D01*
G01X1046228Y68698D02*
Y68688D01*
G01X1046243Y68695D02*
Y68688D01*
G01X1046304Y68779D02*
Y68726D01*
G01Y68673D02*
Y68710D01*
G01X1046319Y68660D02*
Y68779D01*
G01X1046339Y68660D02*
Y68675D01*
G01Y68763D02*
Y68779D01*
G01X1046348Y68708D02*
Y68723D01*
G01X1046413D02*
Y68763D01*
G01Y68675D02*
Y68708D01*
G01X1046427Y68779D02*
Y68660D01*
G01X1046565D02*
Y68675D01*
G01Y68763D02*
Y68779D01*
G01X1046575Y68708D02*
Y68723D01*
G01X1046639D02*
Y68763D01*
G01Y68675D02*
Y68708D01*
G01X1046654Y68779D02*
Y68660D01*
G01X1047047Y70471D02*
Y67322D01*
G01X1047868D02*
Y70471D01*
G01X1048031D02*
Y67322D01*
G01X1048819D02*
Y70471D01*
G01X1048824Y68951D02*
Y69153D01*
G01Y68562D02*
Y68851D01*
G01X1048898Y69153D02*
Y68562D01*
G01X1050197Y67322D02*
Y70471D01*
G01X1064739Y68728D02*
X1064737Y68746D01*
G01X1065145Y68710D02*
X1065148Y68693D01*
G01X1060827Y67322D02*
Y70471D01*
G01X1062205D02*
Y67322D01*
G01X1062992Y70471D02*
Y67322D01*
G01X1063156Y70471D02*
Y67322D01*
G01X1063573Y68660D02*
Y68673D01*
G01X1063612D02*
Y68779D01*
G01X1063627D02*
Y68673D01*
G01X1063667D02*
Y68660D01*
G01X1063686Y68741D02*
Y68751D01*
G01X1063689Y68688D02*
Y68693D01*
G01X1063698Y68751D02*
Y68741D01*
G01X1063701Y68693D02*
Y68688D01*
G01X1063735Y68723D02*
Y68713D01*
G01X1063854Y68688D02*
Y68698D01*
G01Y68738D02*
Y68751D01*
G01X1063868Y68695D02*
Y68690D01*
G01Y68741D02*
Y68748D01*
G01X1063930Y68763D02*
Y68726D01*
G01Y68675D02*
Y68710D01*
G01X1063944Y68779D02*
Y68660D01*
G01X1063964D02*
Y68779D01*
G01X1063976Y70471D02*
Y67322D01*
G01X1063979Y68779D02*
Y68680D01*
G01X1063994Y68698D02*
Y68678D01*
G01X1064013Y68688D02*
Y68698D01*
G01X1064028Y68695D02*
Y68688D01*
G01X1064090Y68726D02*
Y68779D01*
G01Y68673D02*
Y68710D01*
G01X1064104Y68779D02*
Y68660D01*
G01X1064124Y68766D02*
Y68779D01*
G01Y68688D02*
Y68693D01*
G01X1064139D02*
Y68688D01*
G01X1064213Y68779D02*
Y68766D01*
G01X1064232Y68660D02*
Y68779D01*
G01X1064247D02*
Y68686D01*
G01X1064336D02*
Y68779D01*
G01X1064350D02*
Y68660D01*
G01X1064370Y68688D02*
Y68698D01*
G01Y68738D02*
Y68751D01*
G01X1064385Y68695D02*
Y68690D01*
G01Y68741D02*
Y68748D01*
G01X1064446Y68763D02*
Y68726D01*
G01Y68675D02*
Y68710D01*
G01X1064461Y68779D02*
Y68660D01*
G01X1064481Y68723D02*
Y68736D01*
G01X1064515D02*
Y68723D01*
G01X1064616Y68701D02*
Y68738D01*
G01X1064631D02*
Y68701D01*
G01X1064651Y68746D02*
Y68733D01*
G01X1064663Y68743D02*
Y68736D01*
G01X1064724D02*
Y68743D01*
G01X1064727Y68716D02*
Y68710D01*
G01X1064739D02*
Y68728D01*
G01X1064759Y68713D02*
Y68751D01*
G01X1064774Y68748D02*
Y68728D01*
G01X1064796D02*
Y68713D01*
G01X1064840Y68701D02*
Y68738D01*
G01X1064855D02*
Y68701D01*
G01X1064934Y68660D02*
Y68779D01*
G01X1064948D02*
Y68680D01*
G01X1064963Y68698D02*
Y68678D01*
G01X1064983Y68766D02*
Y68779D01*
G01Y68688D02*
Y68693D01*
G01X1064998D02*
Y68688D01*
G01X1065072Y68779D02*
Y68766D01*
G01X1065091Y68723D02*
Y68736D01*
G01X1065126D02*
Y68723D01*
G01X1065145Y68728D02*
Y68710D01*
G01X1065157Y68723D02*
Y68728D01*
G01X1065160Y68701D02*
Y68695D01*
G01X1065222D02*
Y68701D01*
G01X1065234Y68693D02*
Y68703D01*
G01X1065254Y68660D02*
Y68779D01*
G01X1065269D02*
Y68680D01*
G01X1065283Y68698D02*
Y68678D01*
G01X1065421Y68660D02*
Y68673D01*
G01X1065460D02*
Y68779D01*
G01X1065475D02*
Y68673D01*
G01X1065515D02*
Y68660D01*
G01X1065534D02*
Y68779D01*
G01X1065549D02*
Y68723D01*
G01Y68708D02*
Y68660D01*
G01X1065618Y68723D02*
Y68779D01*
G01Y68660D02*
Y68708D01*
G01X1065633Y68779D02*
Y68660D01*
G01X1065652Y68713D02*
Y68751D01*
G01X1065667Y68748D02*
Y68728D01*
G01X1065689D02*
Y68713D01*
G01X1065733Y68701D02*
Y68738D01*
G01X1065748D02*
Y68701D01*
G01X1065768Y68660D02*
Y68779D01*
G01X1065783D02*
Y68660D01*
G01X1065802Y68763D02*
Y68779D01*
G01X1065876Y68660D02*
Y68763D01*
G01X1065891Y68779D02*
Y68660D01*
G01X1065913Y68698D02*
Y68688D01*
G01X1065928Y68695D02*
Y68688D01*
G01X1065989Y68779D02*
Y68726D01*
G01Y68673D02*
Y68710D01*
G01X1066004Y68660D02*
Y68779D01*
G01X1066024Y68660D02*
Y68675D01*
G01Y68763D02*
Y68779D01*
G01X1066033Y68708D02*
Y68723D01*
G01X1066098D02*
Y68763D01*
G01Y68675D02*
Y68708D01*
G01X1045052Y68693D02*
X1045054Y68710D01*
G01X1045463Y68746D02*
X1045460Y68728D01*
G01X1064737Y68693D02*
X1064739Y68710D01*
G01X1065148Y68746D02*
X1065145Y68728D01*
G01X1045042Y68710D02*
X1045039Y68695D01*
G01X1045472Y68728D02*
X1045475Y68743D01*
G01X1044850Y68748D02*
X1044852Y68761D01*
G01X1044946Y68701D02*
X1044944Y68688D01*
G01X1045170Y68701D02*
X1045167Y68688D01*
G01X1046063Y68701D02*
X1046061Y68688D01*
G01X1064727Y68710D02*
X1064724Y68695D01*
G01X1065157Y68728D02*
X1065160Y68743D01*
G01X1064535Y68748D02*
X1064537Y68761D01*
G01X1064631Y68701D02*
X1064629Y68688D01*
G01X1064855Y68701D02*
X1064852Y68688D01*
G01X1065748Y68701D02*
X1065746Y68688D01*
G01X1044004Y68693D02*
X1044006Y68703D01*
G01X1044087Y68688D02*
X1044085Y68678D01*
G01X1044439Y68693D02*
X1044442Y68703D01*
G01X1044525Y68688D02*
X1044523Y68678D01*
G01X1044929Y68690D02*
X1044931Y68701D01*
G01X1045074Y68751D02*
X1045076Y68761D01*
G01X1045153Y68690D02*
X1045155Y68701D01*
G01X1045298Y68693D02*
X1045300Y68703D01*
G01X1045384Y68688D02*
X1045381Y68678D01*
G01X1045967Y68751D02*
X1045970Y68761D01*
G01X1046046Y68690D02*
X1046048Y68701D01*
G01X1063689Y68693D02*
X1063691Y68703D01*
G01X1063772Y68688D02*
X1063770Y68678D01*
G01X1064124Y68693D02*
X1064127Y68703D01*
G01X1064210Y68688D02*
X1064208Y68678D01*
G01X1064614Y68690D02*
X1064616Y68701D01*
G01X1064759Y68751D02*
X1064761Y68761D01*
G01X1064838Y68690D02*
X1064840Y68701D01*
G01X1064983Y68693D02*
X1064985Y68703D01*
G01X1065069Y68688D02*
X1065067Y68678D01*
G01X1065652Y68751D02*
X1065655Y68761D01*
G01X1065731Y68690D02*
X1065733Y68701D01*
G01X1042751Y69002D02*
X1042800Y69153D01*
G01X1042739Y68951D02*
X1042628Y68612D01*
G01X1044001Y68751D02*
X1044004Y68758D01*
G01X1044169Y68751D02*
X1044171Y68758D01*
G01X1044183Y68748D02*
X1044186Y68756D01*
G01X1044169Y68698D02*
X1044171Y68706D01*
G01X1044186Y68703D02*
X1044183Y68695D01*
G01X1044328Y68698D02*
X1044331Y68706D01*
G01X1044346Y68703D02*
X1044343Y68695D01*
G01X1044685Y68751D02*
X1044688Y68758D01*
G01X1044700Y68748D02*
X1044702Y68756D01*
G01X1044685Y68698D02*
X1044688Y68706D01*
G01X1044702Y68703D02*
X1044700Y68695D01*
G01X1044867Y68756D02*
X1044865Y68748D01*
G01X1044980Y68751D02*
X1044978Y68743D01*
G01X1045037Y68728D02*
X1045039Y68736D01*
G01Y68695D02*
X1045037Y68688D01*
G01X1045091Y68756D02*
X1045089Y68748D01*
G01X1045475Y68743D02*
X1045478Y68751D01*
G01Y68708D02*
X1045475Y68701D01*
G01X1045534Y68688D02*
X1045537Y68695D01*
G01X1045984Y68756D02*
X1045982Y68748D01*
G01X1046230Y68706D02*
X1046228Y68698D01*
G01X1046245Y68703D02*
X1046243Y68695D01*
G01X1062436Y69002D02*
X1062485Y69153D01*
G01X1062424Y68951D02*
X1062313Y68612D01*
G01X1063686Y68751D02*
X1063689Y68758D01*
G01X1063854Y68751D02*
X1063856Y68758D01*
G01X1063868Y68748D02*
X1063871Y68756D01*
G01X1063854Y68698D02*
X1063856Y68706D01*
G01X1063871Y68703D02*
X1063868Y68695D01*
G01X1064013Y68698D02*
X1064016Y68706D01*
G01X1064031Y68703D02*
X1064028Y68695D01*
G01X1064370Y68751D02*
X1064373Y68758D01*
G01X1064385Y68748D02*
X1064387Y68756D01*
G01X1064370Y68698D02*
X1064373Y68706D01*
G01X1064387Y68703D02*
X1064385Y68695D01*
G01X1064552Y68756D02*
X1064550Y68748D01*
G01X1064665Y68751D02*
X1064663Y68743D01*
G01X1064722Y68728D02*
X1064724Y68736D01*
G01Y68695D02*
X1064722Y68688D01*
G01X1064776Y68756D02*
X1064774Y68748D01*
G01X1065160Y68743D02*
X1065163Y68751D01*
G01Y68708D02*
X1065160Y68701D01*
G01X1065219Y68688D02*
X1065222Y68695D01*
G01X1065669Y68756D02*
X1065667Y68748D01*
G01X1065915Y68706D02*
X1065913Y68698D01*
G01X1065930Y68703D02*
X1065928Y68695D01*
G01X1042874Y69153D02*
X1042677Y68562D01*
G01X1046447Y68660D02*
X1046486Y68779D01*
G01X1062559Y69153D02*
X1062362Y68562D01*
G01X1046496Y68763D02*
X1046462Y68660D01*
G01X1044606Y68766D02*
X1044570Y68660D01*
G01X1064291Y68766D02*
X1064255Y68660D01*
G01X1044562Y68686D02*
X1044596Y68779D01*
G01X1064247Y68686D02*
X1064281Y68779D01*
G01X1044970Y68758D02*
X1044966Y68746D01*
G01X1045047Y68680D02*
X1045052Y68693D01*
G01X1045468Y68758D02*
X1045463Y68746D01*
G01X1045544Y68680D02*
X1045549Y68693D01*
G01X1064656Y68758D02*
X1064651Y68746D01*
G01X1064732Y68680D02*
X1064737Y68693D01*
G01X1065153Y68758D02*
X1065148Y68746D01*
G01X1065229Y68680D02*
X1065234Y68693D01*
G01X1044016Y68756D02*
X1044013Y68751D01*
G01X1044021Y68703D02*
X1044016Y68693D01*
G01X1044459Y68703D02*
X1044454Y68693D01*
G01X1044944Y68688D02*
X1044939Y68678D01*
G01X1045167Y68688D02*
X1045163Y68678D01*
G01X1045318Y68703D02*
X1045313Y68693D01*
G01X1046061Y68688D02*
X1046056Y68678D01*
G01X1044109Y68690D02*
X1044141Y68753D01*
G01X1044149Y68748D02*
X1044117Y68686D01*
G01X1045190Y68690D02*
X1045222Y68753D01*
G01X1045229Y68748D02*
X1045197Y68686D01*
G01X1044041Y68713D02*
X1044026Y68708D01*
G01X1044191Y68761D02*
X1044198Y68763D01*
G01Y68710D02*
X1044191Y68708D01*
G01X1044358Y68710D02*
X1044350Y68708D01*
G01X1044707Y68761D02*
X1044715Y68763D01*
G01Y68710D02*
X1044707Y68708D01*
G01X1045000Y68766D02*
X1044993Y68763D01*
G01X1045017Y68716D02*
X1045025Y68718D01*
G01Y68675D02*
X1045017Y68673D01*
G01X1045490Y68763D02*
X1045497Y68766D01*
G01Y68723D02*
X1045490Y68721D01*
G01X1045515Y68673D02*
X1045522Y68675D01*
G01X1046257Y68710D02*
X1046250Y68708D01*
G01X1063726Y68713D02*
X1063711Y68708D01*
G01X1063876Y68761D02*
X1063883Y68763D01*
G01Y68710D02*
X1063876Y68708D01*
G01X1064043Y68710D02*
X1064035Y68708D01*
G01X1064393Y68761D02*
X1064400Y68763D01*
G01Y68710D02*
X1064393Y68708D01*
G01X1064685Y68766D02*
X1064678Y68763D01*
G01X1064702Y68716D02*
X1064710Y68718D01*
G01Y68675D02*
X1064702Y68673D01*
G01X1065175Y68763D02*
X1065182Y68766D01*
G01Y68723D02*
X1065175Y68721D01*
G01X1065200Y68673D02*
X1065207Y68675D01*
G01X1065943Y68710D02*
X1065935Y68708D01*
G01X1063701Y68756D02*
X1063698Y68751D01*
G01X1063706Y68703D02*
X1063701Y68693D01*
G01X1064144Y68703D02*
X1064139Y68693D01*
G01X1064629Y68688D02*
X1064624Y68678D01*
G01X1064852Y68688D02*
X1064848Y68678D01*
G01X1065003Y68703D02*
X1064998Y68693D01*
G01X1065746Y68688D02*
X1065741Y68678D01*
G01X1063794Y68690D02*
X1063826Y68753D01*
G01X1063834Y68748D02*
X1063802Y68686D01*
G01X1064875Y68690D02*
X1064907Y68753D01*
G01X1064914Y68748D02*
X1064882Y68686D01*
G01X1044004Y68758D02*
X1044009Y68766D01*
G01X1044006Y68703D02*
X1044011Y68710D01*
G01X1044070Y68680D02*
X1044075Y68688D01*
G01X1044442Y68703D02*
X1044446Y68710D01*
G01X1044508Y68680D02*
X1044513Y68688D01*
G01X1044924Y68683D02*
X1044929Y68690D01*
G01X1044985Y68758D02*
X1044980Y68751D01*
G01X1045037Y68688D02*
X1045032Y68680D01*
G01X1045148Y68683D02*
X1045153Y68690D01*
G01X1045300Y68703D02*
X1045305Y68710D01*
G01X1045367Y68680D02*
X1045372Y68688D01*
G01X1045478Y68751D02*
X1045482Y68758D01*
G01Y68716D02*
X1045478Y68708D01*
G01X1045529Y68680D02*
X1045534Y68688D01*
G01X1046041Y68683D02*
X1046046Y68690D01*
G01X1063689Y68758D02*
X1063694Y68766D01*
G01X1063691Y68703D02*
X1063696Y68710D01*
G01X1063755Y68680D02*
X1063760Y68688D01*
G01X1064127Y68703D02*
X1064131Y68710D01*
G01X1064193Y68680D02*
X1064198Y68688D01*
G01X1064609Y68683D02*
X1064614Y68690D01*
G01X1064670Y68758D02*
X1064665Y68751D01*
G01X1064722Y68688D02*
X1064717Y68680D01*
G01X1064833Y68683D02*
X1064838Y68690D01*
G01X1064985Y68703D02*
X1064990Y68710D01*
G01X1065052Y68680D02*
X1065057Y68688D01*
G01X1065163Y68751D02*
X1065167Y68758D01*
G01Y68716D02*
X1065163Y68708D01*
G01X1065214Y68680D02*
X1065219Y68688D01*
G01X1065726Y68683D02*
X1065731Y68690D01*
G01X1044171Y68758D02*
X1044178Y68768D01*
G01X1044171Y68706D02*
X1044178Y68716D01*
G01X1044331Y68706D02*
X1044338Y68716D01*
G01X1044688Y68758D02*
X1044695Y68768D01*
G01X1044688Y68706D02*
X1044695Y68716D01*
G01X1044978Y68768D02*
X1044970Y68758D01*
G01X1045039Y68670D02*
X1045047Y68680D01*
G01X1045475Y68768D02*
X1045468Y68758D01*
G01X1045537Y68670D02*
X1045544Y68680D01*
G01X1046238Y68716D02*
X1046230Y68706D01*
G01X1063856Y68758D02*
X1063863Y68768D01*
G01X1063856Y68706D02*
X1063863Y68716D01*
G01X1064016Y68706D02*
X1064023Y68716D01*
G01X1064373Y68758D02*
X1064380Y68768D01*
G01X1064373Y68706D02*
X1064380Y68716D01*
G01X1064663Y68768D02*
X1064656Y68758D01*
G01X1064724Y68670D02*
X1064732Y68680D01*
G01X1065160Y68768D02*
X1065153Y68758D01*
G01X1065222Y68670D02*
X1065229Y68680D01*
G01X1065923Y68716D02*
X1065915Y68706D01*
G01X1044294Y68680D02*
X1044309Y68698D01*
G01Y68678D02*
X1044294Y68660D01*
G01X1045263Y68680D02*
X1045278Y68698D01*
G01Y68678D02*
X1045263Y68660D01*
G01X1045583Y68680D02*
X1045598Y68698D01*
G01Y68678D02*
X1045583Y68660D01*
G01X1063979Y68680D02*
X1063994Y68698D01*
G01Y68678D02*
X1063979Y68660D01*
G01X1064948Y68680D02*
X1064963Y68698D01*
G01Y68678D02*
X1064948Y68660D01*
G01X1065269Y68680D02*
X1065283Y68698D01*
G01Y68678D02*
X1065269Y68660D01*
G01X1048455Y68562D02*
X1048676Y68801D01*
G01X1048824Y68851D02*
X1048553Y68562D01*
G01X1044021Y68761D02*
X1044016Y68756D01*
G01X1044026Y68708D02*
X1044021Y68703D01*
G01X1044085Y68678D02*
X1044075Y68668D01*
G01X1044186Y68756D02*
X1044191Y68761D01*
G01Y68708D02*
X1044186Y68703D01*
G01X1044350Y68708D02*
X1044346Y68703D01*
G01X1044523Y68678D02*
X1044513Y68668D01*
G01X1044702Y68756D02*
X1044707Y68761D01*
G01Y68708D02*
X1044702Y68703D01*
G01X1044852Y68761D02*
X1044862Y68771D01*
G01X1044939Y68678D02*
X1044929Y68668D01*
G01X1045032Y68723D02*
X1045037Y68728D01*
G01X1045076Y68761D02*
X1045086Y68771D01*
G01X1045163Y68678D02*
X1045153Y68668D01*
G01X1045381Y68678D02*
X1045372Y68668D01*
G01X1045970Y68761D02*
X1045980Y68771D01*
G01X1046056Y68678D02*
X1046046Y68668D01*
G01X1046250Y68708D02*
X1046245Y68703D01*
G01X1048738Y68864D02*
X1048824Y68951D01*
G01X1063706Y68761D02*
X1063701Y68756D01*
G01X1063711Y68708D02*
X1063706Y68703D01*
G01X1063770Y68678D02*
X1063760Y68668D01*
G01X1063871Y68756D02*
X1063876Y68761D01*
G01Y68708D02*
X1063871Y68703D01*
G01X1064035Y68708D02*
X1064031Y68703D01*
G01X1064208Y68678D02*
X1064198Y68668D01*
G01X1064387Y68756D02*
X1064393Y68761D01*
G01Y68708D02*
X1064387Y68703D01*
G01X1064537Y68761D02*
X1064547Y68771D01*
G01X1064624Y68678D02*
X1064614Y68668D01*
G01X1064717Y68723D02*
X1064722Y68728D01*
G01X1064761Y68761D02*
X1064771Y68771D01*
G01X1064848Y68678D02*
X1064838Y68668D01*
G01X1065067Y68678D02*
X1065057Y68668D01*
G01X1065655Y68761D02*
X1065665Y68771D01*
G01X1065741Y68678D02*
X1065731Y68668D01*
G01X1065935Y68708D02*
X1065930Y68703D01*
G01X1044528Y68766D02*
X1044459Y68703D01*
G01X1045387Y68766D02*
X1045318Y68703D01*
G01X1064213Y68766D02*
X1064144Y68703D01*
G01X1065072Y68766D02*
X1065003Y68703D01*
G01X1044446Y68710D02*
X1044508Y68766D01*
G01X1045305Y68710D02*
X1045367Y68766D01*
G01X1064131Y68710D02*
X1064193Y68766D01*
G01X1064990Y68710D02*
X1065052Y68766D01*
G01X1044011Y68710D02*
X1044021Y68718D01*
G01X1044178Y68768D02*
X1044188Y68776D01*
G01X1044338Y68716D02*
X1044348Y68723D01*
G01X1044695Y68768D02*
X1044705Y68776D01*
G01X1063696Y68710D02*
X1063706Y68718D01*
G01X1063863Y68768D02*
X1063873Y68776D01*
G01X1064023Y68716D02*
X1064033Y68723D01*
G01X1064380Y68768D02*
X1064390Y68776D01*
G01X1044009Y68766D02*
X1044016Y68771D01*
G01X1044063Y68675D02*
X1044070Y68680D01*
G01X1044501Y68675D02*
X1044508Y68680D01*
G01X1044875Y68761D02*
X1044867Y68756D01*
G01X1044993Y68763D02*
X1044985Y68758D01*
G01X1044917Y68678D02*
X1044924Y68683D01*
G01X1045025Y68718D02*
X1045032Y68723D01*
G01X1045098Y68761D02*
X1045091Y68756D01*
G01X1045027Y68706D02*
X1045042Y68716D01*
G01X1045032Y68680D02*
X1045025Y68675D01*
G01X1045141Y68678D02*
X1045148Y68683D01*
G01X1045359Y68675D02*
X1045367Y68680D01*
G01X1045482Y68758D02*
X1045490Y68763D01*
G01X1045487Y68733D02*
X1045472Y68723D01*
G01X1045490Y68721D02*
X1045482Y68716D01*
G01X1045522Y68675D02*
X1045529Y68680D01*
G01X1045992Y68761D02*
X1045984Y68756D01*
G01X1046033Y68678D02*
X1046041Y68683D01*
G01X1063694Y68766D02*
X1063701Y68771D01*
G01X1063748Y68675D02*
X1063755Y68680D01*
G01X1064186Y68675D02*
X1064193Y68680D01*
G01X1064560Y68761D02*
X1064552Y68756D01*
G01X1064678Y68763D02*
X1064670Y68758D01*
G01X1064602Y68678D02*
X1064609Y68683D01*
G01X1064710Y68718D02*
X1064717Y68723D01*
G01X1064783Y68761D02*
X1064776Y68756D01*
G01X1064712Y68706D02*
X1064727Y68716D01*
G01X1064717Y68680D02*
X1064710Y68675D01*
G01X1064826Y68678D02*
X1064833Y68683D01*
G01X1065044Y68675D02*
X1065052Y68680D01*
G01X1065167Y68758D02*
X1065175Y68763D01*
G01X1065172Y68733D02*
X1065157Y68723D01*
G01X1065175Y68721D02*
X1065167Y68716D01*
G01X1065207Y68675D02*
X1065214Y68680D01*
G01X1065677Y68761D02*
X1065669Y68756D01*
G01X1065719Y68678D02*
X1065726Y68683D01*
G01X1044990Y68776D02*
X1044978Y68768D01*
G01X1045027Y68663D02*
X1045039Y68670D01*
G01X1045487Y68776D02*
X1045475Y68768D01*
G01X1045524Y68663D02*
X1045537Y68670D01*
G01X1064675Y68776D02*
X1064663Y68768D01*
G01X1064712Y68663D02*
X1064724Y68670D01*
G01X1065172Y68776D02*
X1065160Y68768D01*
G01X1065209Y68663D02*
X1065222Y68670D01*
G01X1044016Y68771D02*
X1044026Y68776D01*
G01Y68763D02*
X1044021Y68761D01*
G01X1044075Y68668D02*
X1044065Y68663D01*
G01X1044178Y68716D02*
X1044183Y68718D01*
G01X1044513Y68668D02*
X1044503Y68663D01*
G01X1044695Y68716D02*
X1044700Y68718D01*
G01X1044862Y68771D02*
X1044872Y68776D01*
G01X1045086Y68771D02*
X1045096Y68776D01*
G01X1044929Y68668D02*
X1044919Y68663D01*
G01X1045153Y68668D02*
X1045143Y68663D01*
G01X1045372Y68668D02*
X1045362Y68663D01*
G01X1045980Y68771D02*
X1045989Y68776D01*
G01X1046046Y68668D02*
X1046036Y68663D01*
G01X1046248Y68721D02*
X1046238Y68716D01*
G01X1063701Y68771D02*
X1063711Y68776D01*
G01Y68763D02*
X1063706Y68761D01*
G01X1063760Y68668D02*
X1063750Y68663D01*
G01X1063863Y68716D02*
X1063868Y68718D01*
G01X1064198Y68668D02*
X1064188Y68663D01*
G01X1064380Y68716D02*
X1064385Y68718D01*
G01X1064547Y68771D02*
X1064557Y68776D01*
G01X1064771Y68771D02*
X1064781Y68776D01*
G01X1064614Y68668D02*
X1064604Y68663D01*
G01X1064838Y68668D02*
X1064828Y68663D01*
G01X1065057Y68668D02*
X1065047Y68663D01*
G01X1065665Y68771D02*
X1065674Y68776D01*
G01X1065731Y68668D02*
X1065721Y68663D01*
G01X1065933Y68721D02*
X1065923Y68716D01*
G01X1078701Y87637D02*
X1071654D01*
G01X1070315Y88621D02*
X1080039D01*
G01X1072441Y89231D02*
X1070472D01*
G01X1076437Y90885D02*
X1073917D01*
G01X1076437D02*
X1073917D01*
G01X1072441Y91200D02*
X1070472D01*
G01X1075450Y91394D02*
X1074545D01*
G01X1075046Y91508D02*
X1075450D01*
G01X1074641D02*
X1074930D01*
G01X1074705Y91672D02*
X1075650D01*
G01X1074815Y91979D02*
X1074757D01*
G01Y92092D02*
X1074834D01*
G01Y92243D02*
X1074680D01*
G01X1075450Y92356D02*
X1074699D01*
G01X1074545Y92470D02*
X1075450D01*
G01X1075650Y92617D02*
X1074705D01*
G01X1076437Y93405D02*
X1073917D01*
G01X1076437D02*
X1073917D01*
G01X1072441Y93424D02*
X1070472D01*
G01X1072441Y95393D02*
X1070472D01*
G01X1080039Y95964D02*
X1070315D01*
G01X1072480Y96948D02*
X1077874D01*
G01Y97342D02*
X1072480D01*
G01X1070315Y98326D02*
X1080039D01*
G01X1072441Y99074D02*
X1070472D01*
G01X1076437Y100885D02*
X1073917D01*
G01X1072441Y101042D02*
X1070472D01*
G01X1072441Y103345D02*
X1070472D01*
G01X1076437Y103405D02*
X1073917D01*
G01X1072441Y105314D02*
X1070472D01*
G01X1080039Y105964D02*
X1070315D01*
G01X1072480Y106948D02*
X1077874D01*
G01Y107342D02*
X1072480D01*
G01X1074872Y91960D02*
X1074815Y91979D01*
G01X1074834Y92092D02*
X1074892Y92073D01*
G01X1072480Y97342D02*
X1070315Y98326D01*
G01X1072480Y107342D02*
X1070315Y108326D01*
G01Y88621D02*
X1071654Y87637D01*
G01X1074892Y92073D02*
X1074969Y92017D01*
G01X1074680Y92243D02*
X1074545Y92356D01*
G01X1074699D02*
X1074834Y92243D01*
G01X1074911Y91923D02*
X1074872Y91960D01*
G01X1074705Y92617D02*
X1073917Y93405D01*
G01X1076437Y90885D02*
X1075650Y91672D01*
G01X1074969Y92017D02*
X1075026Y91942D01*
G01X1074930Y91866D02*
X1074911Y91923D01*
G01X1075026Y91942D02*
X1075046Y91847D01*
G01X1070315Y105964D02*
Y98326D01*
G01Y95964D02*
Y88621D01*
G01X1070472Y105314D02*
Y103345D01*
G01Y101042D02*
Y99074D01*
G01Y95393D02*
Y93424D01*
G01Y91200D02*
Y89231D01*
G01X1072441Y105314D02*
Y103345D01*
G01Y101042D02*
Y99074D01*
G01Y95393D02*
Y93424D01*
G01Y91200D02*
Y89231D01*
G01X1072480Y107342D02*
Y106948D01*
G01Y97342D02*
Y96948D01*
G01X1073917Y113405D02*
Y90885D01*
G01Y103405D02*
Y100885D01*
G01Y93405D02*
Y90885D01*
G01X1074545Y91394D02*
Y91847D01*
G01Y92356D02*
Y92470D01*
G01X1074641Y91866D02*
Y91508D01*
G01X1074705Y92617D02*
Y91672D01*
G01X1074930Y91508D02*
Y91866D01*
G01X1075046Y91847D02*
Y91508D01*
G01X1075450D02*
Y91394D01*
G01Y92470D02*
Y92356D01*
G01X1075650Y92617D02*
Y91672D01*
G01X1074545Y91847D02*
X1074564Y91942D01*
G01X1074660Y91923D02*
X1074641Y91866D01*
G01X1072480Y106948D02*
X1070315Y105964D01*
G01X1072480Y96948D02*
X1070315Y95964D01*
G01X1074699Y92073D02*
X1074757Y92092D01*
G01Y91979D02*
X1074699Y91960D01*
G01X1074564Y91942D02*
X1074622Y92017D01*
G01X1073917Y90885D02*
X1074705Y91672D01*
G01X1075650Y92617D02*
X1076437Y93405D01*
G01X1074699Y91960D02*
X1074660Y91923D01*
G01X1074622Y92017D02*
X1074699Y92073D01*
G01X1075650Y112617D02*
X1074705D01*
G01X1072441Y113267D02*
X1070472D01*
G01X1076437Y113405D02*
X1073917D01*
G01X1076437D02*
X1073917D01*
G01X1072441Y115235D02*
X1070472D01*
G01X1080039Y115668D02*
X1070315D01*
G01X1071654Y116653D02*
X1078701D01*
G01X1074705Y112617D02*
X1073917Y113405D01*
G01X1070472Y115235D02*
Y113267D01*
G01X1072441Y115235D02*
Y113267D01*
G01X1071654Y116653D02*
X1070315Y115668D01*
G01X1075650Y112617D02*
X1076437Y113405D01*
G01X1070315Y108326D02*
X1080039D01*
G01X1072441Y108916D02*
X1070472D01*
G01X1076437Y110885D02*
X1073917D01*
G01X1076437D02*
X1073917D01*
G01X1072441D02*
X1070472D01*
G01X1074705Y111672D02*
X1075650D01*
G01X1076437Y110885D02*
X1075650Y111672D01*
G01X1070315Y115668D02*
Y108326D01*
G01X1070472Y110885D02*
Y108916D01*
G01X1072441Y110885D02*
Y108916D01*
G01X1073917Y113405D02*
Y110885D01*
G01X1074705Y112617D02*
Y111672D01*
G01X1075650Y112617D02*
Y111672D01*
G01X1074705D02*
X1073917Y110885D01*
G01X1092913Y200550D02*
X1061417D01*
G01D02*
Y303149D01*
G01X1067618Y892519D02*
Y883464D01*
G01X1068602D02*
Y892519D01*
G01X1070768D02*
Y883464D01*
G01X1071752D02*
Y892519D01*
G01X1073917D02*
Y883464D01*
G01X1074902D02*
Y892519D01*
G01X1077067Y883464D02*
X1074902D01*
G01X1073917D02*
X1071752D01*
G01X1070768D02*
X1068602D01*
G01X1042421Y892519D02*
Y883464D01*
G01X1043406D02*
Y892519D01*
G01X1045571D02*
Y883464D01*
G01X1046555D02*
Y892519D01*
G01X1048720D02*
Y883464D01*
G01X1049705D02*
Y892519D01*
G01X1051870D02*
Y883464D01*
G01X1052854D02*
Y892519D01*
G01X1055020D02*
Y883464D01*
G01X1056004D02*
Y892519D01*
G01X1058169D02*
Y883464D01*
G01X1059154D02*
Y892519D01*
G01X1061319D02*
Y883464D01*
G01X1062303D02*
Y892519D01*
G01X1064469D02*
Y883464D01*
G01X1065453D02*
Y892519D01*
G01X1067618Y883464D02*
X1065453D01*
G01X1064469D02*
X1062303D01*
G01X1061319D02*
X1059154D01*
G01X1058169D02*
X1056004D01*
G01X1055020D02*
X1052854D01*
G01X1051870D02*
X1049705D01*
G01X1048720D02*
X1046555D01*
G01X1045571D02*
X1043406D01*
G01X1068602Y892519D02*
X1070768D01*
G01X1074902D02*
X1077067D01*
G01X1071752D02*
X1073917D01*
G01X1046555D02*
X1048720D01*
G01X1043406D02*
X1045571D01*
G01X1049705D02*
X1051870D01*
G01X1056004D02*
X1058169D01*
G01X1052854D02*
X1055020D01*
G01X1059154D02*
X1061319D01*
G01X1065453D02*
X1067618D01*
G01X1062303D02*
X1064469D01*
G01X1062747Y2171102D02*
Y2152090D01*
G01X1090092Y-779736D02*
X1086194D01*
Y-771075D01*
X1090092D01*
G01X1086194Y-775405D02*
X1088630D01*
G01X1078399Y-771075D02*
Y-779736D01*
X1082296D01*
G01X1102272Y-763857D02*
X1105195D01*
G01X1101297Y-766744D02*
X1103733Y-758082D01*
X1106169Y-766744D01*
G01X1086194Y-762413D02*
X1088630D01*
G01X1078399Y-758082D02*
X1080348D01*
X1081322Y-758804D01*
X1082296Y-760248D01*
G01X1093502Y-758082D02*
X1098374D01*
G01X1090092Y-766744D02*
X1086194D01*
Y-758082D01*
X1090092D01*
G01X1082296Y-760248D02*
X1082783Y-762413D01*
X1082296Y-764579D01*
X1081322Y-766022D01*
G01X1095938Y-758082D02*
Y-766744D01*
G01X1081322Y-766022D02*
X1080348Y-766744D01*
X1078399D01*
Y-758082D01*
G01X1118939Y-711221D02*
X1099376Y-709832D01*
G01D02*
X1079658Y-708368D01*
G01X1104079Y-687590D02*
X1101126D01*
G01X1104079D02*
X1101126D01*
G01X1117858Y-676532D02*
X1104079D01*
G01X1117858D02*
X1104079D01*
G01Y-673517D02*
X1117858D01*
G01X1104079D02*
X1117858D01*
G01X1101126Y-687590D02*
Y-663968D01*
G01Y-687590D02*
Y-663968D01*
G01X1104079D02*
Y-673517D01*
G01Y-676532D02*
Y-687590D01*
G01Y-663968D02*
Y-673517D01*
G01Y-676532D02*
Y-687590D01*
G01X1097993Y-682078D02*
X1192481D01*
G01X1097993Y-508849D02*
Y-682078D01*
G01X1208229Y-697826D02*
X1082228D01*
G01X1208229D02*
X1082228D01*
G01D02*
Y-508849D01*
G01Y-697826D02*
Y-508849D01*
G01X1082244Y-697826D02*
Y-508849D01*
G01Y-697826D02*
Y-508849D01*
G01X1101126Y-663968D02*
X1104079D01*
G01X1101126D02*
X1104079D01*
G01X1097993Y-504912D02*
Y-398386D01*
G01Y-504912D02*
Y-440451D01*
G01X1192481Y-508849D02*
X1097993D01*
G01X1078001Y-468929D02*
X1103055Y-458244D01*
G01D02*
X1131655Y-454751D01*
G01X1097993Y-444388D02*
X1125552D01*
G01X1097993Y-402323D02*
X1145237D01*
G01X1109680Y-107678D02*
X1108706Y-109121D01*
X1107731Y-109843D01*
X1106757Y-109121D01*
X1105782Y-107678D01*
Y-106234D01*
X1106757Y-104790D01*
X1107731Y-104069D01*
X1108706Y-104790D01*
X1109680Y-106234D01*
G01X1089704Y-109843D02*
Y-101181D01*
X1092141Y-108399D01*
X1094576Y-101181D01*
Y-109843D01*
G01X1101885Y-107678D02*
X1100910Y-109121D01*
X1099936Y-109843D01*
X1098961Y-109121D01*
X1097987Y-107678D01*
Y-106234D01*
X1098961Y-104790D01*
X1099936Y-104069D01*
X1100910Y-104790D01*
X1101885Y-106234D01*
Y-107678D01*
G01X1085394Y68675D02*
X1085404Y68678D01*
G01X1085372Y68763D02*
X1085362Y68761D01*
G01X1084501Y68675D02*
X1084511Y68678D01*
G01X1084277Y68675D02*
X1084287Y68678D01*
G01X1084478Y68763D02*
X1084469Y68761D01*
G01X1084255Y68763D02*
X1084245Y68761D01*
G01X1083396Y68776D02*
X1083406Y68779D01*
G01X1085406Y68663D02*
X1085394Y68660D01*
G01X1084882D02*
X1084894Y68663D01*
G01X1085359Y68776D02*
X1085372Y68779D01*
G01X1084717Y68673D02*
X1084730Y68675D01*
G01X1084513Y68663D02*
X1084501Y68660D01*
G01X1084870Y68736D02*
X1084857Y68733D01*
G01X1084385Y68660D02*
X1084397Y68663D01*
G01X1084870Y68779D02*
X1084857Y68776D01*
G01X1084289Y68663D02*
X1084277Y68660D01*
G01X1084385Y68703D02*
X1084397Y68706D01*
G01X1084466Y68776D02*
X1084478Y68779D01*
G01X1084373D02*
X1084360Y68776D01*
G01X1083858Y68673D02*
X1083871Y68675D01*
G01X1084242Y68776D02*
X1084255Y68779D01*
G01X1084075Y68776D02*
X1084087Y68779D01*
G01X1083718Y68723D02*
X1083730Y68726D01*
G01X1083420Y68673D02*
X1083433Y68675D01*
G01X1083558Y68776D02*
X1083570Y68779D01*
G01X1083408Y68766D02*
X1083396Y68763D01*
G01X1084732Y68663D02*
X1084715Y68660D01*
G01X1083873Y68663D02*
X1083856Y68660D01*
G01X1083435Y68663D02*
X1083418Y68660D01*
G01X1083661Y67322D02*
X1080512D01*
G01X1081890D02*
X1088189D01*
G01X1086417D02*
X1089567D01*
G01X1087923Y68562D02*
X1087825D01*
G01X1088268D02*
X1088194D01*
G01X1082047D02*
X1081949D01*
G01X1086024Y68660D02*
X1085935D01*
G01X1085832D02*
X1085817D01*
G01X1085915D02*
X1085901D01*
G01X1085797D02*
X1085709D01*
G01X1085576D02*
X1085561D01*
G01X1085468D02*
X1085453D01*
G01X1085394D02*
X1085372D01*
G01X1085234D02*
X1085219D01*
G01X1085318D02*
X1085303D01*
G01X1085200D02*
X1085106D01*
G01X1084954D02*
X1084939D01*
G01X1084715D02*
X1084705D01*
G01X1084633D02*
X1084619D01*
G01X1084501D02*
X1084478D01*
G01X1084277D02*
X1084255D01*
G01X1084146D02*
X1084087D01*
G01X1083940D02*
X1083917D01*
G01X1084035D02*
X1084013D01*
G01X1083856D02*
X1083846D01*
G01X1083789D02*
X1083730D01*
G01X1083664D02*
X1083649D01*
G01X1083630D02*
X1083570D01*
G01X1083418D02*
X1083413D01*
G01X1083352D02*
X1083258D01*
G01X1084375D02*
X1084385D01*
G01X1085630D02*
X1085689D01*
G01X1084870D02*
X1084882D01*
G01X1084387Y68673D02*
X1084373D01*
G01X1083848D02*
X1083858D01*
G01X1083728D02*
X1083775D01*
G01X1083411D02*
X1083420D01*
G01X1083312D02*
X1083352D01*
G01X1083258D02*
X1083297D01*
G01X1085628D02*
X1085674D01*
G01X1085160D02*
X1085200D01*
G01X1085106D02*
X1085145D01*
G01X1084867D02*
X1084885D01*
G01X1084707D02*
X1084717D01*
G01X1084478Y68675D02*
X1084501D01*
G01X1084255D02*
X1084277D01*
G01X1084085D02*
X1084131D01*
G01X1083568D02*
X1083615D01*
G01X1085935D02*
X1086009D01*
G01X1085709D02*
X1085783D01*
G01X1085372D02*
X1085394D01*
G01X1084353Y68688D02*
X1084341D01*
G01X1083883D02*
X1083895D01*
G01X1083445D02*
X1083457D01*
G01X1084742D02*
X1084754D01*
G01X1084444Y68690D02*
X1084459D01*
G01X1084220D02*
X1084235D01*
G01X1085337D02*
X1085352D01*
G01X1084373Y68703D02*
X1084385D01*
G01X1086009Y68708D02*
X1085945D01*
G01X1085783D02*
X1085719D01*
G01X1085303D02*
X1085234D01*
G01X1085674Y68710D02*
X1085628D01*
G01X1084131D02*
X1084085D01*
G01X1083775D02*
X1083728D01*
G01X1083615D02*
X1083568D01*
G01X1085374Y68713D02*
X1085337D01*
G01X1084481D02*
X1084444D01*
G01X1083420D02*
X1083411D01*
G01X1084370Y68716D02*
X1084387D01*
G01X1084885Y68723D02*
X1084867D01*
G01X1084811D02*
X1084776D01*
G01X1084200D02*
X1084166D01*
G01X1083411D02*
X1083420D01*
G01X1085945D02*
X1086009D01*
G01X1085719D02*
X1085783D01*
G01X1085234D02*
X1085303D01*
G01X1085674Y68726D02*
X1085633D01*
G01X1084131D02*
X1084085D01*
G01X1083615D02*
X1083568D01*
G01X1083730D02*
X1083775D01*
G01X1084459Y68728D02*
X1084481D01*
G01X1085352D02*
X1085374D01*
G01X1084882Y68736D02*
X1084870D01*
G01X1084166D02*
X1084200D01*
G01X1084776D02*
X1084811D01*
G01X1084235Y68748D02*
X1084220D01*
G01X1083460Y68751D02*
X1083448D01*
G01X1084902D02*
X1084914D01*
G01X1086009Y68763D02*
X1085935D01*
G01X1085783D02*
X1085709D01*
G01X1085561D02*
X1085487D01*
G01X1085394D02*
X1085372D01*
G01X1084501D02*
X1084478D01*
G01X1084277D02*
X1084255D01*
G01X1084085D02*
X1084131D01*
G01X1083568D02*
X1083615D01*
G01X1084737Y68766D02*
X1084668D01*
G01X1084387D02*
X1084370D01*
G01X1083878D02*
X1083809D01*
G01X1083423D02*
X1083408D01*
G01X1084867D02*
X1084882D01*
G01X1085613Y68779D02*
X1085596D01*
G01X1085689D02*
X1085674D01*
G01X1084880D02*
X1084870D01*
G01X1084385D02*
X1084373D01*
G01X1084619D02*
X1084633D01*
G01X1084478D02*
X1084501D01*
G01X1084255D02*
X1084277D01*
G01X1084087D02*
X1084146D01*
G01X1083917D02*
X1083932D01*
G01X1084021D02*
X1084035D01*
G01X1083967D02*
X1083986D01*
G01X1083809D02*
X1083898D01*
G01X1083775D02*
X1083789D01*
G01X1083649D02*
X1083664D01*
G01X1083570D02*
X1083630D01*
G01X1083406D02*
X1083425D01*
G01X1083297D02*
X1083312D01*
G01X1085935D02*
X1086024D01*
G01X1085856D02*
X1085876D01*
G01X1085709D02*
X1085797D01*
G01X1085487D02*
X1085576D01*
G01X1085453D02*
X1085468D01*
G01X1085372D02*
X1085394D01*
G01X1085219D02*
X1085234D01*
G01X1085303D02*
X1085318D01*
G01X1085145D02*
X1085160D01*
G01X1084939D02*
X1084954D01*
G01X1084668D02*
X1084757D01*
G01X1081887Y68951D02*
X1082109D01*
G01X1081875Y69002D02*
X1082121D01*
G01X1082170Y69153D02*
X1082244D01*
G01X1081752D02*
X1081826D01*
G01X1087825D02*
X1087923D01*
G01X1088194D02*
X1088268D01*
G01X1089567Y70471D02*
X1086417D01*
G01X1088189D02*
X1081890D01*
G01X1080512D02*
X1083661D01*
G01X1083413Y68660D02*
X1083396Y68663D01*
G01Y68726D02*
X1083411Y68723D01*
G01X1083846Y68660D02*
X1083831Y68663D01*
G01X1084705Y68660D02*
X1084690Y68663D01*
G01X1083398Y68675D02*
X1083411Y68673D01*
G01X1083570Y68660D02*
X1083558Y68663D01*
G01X1083730Y68660D02*
X1083718Y68663D01*
G01X1083836Y68675D02*
X1083848Y68673D01*
G01X1083435Y68763D02*
X1083423Y68766D01*
G01X1084087Y68660D02*
X1084075Y68663D01*
G01X1084255Y68660D02*
X1084242Y68663D01*
G01X1084363D02*
X1084375Y68660D01*
G01X1084478D02*
X1084466Y68663D01*
G01X1084360Y68706D02*
X1084373Y68703D01*
G01X1084695Y68675D02*
X1084707Y68673D01*
G01X1084277Y68779D02*
X1084289Y68776D01*
G01X1084857Y68663D02*
X1084870Y68660D01*
G01X1084397Y68776D02*
X1084385Y68779D01*
G01X1084501D02*
X1084513Y68776D01*
G01X1084894Y68733D02*
X1084882Y68736D01*
G01X1085372Y68660D02*
X1085359Y68663D01*
G01X1084892Y68776D02*
X1084880Y68779D01*
G01X1085618Y68663D02*
X1085630Y68660D01*
G01X1085394Y68779D02*
X1085406Y68776D01*
G01X1083425Y68779D02*
X1083435Y68776D01*
G01X1084469Y68678D02*
X1084478Y68675D01*
G01X1084287Y68761D02*
X1084277Y68763D01*
G01X1084245Y68678D02*
X1084255Y68675D01*
G01X1084511Y68761D02*
X1084501Y68763D01*
G01X1085362Y68678D02*
X1085372Y68675D01*
G01X1085404Y68761D02*
X1085394Y68763D01*
G01X1083561Y68678D02*
X1083568Y68675D01*
G01Y68726D02*
X1083561Y68728D01*
G01X1083720Y68675D02*
X1083728Y68673D01*
G01X1084078Y68678D02*
X1084085Y68675D01*
G01Y68726D02*
X1084078Y68728D01*
G01X1084373Y68673D02*
X1084365Y68675D01*
G01X1084363Y68718D02*
X1084370Y68716D01*
G01X1084395Y68763D02*
X1084387Y68766D01*
G01X1084860Y68675D02*
X1084867Y68673D01*
G01X1084892Y68721D02*
X1084885Y68723D01*
G01X1084882Y68766D02*
X1084889Y68763D01*
G01X1085620Y68675D02*
X1085628Y68673D01*
G01X1083391Y68718D02*
X1083379Y68723D01*
G01X1083396Y68663D02*
X1083386Y68668D01*
G01X1083440Y68761D02*
X1083435Y68763D01*
G01X1083553Y68718D02*
X1083548Y68721D01*
G01X1083435Y68776D02*
X1083445Y68771D01*
G01X1083831Y68663D02*
X1083822Y68668D01*
G01X1084070Y68718D02*
X1084065Y68721D01*
G01X1084242Y68663D02*
X1084232Y68668D01*
G01X1084466Y68663D02*
X1084456Y68668D01*
G01X1084289Y68776D02*
X1084299Y68771D01*
G01X1084690Y68663D02*
X1084680Y68668D01*
G01X1084513Y68776D02*
X1084523Y68771D01*
G01X1085359Y68663D02*
X1085350Y68668D01*
G01X1085406Y68776D02*
X1085416Y68771D01*
G01X1084350Y68670D02*
X1084363Y68663D01*
G01X1084348Y68713D02*
X1084360Y68706D01*
G01X1084409Y68768D02*
X1084397Y68776D01*
G01X1084845Y68670D02*
X1084857Y68663D01*
G01X1084907Y68726D02*
X1084894Y68733D01*
G01X1084904Y68768D02*
X1084892Y68776D01*
G01X1083391Y68680D02*
X1083398Y68675D01*
G01X1083389Y68730D02*
X1083396Y68726D01*
G01X1083487Y68686D02*
X1083480Y68690D01*
G01X1083445Y68771D02*
X1083452Y68766D01*
G01X1083511Y68753D02*
X1083519Y68748D01*
G01X1083829Y68680D02*
X1083836Y68675D01*
G01X1084237Y68683D02*
X1084245Y68678D01*
G01X1084365Y68675D02*
X1084358Y68680D01*
G01X1084294Y68756D02*
X1084287Y68761D01*
G01X1084356Y68723D02*
X1084363Y68718D01*
G01X1084461Y68683D02*
X1084469Y68678D01*
G01X1084402Y68758D02*
X1084395Y68763D01*
G01X1084567Y68686D02*
X1084560Y68690D01*
G01X1084518Y68756D02*
X1084511Y68761D01*
G01X1084688Y68680D02*
X1084695Y68675D01*
G01X1084592Y68753D02*
X1084599Y68748D01*
G01X1084852Y68680D02*
X1084860Y68675D01*
G01X1084899Y68716D02*
X1084892Y68721D01*
G01X1084889Y68763D02*
X1084897Y68758D01*
G01X1085354Y68683D02*
X1085362Y68678D01*
G01X1085411Y68756D02*
X1085404Y68761D01*
G01X1083558Y68663D02*
X1083548Y68670D01*
G01X1083718Y68663D02*
X1083708Y68670D01*
G01X1084075Y68663D02*
X1084065Y68670D01*
G01X1085608D02*
X1085618Y68663D01*
G01X1083556Y68683D02*
X1083561Y68678D01*
G01Y68728D02*
X1083556Y68733D01*
G01X1084072Y68683D02*
X1084078Y68678D01*
G01Y68728D02*
X1084072Y68733D01*
G01X1083386Y68668D02*
X1083376Y68678D01*
G01X1083445Y68756D02*
X1083440Y68761D01*
G01X1083716Y68680D02*
X1083720Y68675D01*
G01X1083822Y68668D02*
X1083812Y68678D01*
G01X1084232Y68668D02*
X1084222Y68678D01*
G01X1084341Y68721D02*
X1084348Y68713D01*
G01X1084299Y68771D02*
X1084309Y68761D01*
G01X1084350Y68728D02*
X1084356Y68723D01*
G01X1084456Y68668D02*
X1084446Y68678D01*
G01X1084523Y68771D02*
X1084533Y68761D01*
G01X1084680Y68668D02*
X1084670Y68678D01*
G01X1085350Y68668D02*
X1085340Y68678D01*
G01X1085416Y68771D02*
X1085426Y68761D01*
G01X1085615Y68680D02*
X1085620Y68675D01*
G01X1083548Y68670D02*
X1083541Y68680D01*
G01X1083548Y68721D02*
X1083541Y68730D01*
G01X1083708Y68670D02*
X1083701Y68680D01*
G01X1084065Y68670D02*
X1084058Y68680D01*
G01X1084065Y68721D02*
X1084058Y68730D01*
G01X1084343Y68680D02*
X1084350Y68670D01*
G01X1084417Y68758D02*
X1084409Y68768D01*
G01X1084838Y68680D02*
X1084845Y68670D01*
G01X1084914Y68716D02*
X1084907Y68726D01*
G01X1084911Y68758D02*
X1084904Y68768D01*
G01X1085600Y68680D02*
X1085608Y68670D01*
G01X1083386Y68688D02*
X1083391Y68680D01*
G01X1083379Y68723D02*
X1083374Y68730D01*
G01X1083452Y68766D02*
X1083457Y68758D01*
G01X1083824Y68688D02*
X1083829Y68680D01*
G01X1084299Y68748D02*
X1084294Y68756D01*
G01X1084358Y68680D02*
X1084353Y68688D01*
G01X1084407Y68751D02*
X1084402Y68758D01*
G01X1084523Y68748D02*
X1084518Y68756D01*
G01X1084683Y68688D02*
X1084688Y68680D01*
G01X1084848Y68688D02*
X1084852Y68680D01*
G01X1084904Y68708D02*
X1084899Y68716D01*
G01X1084897Y68758D02*
X1084902Y68751D01*
G01X1085416Y68748D02*
X1085411Y68756D01*
G01X1087923Y69153D02*
X1088108Y68864D01*
G01X1088046Y68801D02*
X1087825Y69153D01*
G01X1083383Y68741D02*
X1083389Y68730D01*
G01X1083448Y68751D02*
X1083445Y68756D01*
G01X1084309Y68761D02*
X1084314Y68751D01*
G01X1084533Y68761D02*
X1084537Y68751D01*
G01X1085426Y68761D02*
X1085431Y68751D01*
G01X1084336Y68733D02*
X1084341Y68721D01*
G01X1084422Y68746D02*
X1084417Y68758D01*
G01X1084833Y68693D02*
X1084838Y68680D01*
G01X1084919Y68703D02*
X1084914Y68716D01*
G01X1085596Y68779D02*
X1085618Y68721D01*
G01X1085633Y68726D02*
X1085613Y68779D01*
G01X1083986D02*
X1084021Y68686D01*
G01X1084013Y68660D02*
X1083976Y68766D01*
G01X1085901Y68660D02*
X1085866Y68763D01*
G01X1081949Y68562D02*
X1081752Y69153D01*
G01X1085876Y68779D02*
X1085915Y68660D01*
G01X1081998Y68612D02*
X1081887Y68951D01*
G01X1081826Y69153D02*
X1081875Y69002D01*
G01X1083457Y68758D02*
X1083460Y68751D01*
G01X1083541Y68680D02*
X1083539Y68688D01*
G01X1083553Y68690D02*
X1083556Y68683D01*
G01X1083541Y68730D02*
X1083539Y68738D01*
G01X1083556Y68733D02*
X1083553Y68741D01*
G01X1083701Y68680D02*
X1083698Y68688D01*
G01X1083713D02*
X1083716Y68680D01*
G01X1084058D02*
X1084055Y68688D01*
G01X1084070Y68690D02*
X1084072Y68683D01*
G01X1084058Y68730D02*
X1084055Y68738D01*
G01X1084072Y68733D02*
X1084070Y68741D01*
G01X1084235Y68690D02*
X1084237Y68683D01*
G01X1084341Y68688D02*
X1084343Y68680D01*
G01X1084348Y68736D02*
X1084350Y68728D01*
G01X1084409Y68743D02*
X1084407Y68751D01*
G01X1084459Y68690D02*
X1084461Y68683D01*
G01X1084845Y68695D02*
X1084848Y68688D01*
G01X1084907Y68701D02*
X1084904Y68708D01*
G01X1084914Y68751D02*
X1084911Y68758D01*
G01X1085352Y68690D02*
X1085354Y68683D01*
G01X1085598Y68688D02*
X1085600Y68680D01*
G01X1085613Y68688D02*
X1085615Y68680D01*
G01X1083376Y68678D02*
X1083374Y68688D01*
G01Y68730D02*
X1083371Y68741D01*
G01X1083812Y68678D02*
X1083809Y68688D01*
G01X1084301Y68738D02*
X1084299Y68748D01*
G01X1084525Y68738D02*
X1084523Y68748D01*
G01X1084670Y68678D02*
X1084668Y68688D01*
G01X1085419Y68738D02*
X1085416Y68748D01*
G01X1084222Y68678D02*
X1084220Y68690D01*
G01X1084314Y68751D02*
X1084316Y68738D01*
G01X1084446Y68678D02*
X1084444Y68690D01*
G01X1084537Y68751D02*
X1084540Y68738D01*
G01X1085340Y68678D02*
X1085337Y68690D01*
G01X1085431Y68751D02*
X1085433Y68738D01*
G01X1084424Y68728D02*
X1084422Y68746D01*
G01X1084830Y68710D02*
X1084833Y68693D01*
G01X1080512Y67322D02*
Y70471D01*
G01X1081890D02*
Y67322D01*
G01X1082677Y70471D02*
Y67322D01*
G01X1082841Y70471D02*
Y67322D01*
G01X1083258Y68660D02*
Y68673D01*
G01X1083297D02*
Y68779D01*
G01X1083312D02*
Y68673D01*
G01X1083352D02*
Y68660D01*
G01X1083371Y68741D02*
Y68751D01*
G01X1083374Y68688D02*
Y68693D01*
G01X1083383Y68751D02*
Y68741D01*
G01X1083386Y68693D02*
Y68688D01*
G01X1083420Y68723D02*
Y68713D01*
G01X1083539Y68688D02*
Y68698D01*
G01Y68738D02*
Y68751D01*
G01X1083553Y68695D02*
Y68690D01*
G01Y68741D02*
Y68748D01*
G01X1083615Y68763D02*
Y68726D01*
G01Y68675D02*
Y68710D01*
G01X1083630Y68779D02*
Y68660D01*
G01X1083649D02*
Y68779D01*
G01X1083661Y70471D02*
Y67322D01*
G01X1083664Y68779D02*
Y68680D01*
G01X1083679Y68698D02*
Y68678D01*
G01X1083698Y68688D02*
Y68698D01*
G01X1083713Y68695D02*
Y68688D01*
G01X1083775Y68726D02*
Y68779D01*
G01Y68673D02*
Y68710D01*
G01X1083789Y68779D02*
Y68660D01*
G01X1083809Y68766D02*
Y68779D01*
G01Y68688D02*
Y68693D01*
G01X1083824D02*
Y68688D01*
G01X1083898Y68779D02*
Y68766D01*
G01X1083917Y68660D02*
Y68779D01*
G01X1083932D02*
Y68686D01*
G01X1084021D02*
Y68779D01*
G01X1084035D02*
Y68660D01*
G01X1084055Y68688D02*
Y68698D01*
G01Y68738D02*
Y68751D01*
G01X1084070Y68695D02*
Y68690D01*
G01Y68741D02*
Y68748D01*
G01X1084131Y68763D02*
Y68726D01*
G01Y68675D02*
Y68710D01*
G01X1084146Y68779D02*
Y68660D01*
G01X1084166Y68723D02*
Y68736D01*
G01X1084200D02*
Y68723D01*
G01X1084301Y68701D02*
Y68738D01*
G01X1084316D02*
Y68701D01*
G01X1084336Y68746D02*
Y68733D01*
G01X1084348Y68743D02*
Y68736D01*
G01X1084409D02*
Y68743D01*
G01X1084412Y68716D02*
Y68710D01*
G01X1084424D02*
Y68728D01*
G01X1084444Y68713D02*
Y68751D01*
G01X1084459Y68748D02*
Y68728D01*
G01X1084481D02*
Y68713D01*
G01X1084525Y68701D02*
Y68738D01*
G01X1084540D02*
Y68701D01*
G01X1084619Y68660D02*
Y68779D01*
G01X1084633D02*
Y68680D01*
G01X1084648Y68698D02*
Y68678D01*
G01X1084668Y68766D02*
Y68779D01*
G01Y68688D02*
Y68693D01*
G01X1084683D02*
Y68688D01*
G01X1084757Y68779D02*
Y68766D01*
G01X1084776Y68723D02*
Y68736D01*
G01X1084811D02*
Y68723D01*
G01X1084830Y68728D02*
Y68710D01*
G01X1084843Y68723D02*
Y68728D01*
G01X1084845Y68701D02*
Y68695D01*
G01X1084907D02*
Y68701D01*
G01X1084919Y68693D02*
Y68703D01*
G01X1084939Y68660D02*
Y68779D01*
G01X1084954D02*
Y68680D01*
G01X1084968Y68698D02*
Y68678D01*
G01X1085106Y68660D02*
Y68673D01*
G01X1085145D02*
Y68779D01*
G01X1085160D02*
Y68673D01*
G01X1085200D02*
Y68660D01*
G01X1085219D02*
Y68779D01*
G01X1085234D02*
Y68723D01*
G01Y68708D02*
Y68660D01*
G01X1085303Y68723D02*
Y68779D01*
G01Y68660D02*
Y68708D01*
G01X1085318Y68779D02*
Y68660D01*
G01X1085337Y68713D02*
Y68751D01*
G01X1085352Y68748D02*
Y68728D01*
G01X1085374D02*
Y68713D01*
G01X1085419Y68701D02*
Y68738D01*
G01X1085433D02*
Y68701D01*
G01X1085453Y68660D02*
Y68779D01*
G01X1085468D02*
Y68660D01*
G01X1085487Y68763D02*
Y68779D01*
G01X1085561Y68660D02*
Y68763D01*
G01X1085576Y68779D02*
Y68660D01*
G01X1085598Y68698D02*
Y68688D01*
G01X1085613Y68695D02*
Y68688D01*
G01X1085674Y68779D02*
Y68726D01*
G01Y68673D02*
Y68710D01*
G01X1085689Y68660D02*
Y68779D01*
G01X1085709Y68660D02*
Y68675D01*
G01Y68763D02*
Y68779D01*
G01X1085719Y68708D02*
Y68723D01*
G01X1085783D02*
Y68763D01*
G01Y68675D02*
Y68708D01*
G01X1085797Y68779D02*
Y68660D01*
G01X1085935D02*
Y68675D01*
G01Y68763D02*
Y68779D01*
G01X1085945Y68708D02*
Y68723D01*
G01X1086009D02*
Y68763D01*
G01Y68675D02*
Y68708D01*
G01X1086024Y68779D02*
Y68660D01*
G01X1086417Y70471D02*
Y67322D01*
G01X1087238D02*
Y70471D01*
G01X1087402D02*
Y67322D01*
G01X1088189D02*
Y70471D01*
G01X1088194Y68951D02*
Y69153D01*
G01Y68562D02*
Y68851D01*
G01X1088268Y69153D02*
Y68562D01*
G01X1089567Y67322D02*
Y70471D01*
G01X1084422Y68693D02*
X1084424Y68710D01*
G01X1084833Y68746D02*
X1084830Y68728D01*
G01X1084412Y68710D02*
X1084409Y68695D01*
G01X1084843Y68728D02*
X1084845Y68743D01*
G01X1084220Y68748D02*
X1084222Y68761D01*
G01X1084316Y68701D02*
X1084314Y68688D01*
G01X1084540Y68701D02*
X1084537Y68688D01*
G01X1085433Y68701D02*
X1085431Y68688D01*
G01X1083374Y68693D02*
X1083376Y68703D01*
G01X1083457Y68688D02*
X1083455Y68678D01*
G01X1083809Y68693D02*
X1083812Y68703D01*
G01X1083895Y68688D02*
X1083893Y68678D01*
G01X1084299Y68690D02*
X1084301Y68701D01*
G01X1084444Y68751D02*
X1084446Y68761D01*
G01X1084523Y68690D02*
X1084525Y68701D01*
G01X1084668Y68693D02*
X1084670Y68703D01*
G01X1084754Y68688D02*
X1084752Y68678D01*
G01X1085337Y68751D02*
X1085340Y68761D01*
G01X1085416Y68690D02*
X1085419Y68701D01*
G01X1083411Y68713D02*
X1083396Y68708D01*
G01X1083561Y68761D02*
X1083568Y68763D01*
G01Y68710D02*
X1083561Y68708D01*
G01X1083728Y68710D02*
X1083720Y68708D01*
G01X1084078Y68761D02*
X1084085Y68763D01*
G01Y68710D02*
X1084078Y68708D01*
G01X1084370Y68766D02*
X1084363Y68763D01*
G01X1084387Y68716D02*
X1084395Y68718D01*
G01Y68675D02*
X1084387Y68673D01*
G01X1084860Y68763D02*
X1084867Y68766D01*
G01Y68723D02*
X1084860Y68721D01*
G01X1084885Y68673D02*
X1084892Y68675D01*
G01X1085628Y68710D02*
X1085620Y68708D01*
G01X1082121Y69002D02*
X1082170Y69153D01*
G01X1082109Y68951D02*
X1081998Y68612D01*
G01X1083371Y68751D02*
X1083374Y68758D01*
G01X1083539Y68751D02*
X1083541Y68758D01*
G01X1083553Y68748D02*
X1083556Y68756D01*
G01X1083539Y68698D02*
X1083541Y68706D01*
G01X1083556Y68703D02*
X1083553Y68695D01*
G01X1083698Y68698D02*
X1083701Y68706D01*
G01X1083716Y68703D02*
X1083713Y68695D01*
G01X1084055Y68751D02*
X1084058Y68758D01*
G01X1084070Y68748D02*
X1084072Y68756D01*
G01X1084055Y68698D02*
X1084058Y68706D01*
G01X1084072Y68703D02*
X1084070Y68695D01*
G01X1084237Y68756D02*
X1084235Y68748D01*
G01X1084350Y68751D02*
X1084348Y68743D01*
G01X1084407Y68728D02*
X1084409Y68736D01*
G01Y68695D02*
X1084407Y68688D01*
G01X1084461Y68756D02*
X1084459Y68748D01*
G01X1084845Y68743D02*
X1084848Y68751D01*
G01Y68708D02*
X1084845Y68701D01*
G01X1084904Y68688D02*
X1084907Y68695D01*
G01X1085354Y68756D02*
X1085352Y68748D01*
G01X1085600Y68706D02*
X1085598Y68698D01*
G01X1085615Y68703D02*
X1085613Y68695D01*
G01X1082244Y69153D02*
X1082047Y68562D01*
G01X1085817Y68660D02*
X1085856Y68779D01*
G01X1085866Y68763D02*
X1085832Y68660D01*
G01X1083976Y68766D02*
X1083940Y68660D01*
G01X1083932Y68686D02*
X1083967Y68779D01*
G01X1084341Y68758D02*
X1084336Y68746D01*
G01X1084417Y68680D02*
X1084422Y68693D01*
G01X1084838Y68758D02*
X1084833Y68746D01*
G01X1084914Y68680D02*
X1084919Y68693D01*
G01X1083386Y68756D02*
X1083383Y68751D01*
G01X1083391Y68703D02*
X1083386Y68693D01*
G01X1083829Y68703D02*
X1083824Y68693D01*
G01X1084314Y68688D02*
X1084309Y68678D01*
G01X1084537Y68688D02*
X1084533Y68678D01*
G01X1084688Y68703D02*
X1084683Y68693D01*
G01X1085431Y68688D02*
X1085426Y68678D01*
G01X1083480Y68690D02*
X1083511Y68753D01*
G01X1083519Y68748D02*
X1083487Y68686D01*
G01X1084560Y68690D02*
X1084592Y68753D01*
G01X1084599Y68748D02*
X1084567Y68686D01*
G01X1083374Y68758D02*
X1083379Y68766D01*
G01X1083376Y68703D02*
X1083381Y68710D01*
G01X1083440Y68680D02*
X1083445Y68688D01*
G01X1083812Y68703D02*
X1083817Y68710D01*
G01X1083878Y68680D02*
X1083883Y68688D01*
G01X1084294Y68683D02*
X1084299Y68690D01*
G01X1084356Y68758D02*
X1084350Y68751D01*
G01X1084407Y68688D02*
X1084402Y68680D01*
G01X1084518Y68683D02*
X1084523Y68690D01*
G01X1084670Y68703D02*
X1084675Y68710D01*
G01X1084737Y68680D02*
X1084742Y68688D01*
G01X1084848Y68751D02*
X1084852Y68758D01*
G01Y68716D02*
X1084848Y68708D01*
G01X1084899Y68680D02*
X1084904Y68688D01*
G01X1085411Y68683D02*
X1085416Y68690D01*
G01X1083541Y68758D02*
X1083548Y68768D01*
G01X1083541Y68706D02*
X1083548Y68716D01*
G01X1083701Y68706D02*
X1083708Y68716D01*
G01X1084058Y68758D02*
X1084065Y68768D01*
G01X1084058Y68706D02*
X1084065Y68716D01*
G01X1084348Y68768D02*
X1084341Y68758D01*
G01X1084409Y68670D02*
X1084417Y68680D01*
G01X1084845Y68768D02*
X1084838Y68758D01*
G01X1084907Y68670D02*
X1084914Y68680D01*
G01X1085608Y68716D02*
X1085600Y68706D01*
G01X1083664Y68680D02*
X1083679Y68698D01*
G01Y68678D02*
X1083664Y68660D01*
G01X1084633Y68680D02*
X1084648Y68698D01*
G01Y68678D02*
X1084633Y68660D01*
G01X1084954Y68680D02*
X1084968Y68698D01*
G01Y68678D02*
X1084954Y68660D01*
G01X1087825Y68562D02*
X1088046Y68801D01*
G01X1088194Y68851D02*
X1087923Y68562D01*
G01X1083391Y68761D02*
X1083386Y68756D01*
G01X1083396Y68708D02*
X1083391Y68703D01*
G01X1083455Y68678D02*
X1083445Y68668D01*
G01X1083556Y68756D02*
X1083561Y68761D01*
G01Y68708D02*
X1083556Y68703D01*
G01X1083720Y68708D02*
X1083716Y68703D01*
G01X1083893Y68678D02*
X1083883Y68668D01*
G01X1084072Y68756D02*
X1084078Y68761D01*
G01Y68708D02*
X1084072Y68703D01*
G01X1084222Y68761D02*
X1084232Y68771D01*
G01X1084309Y68678D02*
X1084299Y68668D01*
G01X1084402Y68723D02*
X1084407Y68728D01*
G01X1084446Y68761D02*
X1084456Y68771D01*
G01X1084533Y68678D02*
X1084523Y68668D01*
G01X1084752Y68678D02*
X1084742Y68668D01*
G01X1085340Y68761D02*
X1085350Y68771D01*
G01X1085426Y68678D02*
X1085416Y68668D01*
G01X1085620Y68708D02*
X1085615Y68703D01*
G01X1088108Y68864D02*
X1088194Y68951D01*
G01X1083898Y68766D02*
X1083829Y68703D01*
G01X1084757Y68766D02*
X1084688Y68703D01*
G01X1083817Y68710D02*
X1083878Y68766D01*
G01X1084675Y68710D02*
X1084737Y68766D01*
G01X1083381Y68710D02*
X1083391Y68718D01*
G01X1083548Y68768D02*
X1083558Y68776D01*
G01X1083708Y68716D02*
X1083718Y68723D01*
G01X1084065Y68768D02*
X1084075Y68776D01*
G01X1083379Y68766D02*
X1083386Y68771D01*
G01X1083433Y68675D02*
X1083440Y68680D01*
G01X1083871Y68675D02*
X1083878Y68680D01*
G01X1084245Y68761D02*
X1084237Y68756D01*
G01X1084363Y68763D02*
X1084356Y68758D01*
G01X1084287Y68678D02*
X1084294Y68683D01*
G01X1084395Y68718D02*
X1084402Y68723D01*
G01X1084469Y68761D02*
X1084461Y68756D01*
G01X1084397Y68706D02*
X1084412Y68716D01*
G01X1084402Y68680D02*
X1084395Y68675D01*
G01X1084511Y68678D02*
X1084518Y68683D01*
G01X1084730Y68675D02*
X1084737Y68680D01*
G01X1084852Y68758D02*
X1084860Y68763D01*
G01X1084857Y68733D02*
X1084843Y68723D01*
G01X1084860Y68721D02*
X1084852Y68716D01*
G01X1084892Y68675D02*
X1084899Y68680D01*
G01X1085362Y68761D02*
X1085354Y68756D01*
G01X1085404Y68678D02*
X1085411Y68683D01*
G01X1084360Y68776D02*
X1084348Y68768D01*
G01X1084397Y68663D02*
X1084409Y68670D01*
G01X1084857Y68776D02*
X1084845Y68768D01*
G01X1084894Y68663D02*
X1084907Y68670D01*
G01X1083386Y68771D02*
X1083396Y68776D01*
G01Y68763D02*
X1083391Y68761D01*
G01X1083445Y68668D02*
X1083435Y68663D01*
G01X1083548Y68716D02*
X1083553Y68718D01*
G01X1083883Y68668D02*
X1083873Y68663D01*
G01X1084065Y68716D02*
X1084070Y68718D01*
G01X1084232Y68771D02*
X1084242Y68776D01*
G01X1084456Y68771D02*
X1084466Y68776D01*
G01X1084299Y68668D02*
X1084289Y68663D01*
G01X1084523Y68668D02*
X1084513Y68663D01*
G01X1084742Y68668D02*
X1084732Y68663D01*
G01X1085350Y68771D02*
X1085359Y68776D01*
G01X1085416Y68668D02*
X1085406Y68663D01*
G01X1085618Y68721D02*
X1085608Y68716D01*
G01X1079882Y89074D02*
X1077913D01*
G01X1079882Y91042D02*
X1077913D01*
G01X1079882Y93582D02*
X1077913D01*
G01X1079882Y95550D02*
X1077913D01*
G01X1079882Y98995D02*
X1077913D01*
G01X1079882Y100964D02*
X1077913D01*
G01X1079882Y103424D02*
X1077913D01*
G01X1079882Y105393D02*
X1077913D01*
G01X1080039Y95964D02*
X1077874Y96948D01*
G01X1080039Y105964D02*
X1077874Y106948D01*
G01X1076437Y113405D02*
Y90885D01*
G01Y103405D02*
Y100885D01*
G01Y93405D02*
Y90885D01*
G01X1077874Y107342D02*
Y106948D01*
G01Y97342D02*
Y96948D01*
G01X1077913Y105393D02*
Y103424D01*
G01Y100964D02*
Y98995D01*
G01Y95550D02*
Y93582D01*
G01Y91042D02*
Y89074D01*
G01X1079882Y105393D02*
Y103424D01*
G01Y100964D02*
Y98995D01*
G01Y95550D02*
Y93582D01*
G01Y91042D02*
Y89074D01*
G01X1080039Y105964D02*
Y98326D01*
G01Y95964D02*
Y88621D01*
G01Y108326D02*
X1077874Y107342D01*
G01Y97342D02*
X1080039Y98326D01*
G01Y88621D02*
X1078701Y87637D01*
G01X1092913Y74566D02*
Y200550D01*
G01X1079882Y113267D02*
X1077913D01*
G01X1079882Y115235D02*
X1077913D01*
G01X1080039Y115668D02*
X1078701Y116653D01*
G01X1077913Y115235D02*
Y113267D01*
G01X1079882Y115235D02*
Y113267D01*
G01Y108916D02*
X1077913D01*
G01X1079882Y110885D02*
X1077913D01*
G01X1076437Y113405D02*
Y110885D01*
G01X1077913D02*
Y108916D01*
G01X1079882Y110885D02*
Y108916D01*
G01X1080039Y115668D02*
Y108326D01*
G01X1100098Y883464D02*
Y892519D01*
G01X1102264D02*
Y883464D01*
G01X1103248D02*
Y892519D01*
G01X1105413D02*
Y883464D01*
G01X1106398D02*
Y892519D01*
G01X1108563D02*
Y883464D01*
G01D02*
X1106398D01*
G01X1105413D02*
X1103248D01*
G01X1102264D02*
X1100098D01*
G01X1077067Y892519D02*
Y883464D01*
G01X1078051D02*
Y892519D01*
G01X1080217D02*
Y883464D01*
G01X1081201D02*
Y892519D01*
G01X1083366D02*
Y883464D01*
G01X1084350D02*
Y892519D01*
G01X1086516D02*
Y883464D01*
G01X1087500D02*
Y892519D01*
G01X1089665D02*
Y883464D01*
G01X1090650D02*
Y892519D01*
G01X1092815D02*
Y883464D01*
G01X1093799D02*
Y892519D01*
G01X1095965D02*
Y883464D01*
G01X1096949D02*
Y892519D01*
G01X1099114D02*
Y883464D01*
G01D02*
X1096949D01*
G01X1095965D02*
X1093799D01*
G01X1092815D02*
X1090650D01*
G01X1089665D02*
X1087500D01*
G01X1086516D02*
X1084350D01*
G01X1083366D02*
X1081201D01*
G01X1080217D02*
X1078051D01*
G01X1103248Y892519D02*
X1105413D01*
G01X1100098D02*
X1102264D01*
G01X1106398D02*
X1108563D01*
G01X1078051D02*
X1080217D01*
G01X1084350D02*
X1086516D01*
G01X1081201D02*
X1083366D01*
G01X1087500D02*
X1089665D01*
G01X1093799D02*
X1095965D01*
G01X1090650D02*
X1092815D01*
G01X1096949D02*
X1099114D01*
G01X1205512Y939354D02*
X1101694D01*
G01D02*
X1209843D01*
G01X1103643Y948737D02*
X1104130Y949459D01*
X1105105Y950180D01*
X1106079D01*
X1107054Y949459D01*
X1107541Y948737D01*
Y947293D01*
X1107054Y946572D01*
X1105105Y945128D01*
G01D02*
X1104130Y943684D01*
X1103643Y941519D01*
X1107541D01*
G01X1142710Y-779736D02*
X1141735Y-779014D01*
X1141248Y-778292D01*
X1140761Y-776849D01*
Y-773962D01*
X1141248Y-772518D01*
X1141735Y-771796D01*
X1142710Y-771075D01*
X1143684Y-771796D01*
X1144171Y-772518D01*
X1144659Y-773962D01*
Y-776849D01*
X1144171Y-778292D01*
X1143684Y-779014D01*
X1142710Y-779736D01*
G01X1119324D02*
X1118837D01*
Y-779014D01*
X1119324Y-779736D01*
G01X1127119D02*
X1126145Y-779014D01*
X1125657Y-778292D01*
X1125170Y-776849D01*
Y-773962D01*
X1125657Y-772518D01*
X1126145Y-771796D01*
X1127119Y-771075D01*
X1128094Y-771796D01*
X1128581Y-772518D01*
X1129068Y-773962D01*
Y-776849D01*
X1128581Y-778292D01*
X1128094Y-779014D01*
X1127119Y-779736D01*
G01X1134915D02*
X1133940Y-779014D01*
X1133453Y-778292D01*
X1132966Y-776849D01*
Y-773962D01*
X1133453Y-772518D01*
X1133940Y-771796D01*
X1134915Y-771075D01*
X1135889Y-771796D01*
X1136376Y-772518D01*
X1136863Y-773962D01*
Y-776849D01*
X1136376Y-778292D01*
X1135889Y-779014D01*
X1134915Y-779736D01*
G01X1109580Y-772518D02*
X1110067Y-771796D01*
X1111041Y-771075D01*
X1112016D01*
X1112990Y-771796D01*
X1113478Y-772518D01*
Y-773962D01*
X1112990Y-774683D01*
G01D02*
X1111041Y-776127D01*
X1110067Y-777571D01*
X1109580Y-779736D01*
X1113478D01*
G01X1140274Y-761692D02*
X1143684D01*
G01X1144659Y-763135D02*
X1143684Y-761692D01*
X1144171Y-760970D01*
Y-758804D01*
X1143684Y-758082D01*
X1140274D01*
G01D02*
Y-766744D01*
X1143684D01*
G01X1111529Y-758082D02*
Y-766744D01*
G01X1117375Y-758082D02*
Y-766744D01*
X1121273D01*
G01X1150033Y-730346D02*
X1135169Y-722453D01*
G01D02*
X1134613Y-721631D01*
G01D02*
X1134067Y-720792D01*
G01X1133511Y-719968D02*
X1118939Y-711221D01*
G01X1134067Y-720792D02*
X1133511Y-719968D01*
G01X1142465Y-687087D02*
X1145417Y-687590D01*
G01X1142465Y-687087D02*
X1145417Y-687590D01*
G01X1142957Y-684574D02*
X1145417Y-685077D01*
G01X1142957Y-684574D02*
X1145417Y-685077D01*
G01X1140004Y-685579D02*
X1142465Y-687087D01*
G01X1140004Y-685579D02*
X1142465Y-687087D01*
G01X1141480Y-683569D02*
X1142957Y-684574D01*
G01X1141480Y-683569D02*
X1142957Y-684574D01*
G01X1138528Y-684071D02*
X1140004Y-685579D01*
G01X1138528Y-684071D02*
X1140004Y-685579D01*
G01X1139512Y-680553D02*
X1141480Y-683569D01*
G01X1139512Y-680553D02*
X1141480Y-683569D01*
G01X1137543Y-682061D02*
X1138528Y-684071D01*
G01X1137543Y-682061D02*
X1138528Y-684071D01*
G01X1137051Y-680553D02*
X1137543Y-682061D01*
G01X1137051Y-680553D02*
X1137543Y-682061D01*
G01X1136559Y-678040D02*
X1137051Y-680553D01*
G01X1136559Y-678040D02*
X1137051Y-680553D01*
G01X1139020Y-677538D02*
X1139512Y-680553D01*
G01X1139020Y-677538D02*
X1139512Y-680553D01*
G01X1136559Y-673517D02*
Y-678040D01*
G01Y-673517D02*
Y-678040D01*
G01X1139020Y-674020D02*
Y-677538D01*
G01Y-674020D02*
Y-677538D01*
G01X1139512Y-671004D02*
X1139020Y-674020D01*
G01X1139512Y-671004D02*
X1139020Y-674020D01*
G01X1137051Y-671004D02*
X1136559Y-673517D01*
G01X1137051Y-671004D02*
X1136559Y-673517D01*
G01X1137543Y-669496D02*
X1137051Y-671004D01*
G01X1137543Y-669496D02*
X1137051Y-671004D01*
G01X1138528Y-667486D02*
X1137543Y-669496D01*
G01X1138528Y-667486D02*
X1137543Y-669496D01*
G01X1141480Y-667988D02*
X1139512Y-671004D01*
G01X1141480Y-667988D02*
X1139512Y-671004D01*
G01X1120811Y-687590D02*
X1117858D01*
G01X1120811D02*
X1117858D01*
G01X1132622Y-679548D02*
X1124748D01*
G01X1132622D02*
X1124748D01*
G01Y-677538D02*
X1132622D01*
G01X1124748D02*
X1132622D01*
G01Y-673517D02*
X1124748D01*
G01X1132622D02*
X1124748D01*
G01Y-671507D02*
X1132622D01*
G01X1124748D02*
X1132622D01*
G01X1117858Y-687590D02*
Y-676532D01*
G01Y-673517D02*
Y-663968D01*
G01Y-687590D02*
Y-676532D01*
G01Y-673517D02*
Y-663968D01*
G01X1120811D02*
Y-687590D01*
G01Y-663968D02*
Y-687590D01*
G01X1124748Y-679548D02*
Y-677538D01*
G01Y-673517D02*
Y-671507D01*
G01Y-679548D02*
Y-677538D01*
G01Y-673517D02*
Y-671507D01*
G01X1132622D02*
Y-673517D01*
G01Y-677538D02*
Y-679548D01*
G01Y-671507D02*
Y-673517D01*
G01Y-677538D02*
Y-679548D01*
G01X1120732Y-682078D02*
X1148413Y-654397D01*
G01X1165709Y-642708D02*
G03I-12598J0D01*
G01D02*
G03I-12598J0D01*
G01X1145417Y-666481D02*
X1142957Y-666983D01*
G01X1145417Y-666481D02*
X1142957Y-666983D01*
G01X1145417Y-663968D02*
X1142465Y-664470D01*
G01X1145417Y-663968D02*
X1142465Y-664470D01*
G01X1140004Y-665978D02*
X1138528Y-667486D01*
G01X1140004Y-665978D02*
X1138528Y-667486D01*
G01X1142957Y-666983D02*
X1141480Y-667988D01*
G01X1142957Y-666983D02*
X1141480Y-667988D01*
G01X1142465Y-664470D02*
X1140004Y-665978D01*
G01X1142465Y-664470D02*
X1140004Y-665978D01*
G01X1117858Y-663968D02*
X1120811D01*
G01X1117858D02*
X1120811D01*
G01X1165709Y-548219D02*
G03I-12598J0D01*
G01D02*
G03I-12598J0D01*
G01X1153111Y-444388D02*
X1125552D01*
G01D02*
X1303456D01*
G01X1131655Y-454751D02*
X1161681Y-455673D01*
G01X1140374Y-108399D02*
X1139887Y-109121D01*
X1138912Y-109843D01*
X1137938Y-109121D01*
X1136963Y-107678D01*
Y-106234D01*
X1137938Y-104790D01*
X1138912Y-104069D01*
X1139887Y-104790D01*
X1140374Y-106234D01*
X1136963D01*
G01X1109680Y-101181D02*
Y-109843D01*
G01X1115526Y-101181D02*
Y-101903D01*
G01Y-104069D02*
Y-109843D01*
G01X1123322D02*
Y-102625D01*
X1124296Y-101181D01*
X1124783D01*
X1125270Y-101903D01*
G01X1131117Y-101181D02*
Y-101903D01*
G01Y-104069D02*
Y-109843D01*
G01X1122347Y-104790D02*
X1124296D01*
G01X1134003Y-39467D02*
X1142670D01*
G01X1142337Y-39440D02*
X1134337D01*
G01X1147270Y-33775D02*
X1139072D01*
G01X1147256Y-33102D02*
X1139087D01*
G01Y-32967D02*
X1147256D01*
G01Y-31261D02*
X1139087D01*
G01Y-30829D02*
X1147256D01*
G01Y-30744D02*
X1139087D01*
G01X1137601Y-33775D02*
X1137595Y-33744D01*
X1137591Y-33713D01*
X1137588Y-33682D01*
G01Y-33663D02*
X1137591Y-33701D01*
X1137595Y-33738D01*
X1137601Y-33775D01*
G01X1137588Y-33682D02*
X1137587Y-33647D01*
G01Y-33621D02*
X1137588Y-33663D01*
G01X1135453Y-34319D02*
Y-32749D01*
G01X1136072D02*
Y-34319D01*
G01X1137588Y-33682D02*
Y-33663D01*
G01X1137587Y-17548D02*
Y-33647D01*
G01X1139087D02*
Y-17548D01*
G01X1139086Y-33663D02*
Y-33682D01*
G01X1140601Y-34319D02*
Y-32749D01*
G01X1141221D02*
Y-34319D01*
G01X1139086Y-33663D02*
X1139087Y-33621D01*
G01Y-33647D02*
X1139086Y-33682D01*
G01D02*
X1139083Y-33713D01*
X1139079Y-33744D01*
X1139072Y-33775D01*
G01D02*
X1139079Y-33738D01*
X1139083Y-33701D01*
X1139086Y-33663D01*
G01X1143337Y-40440D02*
G03X1142337Y-39440I-1000J0D01*
G01X1143337Y-40398D02*
G03X1142670Y-39467I-984J-1D01*
G01X1137601Y-33775D02*
G03X1138337Y-34378I734J145D01*
G01D02*
G03X1139072Y-33775I1J748D01*
G01X1138337Y-32016D02*
G03X1139087Y-31261I2J748D01*
G01X1137587D02*
G03X1138337Y-32016I748J-7D01*
G01X1131422Y-42635D02*
X1116183D01*
G01X1117183Y-42342D02*
X1116183D01*
G01X1116483Y-42135D02*
X1116583D01*
G01X1117183Y-41928D02*
X1116183D01*
G01X1143337Y-41835D02*
X1133337D01*
G01X1143422Y-41635D02*
X1133251D01*
G01X1116183D02*
X1117195D01*
G01X1143337Y-41461D02*
X1133337D01*
G01X1130822Y-41435D02*
X1115789D01*
G01X1133337Y-41403D02*
X1143337D01*
G01X1133337Y-41135D02*
X1143337D01*
G01Y-41107D02*
X1133337D01*
G01X1116183Y-40845D02*
X1115789D01*
G01X1117246Y-40746D02*
X1117183D01*
G01X1116183Y-40679D02*
X1115789D01*
G01X1116183Y-40670D02*
X1115792D01*
G01X1117283Y-40535D02*
X1117183D01*
G01X1115987Y-40442D02*
X1115789D01*
G01X1116183Y-40057D02*
X1115789D01*
G01X1117246Y-39762D02*
X1117183D01*
G01X1117283Y-39535D02*
X1117183D01*
G01X1123923Y-39469D02*
X1120089D01*
G01X1123726Y-39154D02*
X1120089D01*
G01X1119720Y-38336D02*
X1116183D01*
G01Y-34399D02*
X1119720D01*
G01X1133022Y-34319D02*
X1143652D01*
G01X1137601Y-33775D02*
X1129403D01*
G01X1127931D02*
X1119748D01*
G01X1123923Y-33249D02*
X1120089D01*
G01X1137587Y-33102D02*
X1129417D01*
G01X1127917D02*
X1119748D01*
G01Y-32967D02*
X1127917D01*
G01X1129417D02*
X1137587D01*
G01X1117183Y-32749D02*
X1159490D01*
G01X1119551Y-32016D02*
X1115789D01*
G01X1116183Y-31425D02*
X1115789D01*
G01X1137586Y-31261D02*
X1129418D01*
G01X1116183D02*
X1115790D01*
G01X1119748Y-30829D02*
X1127917D01*
G01X1129417D02*
X1137587D01*
G01Y-30744D02*
X1129417D01*
G01X1127917D02*
X1119748D01*
G01X1127917Y-31261D02*
X1119748Y-31255D01*
G01X1116183Y-40444D02*
X1115987Y-40442D01*
G01X1118183Y-29423D02*
X1116183D01*
G01X1117183Y-28812D02*
X1159490D01*
G01X1116183Y-28769D02*
X1117183D01*
G01Y-27769D02*
X1116183D01*
G01X1117183Y-27423D02*
X1118183D01*
G01X1116062Y-41435D02*
X1115922Y-41381D01*
X1115837Y-41220D01*
X1115801Y-40972D01*
X1115792Y-40670D01*
G01X1114175Y-23756D02*
X1115743Y-30829D01*
G01X1114559Y-23671D02*
X1116127Y-30744D01*
G01X1127931Y-33775D02*
X1127926Y-33744D01*
X1127921Y-33713D01*
X1127919Y-33682D01*
G01X1117183Y-42545D02*
X1117193Y-42596D01*
X1117223Y-42626D01*
X1117273Y-42635D01*
G01X1116183Y-42545D02*
X1116188Y-42595D01*
X1116202Y-42625D01*
X1116227Y-42635D01*
G01X1127919Y-33663D02*
X1127921Y-33701D01*
X1127926Y-33738D01*
X1127931Y-33775D01*
G01X1127919Y-33682D02*
X1127917Y-33647D01*
G01X1115792Y-40670D02*
X1115789Y-40442D01*
G01X1127917Y-33621D02*
X1127919Y-33663D01*
G01X1115789Y-31255D02*
Y-41435D01*
G01X1116183Y-42635D02*
Y106958D01*
G01X1117183Y-32749D02*
Y-42635D01*
G01Y-29423D02*
Y106958D01*
G01X1117246Y-41402D02*
Y-39762D01*
G01X1117283Y-39535D02*
Y-41435D01*
G01X1118152Y-32016D02*
Y-41435D01*
G01X1118183Y106958D02*
Y-32016D01*
G01Y-32749D02*
Y-42635D01*
G01X1119498Y-38879D02*
Y-33339D01*
G01X1119551Y-32016D02*
Y-33866D01*
G01X1119748Y-17548D02*
Y-33866D01*
G01X1120720Y-35399D02*
Y-37336D01*
G01X1124317Y-33339D02*
Y-38564D01*
G01X1124514Y-33839D02*
Y-38879D01*
G01X1127919Y-33682D02*
Y-33663D01*
G01X1127917Y-17548D02*
Y-33647D01*
G01X1129417D02*
Y-17548D01*
G01Y-33663D02*
Y-33682D01*
G01X1133022Y-34319D02*
Y-32749D01*
G01X1133337Y-40398D02*
Y-41832D01*
G01X1129417Y-33663D02*
Y-33621D01*
G01Y-33647D02*
Y-33682D01*
G01D02*
X1129414Y-33713D01*
X1129409Y-33744D01*
X1129403Y-33775D01*
G01D02*
X1129409Y-33738D01*
X1129414Y-33701D01*
X1129417Y-33663D01*
G01X1132544Y-41928D02*
X1132130Y-42342D01*
G01X1119720Y-38336D02*
G03X1120720Y-37336I0J1000D01*
G01X1115789Y-41402D02*
G03X1117246I728J0D01*
G01X1116583Y-42135D02*
G03X1117283Y-41435I0J700D01*
G01X1116181Y-42067D02*
G03X1116483Y-42135I301J632D01*
G01X1123923Y-39469D02*
G03X1124514Y-38879I0J591D01*
G01X1119498D02*
G03X1120089Y-39469I591J1D01*
G01X1119498Y-38564D02*
G03X1120089Y-39154I591J1D01*
G01X1123726D02*
G03X1124317Y-38564I1J590D01*
G01X1120720Y-35399D02*
G03X1119720Y-34399I-1000J0D01*
G01X1120089Y-32749D02*
G03X1119498Y-33339I0J-591D01*
G01X1120089Y-33249D02*
G03X1119498Y-33839I0J-591D01*
G01X1119551Y-33866D02*
G03X1119748I99J0D01*
G01X1116183Y-31261D02*
G03X1116127Y-30744I-2362J6D01*
G01X1115789Y-31261D02*
G03X1115743Y-30829I-1968J9D01*
G01X1118183Y-29423D02*
G03Y-27423I0J1000D01*
G01X1119157Y-32016D02*
G03X1119748Y-31425I0J591D01*
G01X1127931Y-33775D02*
G03X1128667Y-34378I734J145D01*
G01D02*
G03X1129403Y-33775I2J748D01*
G01X1124317Y-33339D02*
G03X1123726Y-32749I-590J0D01*
G01X1124317Y-33839D02*
G03X1123726Y-33249I-590J0D01*
G01X1124514Y-33839D02*
G03X1123923Y-33249I-591J-1D01*
G01X1128667Y-32016D02*
G03X1129417Y-31261I2J748D01*
G01X1127918D02*
G03X1128667Y-32016I748J-7D01*
G01X1133251Y-41635D02*
G03X1132544Y-41928I0J-1000D01*
G01X1131422Y-42635D02*
G03X1132130Y-42342I1J1000D01*
G01X1134337Y-39440D02*
G03X1133337Y-40440I0J-1000D01*
G01X1130822Y-41435D02*
G03X1131780Y-40679I0J984D01*
G01X1134003Y-39467D02*
G03X1133337Y-40398I318J-931D01*
G01Y-40845D02*
G03X1131780Y-40679I-787J0D01*
G01X1139874Y-16798D02*
X1139721Y-16813D01*
X1139574Y-16857D01*
X1139439Y-16929D01*
X1139317Y-17028D01*
X1139220Y-17146D01*
X1139147Y-17281D01*
X1139102Y-17427D01*
X1139087Y-17582D01*
G01X1139874Y-16904D02*
X1139721Y-16917D01*
X1139574Y-16954D01*
X1139439Y-17015D01*
X1139317Y-17099D01*
X1139220Y-17199D01*
X1139147Y-17313D01*
X1139102Y-17437D01*
X1139087Y-17568D01*
G01X1147256Y-18862D02*
X1139087D01*
G01Y-18845D02*
X1147256D01*
G01Y-18516D02*
X1139087D01*
G01Y-18481D02*
X1147256D01*
G01Y-18138D02*
X1139087D01*
G01Y-18104D02*
X1147256D01*
G01X1139087Y-17890D02*
X1147256D01*
G01Y-17679D02*
X1139087D01*
G01X1139874Y-17116D02*
X1146469D01*
G01Y-16904D02*
X1139874D01*
G01Y-16798D02*
X1146469D01*
G01Y-16764D02*
X1139874D01*
G01X1136799Y-17116D02*
X1136952Y-17128D01*
X1137100Y-17166D01*
X1137235Y-17227D01*
X1137356Y-17310D01*
X1137454Y-17410D01*
X1137526Y-17525D01*
X1137571Y-17649D01*
X1137587Y-17780D01*
G01X1136799Y-16764D02*
X1136952Y-16779D01*
X1137100Y-16823D01*
X1137235Y-16895D01*
X1137356Y-16994D01*
X1137454Y-17112D01*
X1137526Y-17247D01*
X1137571Y-17393D01*
X1137587Y-17548D01*
G01Y-17582D02*
X1137572Y-17430D01*
X1137528Y-17284D01*
X1137455Y-17149D01*
X1137356Y-17028D01*
X1137237Y-16931D01*
X1137102Y-16858D01*
X1136955Y-16814D01*
X1136799Y-16798D01*
G01X1137587Y-17568D02*
X1137572Y-17439D01*
X1137528Y-17315D01*
X1137455Y-17201D01*
X1137356Y-17099D01*
X1137237Y-17016D01*
X1137102Y-16955D01*
X1136955Y-16917D01*
X1136799Y-16904D01*
G01Y-16764D02*
Y-16798D01*
G01Y-17116D02*
Y-16904D01*
G01X1139874D02*
Y-17116D01*
G01Y-16798D02*
Y-16764D01*
G01X1139087Y-17548D02*
X1139102Y-17396D01*
X1139146Y-17249D01*
X1139219Y-17114D01*
X1139317Y-16994D01*
X1139436Y-16896D01*
X1139572Y-16824D01*
X1139719Y-16779D01*
X1139874Y-16764D01*
G01X1139087Y-17780D02*
X1139102Y-17651D01*
X1139146Y-17527D01*
X1139219Y-17412D01*
X1139317Y-17310D01*
X1139436Y-17228D01*
X1139572Y-17167D01*
X1139719Y-17129D01*
X1139874Y-17116D01*
G01X1139087Y-24077D02*
X1147256D01*
G01Y-23942D02*
X1139087D01*
G01X1147256Y-23756D02*
X1139087D01*
G01Y-23671D02*
X1147256D01*
G01X1139087Y-23348D02*
X1147256D01*
G01Y-23331D02*
X1139087D01*
G01Y-23097D02*
X1147256D01*
G01Y-23063D02*
X1139087D01*
G01X1118807Y-958D02*
X1118755Y-972D01*
G01X1118624Y-717D02*
X1118676Y-704D01*
G01X1118755Y-1039D02*
X1118820Y-1025D01*
G01X1118676Y-637D02*
X1118611Y-650D01*
G01X1116773Y-744D02*
X1116708Y-757D01*
G01X1130205Y-16798D02*
X1130052Y-16813D01*
X1129905Y-16857D01*
X1129769Y-16929D01*
X1129648Y-17028D01*
X1129550Y-17146D01*
X1129478Y-17281D01*
X1129433Y-17427D01*
X1129417Y-17582D01*
G01X1120535Y-16798D02*
X1120383Y-16813D01*
X1120235Y-16857D01*
X1120100Y-16929D01*
X1119979Y-17028D01*
X1119881Y-17146D01*
X1119809Y-17281D01*
X1119764Y-17427D01*
X1119748Y-17582D01*
G01X1130205Y-16904D02*
X1130052Y-16917D01*
X1129905Y-16954D01*
X1129769Y-17015D01*
X1129648Y-17099D01*
X1129550Y-17199D01*
X1129478Y-17313D01*
X1129433Y-17437D01*
X1129417Y-17568D01*
G01X1120535Y-16904D02*
X1120383Y-16917D01*
X1120235Y-16954D01*
X1120100Y-17015D01*
X1119979Y-17099D01*
X1119881Y-17199D01*
X1119809Y-17313D01*
X1119764Y-17437D01*
X1119748Y-17568D01*
G01X1289411Y-21761D02*
X1117183D01*
G01X1116183Y-21261D02*
X1120120D01*
G01X1137587Y-18862D02*
X1129417D01*
G01X1127917D02*
X1119748D01*
G01Y-18845D02*
X1127917D01*
G01X1129417D02*
X1137587D01*
G01X1127917Y-18516D02*
X1119748D01*
G01X1137587D02*
X1129417D01*
G01X1119748Y-18481D02*
X1127917D01*
G01X1129417D02*
X1137587D01*
G01Y-18138D02*
X1129417D01*
G01X1127917D02*
X1119748D01*
G01Y-18104D02*
X1127917D01*
G01X1129417D02*
X1137587D01*
G01X1119748Y-17890D02*
X1127917D01*
G01X1129417D02*
X1137587D01*
G01Y-17679D02*
X1129417D01*
G01X1127917D02*
X1119748D01*
G01X1129787Y-17318D02*
X1124866D01*
G01X1120535Y-17116D02*
X1127130D01*
G01X1130205D02*
X1136799D01*
G01Y-16904D02*
X1130205D01*
G01X1127130D02*
X1120535D01*
G01Y-16798D02*
X1127130D01*
G01X1130205D02*
X1136799D01*
G01Y-16764D02*
X1130205D01*
G01X1127130D02*
X1120535D01*
G01X1129787Y-14786D02*
X1124866D01*
G01Y-14307D02*
X1129787D01*
G01X1116183Y-13551D02*
X1120120D01*
G01X1114923Y-12551D02*
X1118183D01*
G01X1117183Y-11551D02*
X1116317D01*
G01X1114923Y-11383D02*
X1116183D01*
G01X1129787Y-9699D02*
X1124866D01*
G01Y-9220D02*
X1129787D01*
G01X1121695Y-8460D02*
X1116451D01*
G01X1124866Y-6688D02*
X1129787D01*
G01X1116451Y-4525D02*
X1121695D01*
G01X1117183Y-2525D02*
X1116183D01*
G01Y-2040D02*
X1114923D01*
G01X1116183Y-1874D02*
X1117183D01*
G01X1116183Y-1777D02*
X1117183D01*
G01X1129787Y-1570D02*
X1124866D01*
G01X1116183Y-1273D02*
X1117183D01*
G01X1116183Y-1244D02*
X1117183D01*
G01X1114923Y-1208D02*
X1116183D01*
G01X1118112Y-1039D02*
X1118033D01*
G01X1117666D02*
X1117587D01*
G01X1118374D02*
X1118296D01*
G01X1116472D02*
X1116393D01*
G01X1117272D02*
X1117193D01*
G01X1118676D02*
X1118755D01*
G01Y-972D02*
X1118676D01*
G01X1118558Y-878D02*
X1118480D01*
G01X1117183Y-832D02*
X1116183D01*
G01X1116708Y-757D02*
X1116472D01*
G01X1118480D02*
X1118571D01*
G01X1118033Y-744D02*
X1117666D01*
G01X1118676Y-704D02*
X1118755D01*
G01X1116472Y-677D02*
X1116721D01*
G01X1117666Y-664D02*
X1118033D01*
G01X1118755Y-637D02*
X1118676D01*
G01X1116721Y-476D02*
X1116472D01*
G01X1117193D02*
X1116983D01*
G01X1117482D02*
X1117272D01*
G01X1118545D02*
X1118926D01*
G01Y-409D02*
X1118480D01*
G01X1116393D02*
X1116708D01*
G01X1116983D02*
X1117482D01*
G01X1118033D02*
X1118112D01*
G01X1117587D02*
X1117666D01*
G01X1118296D02*
X1118374D01*
G01X1116183Y153D02*
X1117183D01*
G01X1116183Y560D02*
X1117183D01*
G01X1116183Y590D02*
X1117183D01*
G01X1129787Y962D02*
X1124866D01*
G01X1116183Y1097D02*
X1117183D01*
G01Y1190D02*
X1116183D01*
G01X1124866Y1441D02*
X1129787D01*
G01X1117183Y1845D02*
X1116183D01*
G01X1117183Y3845D02*
X1116183D01*
G01X1117183Y4436D02*
X1116183D01*
G01X1129787Y6049D02*
X1124866D01*
G01X1127130Y-17116D02*
X1127283Y-17128D01*
X1127430Y-17166D01*
X1127566Y-17227D01*
X1127687Y-17310D01*
X1127784Y-17410D01*
X1127857Y-17525D01*
X1127902Y-17649D01*
X1127917Y-17780D01*
G01X1127130Y-16764D02*
X1127283Y-16779D01*
X1127430Y-16823D01*
X1127566Y-16895D01*
X1127687Y-16994D01*
X1127784Y-17112D01*
X1127857Y-17247D01*
X1127902Y-17393D01*
X1127917Y-17548D01*
G01X1118611Y-1025D02*
X1118676Y-1039D01*
G01X1116708Y-409D02*
X1116773Y-422D01*
G01X1118820Y-650D02*
X1118755Y-637D01*
G01X1118676Y-972D02*
X1118624Y-958D01*
G01X1118755Y-704D02*
X1118807Y-717D01*
G01X1116760Y-490D02*
X1116721Y-476D01*
G01X1118545Y-985D02*
X1118611Y-1025D01*
G01X1118886Y-690D02*
X1118820Y-650D01*
G01X1118624Y-958D02*
X1118584Y-932D01*
G01X1118807Y-717D02*
X1118847Y-744D01*
G01X1116773Y-422D02*
X1116826Y-462D01*
G01X1116787Y-516D02*
X1116760Y-490D01*
G01X1116826Y-462D02*
X1116865Y-516D01*
G01X1118506Y-932D02*
X1118545Y-985D01*
G01X1118926Y-744D02*
X1118886Y-690D01*
G01X1118847Y-744D02*
X1118873Y-784D01*
G01X1113125Y-17116D02*
X1113619Y-17890D01*
G01X1113457Y-16904D02*
X1113951Y-17679D01*
G01X1118480Y-878D02*
X1118506Y-932D01*
G01X1118584D02*
X1118558Y-878D01*
G01X1118952Y-811D02*
X1118926Y-744D01*
G01X1116800Y-557D02*
X1116787Y-516D01*
G01X1116865D02*
X1116878Y-557D01*
G01X1118873Y-784D02*
X1118886Y-825D01*
G01X1127917Y-17582D02*
X1127902Y-17430D01*
X1127858Y-17284D01*
X1127786Y-17149D01*
X1127687Y-17028D01*
X1127568Y-16931D01*
X1127433Y-16858D01*
X1127286Y-16814D01*
X1127130Y-16798D01*
G01X1127917Y-17568D02*
X1127902Y-17439D01*
X1127858Y-17315D01*
X1127786Y-17201D01*
X1127687Y-17099D01*
X1127568Y-17016D01*
X1127433Y-16955D01*
X1127286Y-16917D01*
X1127130Y-16904D01*
G01X1114923Y35593D02*
Y-12551D01*
G01X1116317Y-11551D02*
Y-12551D01*
G01X1116393Y-1039D02*
Y-409D01*
G01X1116451Y-4525D02*
Y-8460D01*
G01X1116472Y-757D02*
Y-1039D01*
G01Y-476D02*
Y-677D01*
G01X1116800Y-597D02*
Y-557D01*
G01X1116878D02*
Y-610D01*
G01X1116983Y-476D02*
Y-409D01*
G01X1117193Y-1039D02*
Y-476D01*
G01X1117272D02*
Y-1039D01*
G01X1117482Y-409D02*
Y-476D01*
G01X1117587Y-1039D02*
Y-409D01*
G01X1117666Y-744D02*
Y-1039D01*
G01Y-409D02*
Y-664D01*
G01X1118033Y-1039D02*
Y-744D01*
G01Y-664D02*
Y-409D01*
G01X1118112D02*
Y-1039D01*
G01X1118217Y-610D02*
Y-503D01*
G01X1118296Y-1039D02*
Y-516D01*
G01X1118374Y-409D02*
Y-1039D01*
G01X1118480Y-409D02*
Y-757D01*
G01X1118545Y-690D02*
Y-476D01*
G01X1118886Y-825D02*
Y-851D01*
G01X1118926Y-476D02*
Y-409D01*
G01X1118952Y-865D02*
Y-811D01*
G01X1120535Y-16904D02*
Y-17116D01*
G01Y-16798D02*
Y-16764D01*
G01X1121120Y-14551D02*
Y-20261D01*
G01X1122695Y-5525D02*
Y-7460D01*
G01X1124866Y9060D02*
Y-1570D01*
G01Y-6688D02*
Y-17318D01*
G01X1127130Y-16764D02*
Y-16798D01*
G01Y-17116D02*
Y-16904D01*
G01X1129787Y-17318D02*
Y-6688D01*
G01Y-1570D02*
Y9060D01*
G01X1130205Y-16904D02*
Y-17116D01*
G01Y-16798D02*
Y-16764D01*
G01X1119748Y-17548D02*
X1119763Y-17396D01*
X1119807Y-17249D01*
X1119880Y-17114D01*
X1119979Y-16994D01*
X1120098Y-16896D01*
X1120233Y-16824D01*
X1120380Y-16779D01*
X1120535Y-16764D01*
G01X1129417Y-17548D02*
X1129433Y-17396D01*
X1129477Y-17249D01*
X1129549Y-17114D01*
X1129648Y-16994D01*
X1129767Y-16896D01*
X1129902Y-16824D01*
X1130049Y-16779D01*
X1130205Y-16764D01*
G01X1119748Y-17780D02*
X1119763Y-17651D01*
X1119807Y-17527D01*
X1119880Y-17412D01*
X1119979Y-17310D01*
X1120098Y-17228D01*
X1120233Y-17167D01*
X1120380Y-17129D01*
X1120535Y-17116D01*
G01X1129417Y-17780D02*
X1129433Y-17651D01*
X1129477Y-17527D01*
X1129549Y-17412D01*
X1129648Y-17310D01*
X1129767Y-17228D01*
X1129902Y-17167D01*
X1130049Y-17129D01*
X1130205Y-17116D01*
G01X1116787Y-637D02*
X1116800Y-597D01*
G01X1116878Y-610D02*
X1116865Y-650D01*
G01X1118886Y-851D02*
X1118873Y-892D01*
G01X1118926Y-932D02*
X1118952Y-865D01*
G01X1118873Y-892D02*
X1118847Y-932D01*
G01X1118611Y-650D02*
X1118545Y-690D01*
G01X1118820Y-1025D02*
X1118886Y-985D01*
G01X1116721Y-677D02*
X1116760Y-664D01*
G01X1116865Y-650D02*
X1116826Y-704D01*
G01X1118886Y-985D02*
X1118926Y-932D01*
G01X1118217Y-503D02*
X1118296Y-409D01*
G01Y-516D02*
X1118217Y-610D01*
G01X1116760Y-664D02*
X1116787Y-637D01*
G01X1116826Y-704D02*
X1116773Y-744D01*
G01X1118571Y-757D02*
X1118624Y-717D01*
G01X1118847Y-932D02*
X1118807Y-958D01*
G01X1113457Y-16904D02*
X1113125Y-17116D01*
G01X1113880Y-17568D02*
X1113548Y-17780D01*
G01X1114319Y-18845D02*
G03X1113951Y-17679I-2360J-104D01*
G01X1113925Y-18862D02*
G03X1113619Y-17890I-1967J-85D01*
G01X1120120Y-21261D02*
G03X1121120Y-20261I0J1000D01*
G01X1118183Y-14551D02*
G03X1117183Y-15551I0J-1000D01*
G01X1121120Y-14551D02*
G03X1120120Y-13551I-1000J0D01*
G01X1118183Y-14551D02*
G03Y-12551I0J1000D01*
G01X1121695Y-8460D02*
G03X1122695Y-7460I0J1000D01*
G01Y-5525D02*
G03X1121695Y-4525I-1000J0D01*
G01X1117183Y-24510D02*
X1289411D01*
G01X1116183Y-24261D02*
X1117183D01*
G01X1119748Y-24077D02*
X1127917D01*
G01X1129417D02*
X1137587D01*
G01Y-23942D02*
X1129417D01*
G01X1127917D02*
X1119748D01*
G01X1289411Y-23803D02*
X1117183D01*
G01X1137587Y-23756D02*
X1129417D01*
G01X1127917D02*
X1119748D01*
G01Y-23671D02*
X1127917D01*
G01X1129417D02*
X1137587D01*
G01X1119748Y-23348D02*
X1127917D01*
G01X1129417D02*
X1137587D01*
G01Y-23331D02*
X1129417D01*
G01X1127917D02*
X1119748D01*
G01X1116183Y-23261D02*
X1117183D01*
G01Y-23175D02*
X1289411D01*
G01X1119748Y-23097D02*
X1127917D01*
G01X1129417D02*
X1137587D01*
G01X1117183Y-23095D02*
X1159490D01*
G01X1137587Y-23063D02*
X1129417D01*
G01X1127917D02*
X1119748D01*
G01X1159490Y-22468D02*
X1117183D01*
G01X1113925Y-18862D02*
X1114121Y-23348D01*
G01X1114319Y-18845D02*
X1114515Y-23331D01*
G01X1114121Y-23348D02*
G03X1114175Y-23756I2360J105D01*
G01X1114515Y-23331D02*
G03X1114559Y-23671I1967J82D01*
G01X1139781Y12877D02*
X1141781D01*
G01X1139781Y14058D02*
X1140781D01*
G01X1135010Y18393D02*
X1135710D01*
G01X1137963D02*
X1138663D01*
G01X1140915D02*
X1141615D01*
G01X1140781Y18585D02*
X1139781D01*
G01X1141781Y19766D02*
X1139781D01*
G01X1141615Y21371D02*
X1140915D01*
G01X1138663D02*
X1137963D01*
G01X1135710D02*
X1135010D01*
G01X1141615Y24336D02*
X1140915D01*
G01X1138663D02*
X1137963D01*
G01X1135710D02*
X1135010D01*
G01X1141615Y24561D02*
X1140915D01*
G01X1138663D02*
X1137963D01*
G01X1135710D02*
X1135010D01*
G01X1141992Y27251D02*
X1139039D01*
G01X1138039D02*
X1134681D01*
G01X1141992Y28251D02*
X1139039D01*
G01X1138039D02*
X1134681D01*
G01X1141992Y29251D02*
X1139039D01*
G01X1138039D02*
X1134681D01*
G01X1141992Y29501D02*
X1139039D01*
G01X1138039D02*
X1134681D01*
G01X1141598Y29645D02*
X1135075D01*
G01X1139630Y31367D02*
X1141402D01*
G01X1137449Y32851D02*
X1135272D01*
G01X1136958Y34687D02*
X1137788Y34292D01*
X1138720Y34145D01*
X1139650Y34260D01*
X1140536Y34632D01*
X1141315Y35247D01*
X1141911Y36062D01*
X1142291Y37073D01*
G01X1136958Y34686D02*
X1137769Y34298D01*
X1138691Y34147D01*
X1139623Y34252D01*
X1140518Y34621D01*
X1141306Y35238D01*
X1141908Y36057D01*
X1142291Y37073D01*
G01X1141875Y39341D02*
X1141181Y40133D01*
X1140343Y40686D01*
X1139391Y40994D01*
X1138414Y41031D01*
X1137490Y40806D01*
X1136669Y40333D01*
X1136041Y39674D01*
G01X1141874Y39341D02*
X1141217Y40265D01*
X1140319Y40969D01*
X1139219Y41398D01*
X1138061Y41489D01*
X1136923Y41238D01*
X1135921Y40682D01*
X1135111Y39846D01*
X1134576Y38822D01*
X1134361Y37666D01*
X1134489Y36502D01*
X1134938Y35448D01*
X1135691Y34547D01*
X1136683Y33899D01*
X1137822Y33574D01*
X1138987Y33592D01*
X1140097Y33950D01*
X1141056Y34614D01*
X1141793Y35547D01*
X1142223Y36666D01*
X1142301Y37866D01*
X1142004Y39065D01*
X1141396Y40063D01*
X1140539Y40833D01*
X1139446Y41340D01*
X1138281Y41497D01*
X1137139Y41313D01*
X1136071Y40790D01*
X1135229Y40005D01*
X1134646Y39005D01*
X1134372Y37852D01*
X1134440Y36714D01*
X1134833Y35630D01*
X1135530Y34697D01*
X1136481Y33999D01*
X1137581Y33612D01*
X1138733Y33560D01*
X1139849Y33837D01*
X1140790Y34385D01*
X1141567Y35195D01*
X1142105Y36241D01*
X1142313Y37379D01*
X1142180Y38551D01*
X1141725Y39606D01*
X1140971Y40501D01*
X1139993Y41136D01*
X1138847Y41464D01*
X1137719Y41451D01*
X1136606Y41101D01*
X1135654Y40458D01*
X1134906Y39533D01*
X1134453Y38387D01*
X1134371Y37197D01*
X1134626Y36081D01*
X1135193Y35079D01*
X1136033Y34274D01*
X1137094Y33738D01*
X1138268Y33540D01*
X1139463Y33702D01*
X1140515Y34188D01*
X1141386Y34961D01*
X1141996Y35956D01*
X1142292Y37089D01*
X1142249Y38249D01*
X1141874Y39341D01*
G01D02*
X1142199Y38627D01*
X1142341Y37855D01*
X1142291Y37073D01*
G01X1142293Y38246D02*
X1141911Y39363D01*
X1141222Y40321D01*
X1140282Y41039D01*
X1139176Y41452D01*
X1137998Y41526D01*
X1136842Y41253D01*
X1135830Y40664D01*
X1135019Y39792D01*
X1134502Y38731D01*
X1134315Y37567D01*
X1134476Y36392D01*
X1134964Y35327D01*
X1135756Y34434D01*
X1136763Y33817D01*
X1137902Y33520D01*
X1139083Y33566D01*
X1140197Y33953D01*
X1141157Y34651D01*
X1141870Y35597D01*
X1142275Y36703D01*
X1142343Y37880D01*
X1142064Y39030D01*
X1141464Y40048D01*
X1140590Y40850D01*
X1139526Y41361D01*
X1138360Y41540D01*
X1137190Y41373D01*
X1136122Y40876D01*
X1135238Y40083D01*
X1134627Y39072D01*
X1134336Y37928D01*
X1134389Y36749D01*
X1134782Y35636D01*
X1135482Y34685D01*
X1136429Y33978D01*
X1137539Y33577D01*
X1138719Y33515D01*
X1139866Y33799D01*
X1140879Y34402D01*
X1141674Y35274D01*
X1142182Y36340D01*
X1142359Y37508D01*
X1142189Y38676D01*
X1141686Y39745D01*
X1140901Y40618D01*
X1139891Y41228D01*
X1138746Y41519D01*
X1137567Y41466D01*
X1136450Y41070D01*
X1135511Y40380D01*
X1134803Y39439D01*
X1134398Y38330D01*
X1134331Y37152D01*
X1134613Y35999D01*
X1135204Y34995D01*
X1136069Y34197D01*
X1137131Y33682D01*
X1138296Y33497D01*
X1139465Y33658D01*
X1140534Y34150D01*
X1141411Y34925D01*
X1142032Y35930D01*
X1142334Y37069D01*
X1142293Y38246D01*
G01X1142199Y38627D02*
X1142341Y37855D01*
X1142291Y37073D01*
G01D02*
X1142249Y38248D01*
X1141855Y39377D01*
X1141172Y40312D01*
X1140235Y41015D01*
X1139097Y41425D01*
X1137896Y41473D01*
X1136717Y41153D01*
X1135755Y40547D01*
X1135010Y39701D01*
X1134521Y38649D01*
X1134359Y37437D01*
X1134574Y36222D01*
X1135093Y35212D01*
X1135898Y34375D01*
X1136896Y33809D01*
X1138010Y33553D01*
X1139229Y33640D01*
X1140335Y34077D01*
X1141220Y34776D01*
X1141877Y35701D01*
X1142250Y36795D01*
X1142293Y37942D01*
X1141989Y39097D01*
X1141388Y40073D01*
X1140515Y40847D01*
X1139497Y41325D01*
X1138352Y41498D01*
X1137136Y41312D01*
X1136109Y40818D01*
X1135268Y40051D01*
X1134657Y39033D01*
X1134376Y37904D01*
X1134433Y36751D01*
X1134838Y35620D01*
X1135533Y34695D01*
X1136432Y34025D01*
X1137520Y33624D01*
X1138729Y33559D01*
X1139859Y33842D01*
X1140836Y34422D01*
X1141635Y35293D01*
X1142126Y36305D01*
X1142316Y37526D01*
X1142126Y38734D01*
X1141637Y39744D01*
X1140869Y40588D01*
X1139894Y41180D01*
X1138764Y41475D01*
X1137559Y41421D01*
X1136453Y41025D01*
X1135555Y40364D01*
X1134853Y39441D01*
X1134457Y38402D01*
X1134368Y37241D01*
X1134647Y36025D01*
X1135232Y35030D01*
X1136087Y34237D01*
X1137157Y33718D01*
X1138307Y33540D01*
X1139457Y33700D01*
X1140526Y34195D01*
X1141376Y34949D01*
X1141999Y35962D01*
X1142291Y37073D01*
G01X1133681Y31038D02*
Y26751D01*
G01X1134681Y32261D02*
Y26751D01*
G01X1135010Y24561D02*
Y18393D01*
G01X1135710Y24561D02*
Y18393D01*
G01X1137963Y24561D02*
Y18393D01*
G01X1138039Y32261D02*
Y26751D01*
G01X1138663Y24561D02*
Y18393D01*
G01X1139039Y30777D02*
Y26751D01*
G01X1139781Y19766D02*
Y12877D01*
G01X1140781D02*
Y19766D01*
G01X1140915Y24561D02*
Y18393D01*
G01X1141615Y24561D02*
Y18393D01*
G01X1141781Y19766D02*
Y12877D01*
G01X1141992Y30777D02*
Y26751D01*
G01X1142992Y31038D02*
Y26751D01*
G01X1143180Y43339D02*
Y39178D01*
G01X1136668Y40332D02*
X1137481Y40802D01*
X1138391Y41029D01*
X1139354Y41001D01*
X1140306Y40703D01*
X1141159Y40152D01*
X1141874Y39341D01*
G01X1146211Y34257D02*
X1141598Y29645D01*
G01X1141992Y30777D02*
G03X1141402Y31367I-591J-1D01*
G01X1139630D02*
G03X1139039Y30777I0J-591D01*
G01X1141992Y26751D02*
G03X1142992I500J0D01*
G01X1138039D02*
G03X1139039I500J0D01*
G01X1133681D02*
G03X1134681I500J0D01*
G01X1142667Y37519D02*
G03I-4330J0D01*
G01X1141486D02*
G03I-3149J0D01*
G01X1135272Y32851D02*
G03X1134681Y32261I0J-591D01*
G01X1138039D02*
G03X1137449Y32851I-590J0D01*
G01X1143180Y39178D02*
G03X1143770Y38588I590J0D01*
G01X1128802D02*
X1128521Y38547D01*
X1128288Y38441D01*
X1128126Y38279D01*
X1128069Y38088D01*
G01X1155931Y12019D02*
X1120695D01*
G01X1114805Y14915D02*
X1116183D01*
G01X1153766Y14955D02*
X1122860D01*
G01X1116183Y17868D02*
X1114805D01*
G01X1121695Y18242D02*
X1116451D01*
G01X1126152Y18393D02*
X1126852D01*
G01X1129105D02*
X1129805D01*
G01X1132057D02*
X1132757D01*
G01Y21371D02*
X1132057D01*
G01X1129805D02*
X1129105D01*
G01X1126852D02*
X1126152D01*
G01X1132757Y24336D02*
X1132057D01*
G01X1129805D02*
X1129105D01*
G01X1126852D02*
X1126152D01*
G01X1132757Y24561D02*
X1132057D01*
G01X1129805D02*
X1129105D01*
G01X1126852D02*
X1126152D01*
G01X1116317Y26116D02*
X1121695D01*
G01X1117183Y27116D02*
X1116317D01*
G01X1116183Y33593D02*
X1114923D01*
G01X1122860Y34353D02*
X1153766D01*
G01X1116317Y34908D02*
X1117183D01*
G01X1153766Y35141D02*
X1122860D01*
G01X1155931Y35267D02*
X1120695D01*
G01X1116923Y35593D02*
X1114923D01*
G01X1146524Y35857D02*
X1130101D01*
G01X1117183Y35908D02*
X1116183D01*
G01X1131147Y36767D02*
X1120695D01*
G01X1117183Y36908D02*
X1116183D01*
G01X1130463Y37588D02*
X1128569D01*
G01X1128435Y38588D02*
X1132904D01*
G01X1132211Y39032D02*
X1132183D01*
G01X1114805Y12946D02*
X1116183Y12151D01*
G01X1135075Y29645D02*
X1130463Y34257D01*
G01X1114805Y19836D02*
Y12946D01*
G01X1116317Y35593D02*
Y26116D01*
G01X1116451D02*
Y18242D01*
G01X1122695Y25116D02*
Y19242D01*
G01X1122860Y35141D02*
Y14955D01*
G01X1126152Y24561D02*
Y18393D01*
G01X1126852Y24561D02*
Y18393D01*
G01X1128069Y43930D02*
Y38088D01*
G01X1128100Y44408D02*
Y36767D01*
G01X1129069Y43930D02*
Y38588D01*
G01X1129105Y24561D02*
Y18393D01*
G01X1129805Y24561D02*
Y18393D01*
G01X1130069Y44408D02*
Y38588D01*
G01X1130319Y43930D02*
Y38588D01*
G01X1130463Y34257D02*
Y40780D01*
G01X1131344Y44408D02*
Y36569D01*
G01X1131485Y44408D02*
Y37242D01*
G01X1132057Y24561D02*
Y18393D01*
G01X1132183Y37940D02*
Y44408D01*
G01X1132211Y38069D02*
Y44408D01*
G01X1132757Y24561D02*
Y18393D01*
G01X1133494Y43339D02*
Y39178D01*
G01X1128069Y38088D02*
X1128100Y38288D01*
X1128183Y38447D01*
X1128303Y38552D01*
X1128435Y38588D01*
G01X1131147Y36767D02*
X1130281Y35267D01*
G01X1131344Y36569D02*
X1132211Y38069D01*
G01X1131147Y36767D02*
X1132211Y38069D01*
G01X1130281Y35267D02*
X1131344Y36569D01*
G01X1135163Y41985D02*
X1132211Y39032D01*
G01X1132183Y37940D02*
X1130101Y35857D01*
G01X1116183Y20632D02*
X1114805Y19836D01*
G01X1121695Y18242D02*
G03X1122695Y19242I0J1000D01*
G01Y25116D02*
G03X1121695Y26116I-1000J0D01*
G01X1116923Y35593D02*
G03X1117183Y38570I0J1500D01*
G01X1128069Y38088D02*
G03X1128569Y37588I500J0D01*
G01X1132904Y38588D02*
G03X1133494Y39178I0J590D01*
G01X1124866Y6528D02*
X1129787D01*
G01X1116183Y6877D02*
X1117183D01*
G01Y7468D02*
X1116183D01*
G01X1124866Y9060D02*
X1129787D01*
G01X1120695Y11019D02*
X1155931D01*
G01X1120695Y44408D02*
Y11019D01*
G01X1122860Y14955D02*
X1121679Y11019D01*
G01X1122860Y14955D02*
X1121679Y11019D01*
G01X1135075Y45393D02*
X1141598D01*
G01X1137963Y48355D02*
X1138663D01*
G01Y48571D02*
X1137963D01*
G01X1138663Y48667D02*
X1137963D01*
G01X1138663Y48729D02*
X1137963D01*
G01X1138663Y48827D02*
X1137963D01*
G01X1138663Y49812D02*
X1137963D01*
G01X1138663Y49910D02*
X1137963D01*
G01X1138663Y49973D02*
X1137963D01*
G01X1138663Y50068D02*
X1137963D01*
G01Y50284D02*
X1138663D01*
G01X1140915Y51111D02*
X1141615D01*
G01Y51327D02*
X1140915D01*
G01X1141615Y51423D02*
X1140915D01*
G01X1141615Y51485D02*
X1140915D01*
G01X1141615Y51583D02*
X1140915D01*
G01X1141616Y52568D02*
X1140916D01*
G01X1141615Y52666D02*
X1140915D01*
G01X1141615Y52729D02*
X1140915D01*
G01X1141615Y52823D02*
X1140915D01*
G01Y53040D02*
X1141615D01*
G01X1135710Y53867D02*
X1135010D01*
G01Y54083D02*
X1135710D01*
G01X1135010Y54179D02*
X1135710D01*
G01X1135010Y54241D02*
X1135710D01*
G01Y54339D02*
X1135010D01*
G01X1135710Y55323D02*
X1135010D01*
G01X1135710Y55422D02*
X1135010D01*
G01Y55484D02*
X1135710D01*
G01X1135010Y55579D02*
X1135710D01*
G01Y55796D02*
X1135010D01*
G01X1137963Y63316D02*
X1138663D01*
G01Y63532D02*
X1137963D01*
G01X1138663Y63627D02*
X1137963D01*
G01X1138663Y63690D02*
X1137963D01*
G01X1138663Y63788D02*
X1137963D01*
G01X1138663Y64772D02*
X1137963D01*
G01X1138663Y64871D02*
X1137963D01*
G01X1138663Y64933D02*
X1137963D01*
G01X1138663Y65028D02*
X1137963D01*
G01Y65245D02*
X1138663D01*
G01X1140915Y66071D02*
X1141615D01*
G01Y66288D02*
X1140915D01*
G01X1141615Y66383D02*
X1140915D01*
G01X1141615Y66445D02*
X1140915D01*
G01X1141615Y66544D02*
X1140915D01*
G01X1141616Y67528D02*
X1140916D01*
G01X1141615Y67627D02*
X1140915D01*
G01X1141615Y67689D02*
X1140915D01*
G01X1141615Y67784D02*
X1140915D01*
G01Y68001D02*
X1141615D01*
G01X1135710Y68827D02*
X1135010D01*
G01Y69044D02*
X1135710D01*
G01X1135010Y69139D02*
X1135710D01*
G01X1135010Y69201D02*
X1135710D01*
G01Y69300D02*
X1135010D01*
G01X1135710Y70284D02*
X1135010D01*
G01X1135710Y70382D02*
X1135010D01*
G01Y70445D02*
X1135710D01*
G01Y70540D02*
X1135010D01*
G01X1135710Y70756D02*
X1135010D01*
G01Y53868D02*
Y55794D01*
G01Y68829D02*
Y70755D01*
G01X1135710Y53869D02*
Y55795D01*
G01Y68829D02*
Y70755D01*
G01X1137963Y48356D02*
Y50282D01*
G01Y63317D02*
Y65243D01*
G01X1138663Y48357D02*
Y50283D01*
G01Y63318D02*
Y65243D01*
G01X1140915Y51112D02*
Y53038D01*
G01Y66073D02*
Y67999D01*
G01X1141615Y51113D02*
Y53039D01*
G01Y66073D02*
Y67999D01*
G01X1141463Y41985D02*
X1135163D01*
G01X1144415Y39032D02*
X1141463Y41985D01*
G01X1146211Y40780D02*
X1141598Y45393D01*
G01X1143770Y43930D02*
G03X1143180Y43339I0J-590D01*
G01X1116734Y52073D02*
X1116669Y52059D01*
G01X1117263Y56275D02*
X1117219Y56266D01*
X1117192Y56240D01*
X1117183Y56195D01*
G01X1143234Y45528D02*
X1133392D01*
G01X1143234Y46512D02*
X1133392D01*
G01X1129105Y48355D02*
X1129805D01*
G01Y48571D02*
X1129105D01*
G01X1129805Y48667D02*
X1129105D01*
G01X1129805Y48729D02*
X1129105D01*
G01X1129805Y48827D02*
X1129105D01*
G01X1129805Y49812D02*
X1129105D01*
G01X1129805Y49910D02*
X1129105D01*
G01X1129805Y49973D02*
X1129105D01*
G01X1129805Y50068D02*
X1129105D01*
G01Y50284D02*
X1129805D01*
G01X1116183Y50541D02*
X1117183D01*
G01X1116183Y50638D02*
X1117183D01*
G01X1132057Y51111D02*
X1132757D01*
G01X1116183Y51142D02*
X1117183D01*
G01X1116183Y51171D02*
X1117183D01*
G01X1132757Y51327D02*
X1132057D01*
G01X1132757Y51423D02*
X1132057D01*
G01X1132757Y51485D02*
X1132057D01*
G01X1132757Y51583D02*
X1132057D01*
G01X1117183D02*
X1116183D01*
G01X1118073Y51778D02*
X1117994D01*
G01X1117627D02*
X1117548D01*
G01X1118335D02*
X1118257D01*
G01X1116433D02*
X1116354D01*
G01X1117233D02*
X1117154D01*
G01X1116669Y52059D02*
X1116433D01*
G01X1117994Y52073D02*
X1117627D01*
G01X1116433Y52140D02*
X1116682D01*
G01X1117627Y52153D02*
X1117994D01*
G01X1116682Y52341D02*
X1116433D01*
G01X1117154D02*
X1116944D01*
G01X1117443D02*
X1117233D01*
G01X1116354Y52408D02*
X1116669D01*
G01X1116944D02*
X1117443D01*
G01X1117994D02*
X1118073D01*
G01X1117548D02*
X1117627D01*
G01X1118257D02*
X1118335D01*
G01X1132757Y52568D02*
X1132057D01*
G01X1116183D02*
X1117183D01*
G01X1132757Y52666D02*
X1132057D01*
G01X1132757Y52729D02*
X1132057D01*
G01X1132757Y52823D02*
X1132057D01*
G01X1116183Y52975D02*
X1117183D01*
G01X1116183Y53005D02*
X1117183D01*
G01X1132057Y53040D02*
X1132757D01*
G01X1116183Y53512D02*
X1117183D01*
G01Y53605D02*
X1116183D01*
G01X1126852Y53867D02*
X1126152D01*
G01Y54083D02*
X1126852D01*
G01X1126152Y54179D02*
X1126852D01*
G01X1126152Y54241D02*
X1126852D01*
G01X1117183Y54260D02*
X1116183D01*
G01X1117183Y54275D02*
X1116183D01*
G01X1126852Y54339D02*
X1126152D01*
G01X1126823Y54546D02*
X1126764D01*
G01X1127158D02*
X1127099D01*
G01X1127355D02*
X1127296D01*
G01X1126351D02*
X1126292D01*
G01X1126685D02*
X1126626D01*
G01X1127059Y54667D02*
X1126863D01*
G01X1126587D02*
X1126390D01*
G01X1127050Y54707D02*
X1126872D01*
G01X1126577D02*
X1126400D01*
G01X1126449Y55019D02*
X1126528D01*
G01X1126922D02*
X1127000D01*
G01X1127296D02*
X1127355D01*
G01X1126852Y55323D02*
X1126152D01*
G01X1126852Y55422D02*
X1126152D01*
G01Y55484D02*
X1126852D01*
G01X1126152Y55579D02*
X1126852D01*
G01Y55796D02*
X1126152D01*
G01X1116183Y56275D02*
X1120703D01*
G01X1129105Y63316D02*
X1129805D01*
G01Y63532D02*
X1129105D01*
G01X1129805Y63627D02*
X1129105D01*
G01X1129805Y63690D02*
X1129105D01*
G01X1129805Y63788D02*
X1129105D01*
G01X1129805Y64772D02*
X1129105D01*
G01X1129805Y64871D02*
X1129105D01*
G01X1129805Y64933D02*
X1129105D01*
G01X1129805Y65028D02*
X1129105D01*
G01Y65245D02*
X1129805D01*
G01X1132057Y66071D02*
X1132757D01*
G01Y66288D02*
X1132057D01*
G01X1132757Y66383D02*
X1132057D01*
G01X1132757Y66445D02*
X1132057D01*
G01X1132757Y66544D02*
X1132057D01*
G01X1132757Y67528D02*
X1132057D01*
G01X1132757Y67627D02*
X1132057D01*
G01X1132757Y67689D02*
X1132057D01*
G01X1132757Y67784D02*
X1132057D01*
G01Y68001D02*
X1132757D01*
G01X1116183Y68775D02*
X1120703D01*
G01X1126852Y68827D02*
X1126152D01*
G01Y69044D02*
X1126852D01*
G01X1126152Y69139D02*
X1126852D01*
G01X1126152Y69201D02*
X1126852D01*
G01Y69300D02*
X1126152D01*
G01X1126852Y70284D02*
X1126152D01*
G01X1126852Y70382D02*
X1126152D01*
G01Y70445D02*
X1126852D01*
G01Y70540D02*
X1126152D01*
G01X1126852Y70756D02*
X1126152D01*
G01X1116183Y70775D02*
X1117183D01*
G01Y71775D02*
X1116183D01*
G01X1116669Y52408D02*
X1116734Y52394D01*
G01X1116721Y52327D02*
X1116682Y52341D01*
G01X1114805Y72001D02*
X1116183Y71206D01*
G01X1116734Y52394D02*
X1116787Y52354D01*
G01X1116748Y52301D02*
X1116721Y52327D01*
G01X1116787Y52354D02*
X1116826Y52301D01*
G01X1126528Y55019D02*
X1126685Y54546D01*
G01X1127000Y55019D02*
X1127158Y54546D01*
G01X1116761Y52260D02*
X1116748Y52301D01*
G01X1116826D02*
X1116839Y52260D01*
G01X1126626Y54546D02*
X1126587Y54667D01*
G01X1126489Y54979D02*
X1126577Y54707D01*
G01X1127099Y54546D02*
X1127059Y54667D01*
G01X1126961Y54979D02*
X1127050Y54707D01*
G01X1117183Y68855D02*
X1117192Y68810D01*
X1117219Y68783D01*
X1117263Y68775D01*
G01X1114805Y72001D02*
Y78891D01*
G01X1116354Y51778D02*
Y52408D01*
G01X1116433Y52059D02*
Y51778D01*
G01Y52341D02*
Y52140D01*
G01X1116761Y52220D02*
Y52260D01*
G01X1116839D02*
Y52206D01*
G01X1116944Y52341D02*
Y52408D01*
G01X1117154Y51778D02*
Y52341D01*
G01X1117233D02*
Y51778D01*
G01X1117443Y52408D02*
Y52341D01*
G01X1117548Y51778D02*
Y52408D01*
G01X1117627Y52073D02*
Y51778D01*
G01Y52408D02*
Y52153D01*
G01X1117994Y51778D02*
Y52073D01*
G01Y52153D02*
Y52408D01*
G01X1118073D02*
Y51778D01*
G01X1118178Y52206D02*
Y52314D01*
G01X1118257Y51778D02*
Y52301D01*
G01X1118335Y52408D02*
Y51778D01*
G01X1119782Y56275D02*
Y68775D01*
G01X1120120D02*
Y92474D01*
G01X1121703Y67775D02*
Y57275D01*
G01X1126152Y53868D02*
Y55794D01*
G01Y68829D02*
Y70755D01*
G01X1126852Y53869D02*
Y55795D01*
G01Y68829D02*
Y70755D01*
G01X1127237Y54868D02*
Y54948D01*
G01X1127296Y54546D02*
Y54938D01*
G01X1127355Y55019D02*
Y54546D01*
G01X1129105Y48356D02*
Y50282D01*
G01Y63317D02*
Y65243D01*
G01X1129805Y48357D02*
Y50283D01*
G01Y63318D02*
Y65243D01*
G01X1132057Y51112D02*
Y53038D01*
G01Y66073D02*
Y67999D01*
G01X1132757Y51113D02*
Y53039D01*
G01Y66073D02*
Y67999D01*
G01X1116748Y52180D02*
X1116761Y52220D01*
G01X1116839Y52206D02*
X1116826Y52166D01*
G01X1126400Y54707D02*
X1126489Y54979D01*
G01X1126390Y54667D02*
X1126351Y54546D01*
G01X1126872Y54707D02*
X1126961Y54979D01*
G01X1126863Y54667D02*
X1126823Y54546D01*
G01X1126292D02*
X1126449Y55019D01*
G01X1126764Y54546D02*
X1126922Y55019D01*
G01X1116682Y52140D02*
X1116721Y52153D01*
G01X1116826Y52166D02*
X1116787Y52113D01*
G01X1118178Y52314D02*
X1118257Y52408D01*
G01Y52301D02*
X1118178Y52206D01*
G01X1127237Y54948D02*
X1127296Y55019D01*
G01Y54938D02*
X1127237Y54868D01*
G01X1116721Y52153D02*
X1116748Y52180D01*
G01X1116787Y52113D02*
X1116734Y52073D01*
G01X1121703Y67775D02*
G03X1120703Y68775I-1000J0D01*
G01Y56275D02*
G03X1121703Y57275I0J1000D01*
G01X1176211Y43930D02*
X1117183D01*
G01X1119120Y44408D02*
X1157506D01*
G01X1119120Y105171D02*
Y44408D01*
G01X1120120D02*
Y56275D01*
G01X1120748Y105171D02*
Y44408D01*
G01X1122161Y105171D02*
Y44408D01*
G01X1133392Y46512D02*
Y44408D01*
G01X1135075Y45393D02*
X1130463Y40780D01*
G01X1133494Y43339D02*
G03X1132904Y43930I-591J0D01*
G01X1138663Y79733D02*
X1137963D01*
G01X1138663Y79831D02*
X1137963D01*
G01X1138663Y79894D02*
X1137963D01*
G01X1138663Y79989D02*
X1137963D01*
G01Y80205D02*
X1138663D01*
G01X1140915Y81032D02*
X1141615D01*
G01Y81249D02*
X1140915D01*
G01X1141615Y81344D02*
X1140915D01*
G01X1141615Y81406D02*
X1140915D01*
G01X1141615Y81505D02*
X1140915D01*
G01X1141616Y82489D02*
X1140916D01*
G01X1141615Y82587D02*
X1140915D01*
G01X1141615Y82650D02*
X1140915D01*
G01X1141615Y82745D02*
X1140915D01*
G01Y82961D02*
X1141615D01*
G01X1135710Y83788D02*
X1135010D01*
G01Y84005D02*
X1135710D01*
G01X1135010Y84100D02*
X1135710D01*
G01X1135010Y84162D02*
X1135710D01*
G01Y84260D02*
X1135010D01*
G01X1135710Y85245D02*
X1135010D01*
G01X1135710Y85343D02*
X1135010D01*
G01Y85406D02*
X1135710D01*
G01Y85501D02*
X1135010D01*
G01X1135710Y85717D02*
X1135010D01*
G01X1137963Y93237D02*
X1138663D01*
G01Y93453D02*
X1137963D01*
G01X1138663Y93549D02*
X1137963D01*
G01X1138663Y93611D02*
X1137963D01*
G01X1138663Y93709D02*
X1137963D01*
G01X1138663Y94693D02*
X1137963D01*
G01X1138663Y94792D02*
X1137963D01*
G01X1138663Y94855D02*
X1137963D01*
G01X1138663Y94949D02*
X1137963D01*
G01Y95166D02*
X1138663D01*
G01X1140915Y95993D02*
X1141615D01*
G01Y96209D02*
X1140915D01*
G01X1141615Y96305D02*
X1140915D01*
G01X1141615Y96367D02*
X1140915D01*
G01X1141615Y96465D02*
X1140915D01*
G01X1141616Y97449D02*
X1140916D01*
G01X1141615Y97548D02*
X1140915D01*
G01X1141615Y97610D02*
X1140915D01*
G01X1141615Y97705D02*
X1140915D01*
G01Y97922D02*
X1141615D01*
G01X1135710Y98749D02*
X1135010D01*
G01Y98965D02*
X1135710D01*
G01X1135010Y99060D02*
X1135710D01*
G01X1135010Y99123D02*
X1135710D01*
G01Y99221D02*
X1135010D01*
G01X1135710Y100205D02*
X1135010D01*
G01X1135710Y100304D02*
X1135010D01*
G01Y100366D02*
X1135710D01*
G01Y100461D02*
X1135010D01*
G01X1135710Y100678D02*
X1135010D01*
G01X1133844Y105958D02*
Y106958D01*
G01X1133941Y105958D02*
Y106958D01*
G01X1134593Y105958D02*
Y106958D01*
G01X1135010Y83790D02*
Y85716D01*
G01Y98750D02*
Y100676D01*
G01X1135360Y102336D02*
Y105171D01*
G01Y105958D02*
Y106958D01*
G01X1135710Y83790D02*
Y85716D01*
G01Y98751D02*
Y100677D01*
G01X1136093Y105958D02*
Y106958D01*
G01X1136738Y102336D02*
Y105171D01*
G01X1137963Y93238D02*
Y95164D01*
G01X1138663Y93239D02*
Y95165D01*
G01X1140915Y81034D02*
Y82960D01*
G01Y95994D02*
Y97920D01*
G01X1141266Y105958D02*
Y106958D01*
G01X1141615Y81034D02*
Y82960D01*
G01Y95995D02*
Y97921D01*
G01X1137963Y78276D02*
X1138663D01*
G01Y78493D02*
X1137963D01*
G01X1138663Y78588D02*
X1137963D01*
G01X1138663Y78650D02*
X1137963D01*
G01X1138663Y78749D02*
X1137963D01*
G01Y78278D02*
Y80204D01*
G01X1138663Y78278D02*
Y80204D01*
G01X1127065Y99499D02*
X1127025Y99489D01*
G01X1127074Y99438D02*
X1127025Y99428D01*
G01X1117263Y92474D02*
X1117219Y92466D01*
X1117192Y92439D01*
X1117183Y92394D01*
G01X1129805Y79733D02*
X1129105D01*
G01X1129805Y79831D02*
X1129105D01*
G01X1129805Y79894D02*
X1129105D01*
G01X1129805Y79989D02*
X1129105D01*
G01Y80205D02*
X1129805D01*
G01X1132057Y81032D02*
X1132757D01*
G01Y81249D02*
X1132057D01*
G01X1132757Y81344D02*
X1132057D01*
G01X1132757Y81406D02*
X1132057D01*
G01X1132757Y81505D02*
X1132057D01*
G01X1132757Y82489D02*
X1132057D01*
G01X1132757Y82587D02*
X1132057D01*
G01X1132757Y82650D02*
X1132057D01*
G01X1132757Y82745D02*
X1132057D01*
G01Y82961D02*
X1132757D01*
G01X1126852Y83788D02*
X1126152D01*
G01Y84005D02*
X1126852D01*
G01X1126152Y84100D02*
X1126852D01*
G01X1126152Y84162D02*
X1126852D01*
G01Y84260D02*
X1126152D01*
G01X1126852Y85245D02*
X1126152D01*
G01X1126852Y85343D02*
X1126152D01*
G01Y85406D02*
X1126852D01*
G01Y85501D02*
X1126152D01*
G01X1126852Y85717D02*
X1126152D01*
G01X1116183Y89474D02*
X1117183D01*
G01Y90474D02*
X1116183D01*
G01X1117183Y91474D02*
X1116183D01*
G01X1120703Y92474D02*
X1116183D01*
G01X1129105Y93237D02*
X1129805D01*
G01Y93453D02*
X1129105D01*
G01X1129805Y93549D02*
X1129105D01*
G01X1129805Y93611D02*
X1129105D01*
G01X1129805Y93709D02*
X1129105D01*
G01X1129805Y94693D02*
X1129105D01*
G01X1129805Y94792D02*
X1129105D01*
G01X1129805Y94855D02*
X1129105D01*
G01X1129805Y94949D02*
X1129105D01*
G01X1116183Y94974D02*
X1115002D01*
G01X1129105Y95166D02*
X1129805D01*
G01X1132057Y95993D02*
X1132757D01*
G01Y96209D02*
X1132057D01*
G01X1132757Y96305D02*
X1132057D01*
G01X1132757Y96367D02*
X1132057D01*
G01X1132757Y96465D02*
X1132057D01*
G01X1115002Y96942D02*
X1116183D01*
G01X1116396Y96943D02*
X1115002D01*
G01X1132757Y97449D02*
X1132057D01*
G01X1132757Y97548D02*
X1132057D01*
G01X1132757Y97610D02*
X1132057D01*
G01X1132757Y97705D02*
X1132057D01*
G01Y97922D02*
X1132757D01*
G01X1126852Y98749D02*
X1126152D01*
G01Y98965D02*
X1126852D01*
G01X1126152Y99060D02*
X1126852D01*
G01X1126152Y99123D02*
X1126852D01*
G01Y99221D02*
X1126152D01*
G01X1127025Y99428D02*
X1126789D01*
G01X1127380D02*
X1127320D01*
G01X1126376D02*
X1126317D01*
G01X1126710D02*
X1126651D01*
G01X1127025Y99489D02*
X1126848D01*
G01X1126612Y99549D02*
X1126415D01*
G01X1126602Y99589D02*
X1126425D01*
G01X1126848Y99840D02*
X1127025D01*
G01X1126474Y99901D02*
X1126553D01*
G01X1126789D02*
X1127025D01*
G01X1127320D02*
X1127380D01*
G01X1126852Y100205D02*
X1126152D01*
G01X1126852Y100304D02*
X1126152D01*
G01Y100366D02*
X1126852D01*
G01Y100461D02*
X1126152D01*
G01X1126852Y100678D02*
X1126152D01*
G01X1124927Y102336D02*
X1151699D01*
G01X1116396Y104974D02*
X1117183D01*
G01X1116396Y105169D02*
X1116955D01*
G01X1116396Y105171D02*
X1290199D01*
G01X1116183Y105191D02*
X1116396D01*
G01X1117183Y105464D02*
X1116183D01*
G01X1289593Y105958D02*
X1117002D01*
G01X1290411Y106958D02*
X1116183D01*
G01X1127025Y99901D02*
X1127074Y99891D01*
G01X1127025Y99840D02*
X1127065Y99830D01*
G01X1127074Y99891D02*
X1127114Y99871D01*
G01X1127065Y99830D02*
X1127094Y99810D01*
G01X1127114Y99871D02*
X1127153Y99830D01*
G01X1127094Y99810D02*
X1127114Y99780D01*
G01X1127153Y99830D02*
X1127173Y99790D01*
G01X1126553Y99901D02*
X1126710Y99428D01*
G01X1126651D02*
X1126612Y99549D01*
G01X1126513Y99860D02*
X1126602Y99589D01*
G01X1127114Y99780D02*
X1127124Y99740D01*
G01X1127173Y99790D02*
X1127183Y99740D01*
G01X1115002Y104958D02*
Y94974D01*
G01X1116396Y105753D02*
Y95186D01*
G01X1117380Y105958D02*
Y106958D01*
G01X1117880D02*
Y105958D01*
G01X1118380D02*
Y106958D01*
G01X1118880D02*
Y105958D01*
G01X1119782Y92474D02*
Y105171D01*
G01X1121104Y107942D02*
Y106958D01*
G01X1121703Y104171D02*
Y93474D01*
G01X1122104Y107942D02*
Y106958D01*
G01X1124707Y105958D02*
Y106958D01*
G01X1124927Y105171D02*
Y102336D01*
G01X1125707Y106958D02*
Y105958D01*
G01X1126152Y83790D02*
Y85716D01*
G01Y98750D02*
Y100676D01*
G01X1126789Y99428D02*
Y99901D01*
G01X1126848Y99489D02*
Y99840D01*
G01X1126852Y83790D02*
Y85716D01*
G01Y98751D02*
Y100677D01*
G01X1127124Y99740D02*
Y99589D01*
G01X1127183Y99740D02*
Y99589D01*
G01X1127261Y99750D02*
Y99830D01*
G01X1127320Y99428D02*
Y99820D01*
G01X1127380Y99901D02*
Y99428D01*
G01X1127703Y106958D02*
Y105958D01*
G01X1127707Y105171D02*
Y106958D01*
G01X1128723D02*
Y105958D01*
G01X1129105Y93238D02*
Y95164D01*
G01X1129805Y93239D02*
Y95165D01*
G01X1130066Y105958D02*
Y106958D01*
G01X1130878D02*
Y105958D01*
G01X1130970D02*
Y106958D01*
G01X1131456Y105958D02*
Y106958D01*
G01X1131508Y105958D02*
Y106958D01*
G01X1131915Y105958D02*
Y106958D01*
G01X1132057Y81034D02*
Y82960D01*
G01Y95994D02*
Y97920D01*
G01X1132757Y81034D02*
Y82960D01*
G01Y95995D02*
Y97921D01*
G01X1132900Y106958D02*
Y105958D01*
G01X1133311D02*
Y106958D01*
G01X1133363Y105958D02*
Y106958D01*
G01X1127183Y99589D02*
X1127173Y99539D01*
G01X1127124Y99589D02*
X1127114Y99549D01*
G01X1126425Y99589D02*
X1126513Y99860D01*
G01X1126415Y99549D02*
X1126376Y99428D01*
G01X1126317D02*
X1126474Y99901D01*
G01X1127173Y99539D02*
X1127153Y99499D01*
G01X1116396Y95186D02*
X1116183Y94974D01*
G01X1127094Y99519D02*
X1127065Y99499D01*
G01X1116183Y79687D02*
X1114805Y78891D01*
G01X1127114Y99458D02*
X1127074Y99438D01*
G01X1127114Y99549D02*
X1127094Y99519D01*
G01X1127261Y99830D02*
X1127320Y99901D01*
G01Y99820D02*
X1127261Y99750D01*
G01X1127153Y99499D02*
X1127114Y99458D01*
G01X1117002Y106958D02*
G03X1115002Y104958I0J-2000D01*
G01X1118183Y107942D02*
G03X1116411Y106869I0J-2000D01*
G01X1120703Y92474D02*
G03X1121703Y93474I0J1000D01*
G01Y104171D02*
G03X1120703Y105171I-1000J0D01*
G01X1117002Y105958D02*
G03X1116396Y105753I1J-1000D01*
G01X1117271Y105958D02*
G03X1117183Y105549I912J-410D01*
G01X1114805Y73970D02*
X1116183D01*
G01Y76923D02*
X1114805D01*
G01X1129105Y78276D02*
X1129805D01*
G01Y78493D02*
X1129105D01*
G01X1129805Y78588D02*
X1129105D01*
G01X1129805Y78650D02*
X1129105D01*
G01X1129805Y78749D02*
X1129105D01*
G01X1119120Y75643D02*
X1117183Y77580D01*
G01X1129105Y78278D02*
Y80204D01*
G01X1129805Y78278D02*
Y80204D01*
G01X1122104Y107942D02*
X1118183D01*
G01X1133760Y892519D02*
Y883464D01*
G01X1134744D02*
Y892519D01*
G01X1136909D02*
Y883464D01*
G01X1137894D02*
Y892519D01*
G01X1140059D02*
Y883464D01*
G01X1140098Y860500D02*
Y865275D01*
G01X1141043Y883464D02*
Y892519D01*
G01X1140098Y865275D02*
X1141575D01*
G01X1143209Y883464D02*
X1141043D01*
G01X1140059D02*
X1137894D01*
G01X1136909D02*
X1134744D01*
G01X1140098Y853464D02*
Y858992D01*
G01X1141575Y865275D02*
Y853464D01*
G01D02*
X1140098D01*
G01X1109547Y883464D02*
Y892519D01*
G01X1111713D02*
Y883464D01*
G01X1112697D02*
Y892519D01*
G01X1114862D02*
Y883464D01*
G01X1115846D02*
Y892519D01*
G01X1118012D02*
Y883464D01*
G01X1118996D02*
Y892519D01*
G01X1121161D02*
Y883464D01*
G01X1122146D02*
Y892519D01*
G01X1124311D02*
Y883464D01*
G01X1125295D02*
Y892519D01*
G01X1127461D02*
Y883464D01*
G01X1128445D02*
Y892519D01*
G01X1130610D02*
Y883464D01*
G01X1131594D02*
Y892519D01*
G01X1133209Y865275D02*
Y860500D01*
G01X1140098Y858992D02*
X1133209D01*
G01Y860500D02*
X1140098D01*
G01X1131732Y865275D02*
X1133209D01*
G01X1133760Y883464D02*
X1131594D01*
G01X1130610D02*
X1128445D01*
G01X1127461D02*
X1125295D01*
G01X1124311D02*
X1122146D01*
G01X1121161D02*
X1118996D01*
G01X1118012D02*
X1115846D01*
G01X1114862D02*
X1112697D01*
G01X1111713D02*
X1109547D01*
G01X1131732Y853464D02*
Y865275D01*
G01X1133209Y858992D02*
Y853464D01*
G01D02*
X1131732D01*
G01X1134744Y892519D02*
X1136909D01*
G01X1137894D02*
X1140059D01*
G01X1141043D02*
X1143209D01*
G01X1112697D02*
X1114862D01*
G01X1109547D02*
X1111713D01*
G01X1115846D02*
X1118012D01*
G01X1118996D02*
X1121161D01*
G01X1125295D02*
X1127461D01*
G01X1122146D02*
X1124311D01*
G01X1128445D02*
X1130610D01*
G01X1131594D02*
X1133760D01*
G01X1137206Y950180D02*
Y941519D01*
G01X1120695Y945128D02*
X1119721Y943684D01*
X1119234Y941519D01*
X1123131D01*
G01X1119234Y948737D02*
X1119721Y949459D01*
X1120695Y950180D01*
X1121670D01*
X1122644Y949459D01*
X1123131Y948737D01*
Y947293D01*
X1122644Y946572D01*
X1120695Y945128D01*
G01X1113387Y941519D02*
X1112900D01*
Y942241D01*
X1113387Y941519D01*
G01X1132876D02*
X1141537D01*
G01X1132876Y945850D02*
X1141537D01*
G01X1128978Y941519D02*
X1128004Y942241D01*
X1127516Y942963D01*
X1127029Y944406D01*
Y947293D01*
X1127516Y948737D01*
X1128004Y949459D01*
X1128978Y950180D01*
X1129952Y949459D01*
X1130439Y948737D01*
X1130926Y947293D01*
Y944406D01*
X1130439Y942963D01*
X1129952Y942241D01*
X1128978Y941519D01*
G01X1174206Y-1129166D02*
X1172780Y-1128215D01*
X1172067Y-1127265D01*
Y-1126314D01*
X1172780Y-1125364D01*
X1174206Y-1124413D01*
X1175631D01*
X1177057Y-1125364D01*
X1177770Y-1126314D01*
Y-1127265D01*
X1177057Y-1128215D01*
X1175631Y-1129166D01*
G01X1171354Y-1132968D02*
Y-1132018D01*
X1172067Y-1131067D01*
X1172780Y-1130117D01*
X1174206Y-1129166D01*
X1175631D01*
X1177057Y-1130117D01*
G01X1174206Y-1135820D02*
X1172780Y-1134870D01*
X1171354Y-1132968D01*
G01X1177057Y-1130117D02*
X1178483Y-1132018D01*
Y-1132968D01*
X1177770Y-1133919D01*
X1177057Y-1134870D01*
X1175631Y-1135820D01*
X1174206D01*
G01X1143684Y-766744D02*
X1144659Y-765300D01*
Y-763135D01*
G01X1191507Y-719139D02*
X1170296Y-727375D01*
G01D02*
X1150033Y-730346D01*
G01X1176421Y-687590D02*
X1173961D01*
G01X1176421D02*
X1173961D01*
G01X1171992Y-673517D02*
X1170516D01*
G01X1171992D02*
X1170516D01*
G01X1171008Y-671507D02*
X1172976D01*
G01X1171008D02*
X1172976D01*
G01D02*
X1174453Y-672009D01*
G01X1172976Y-671507D02*
X1174453Y-672009D01*
G01X1172976Y-674020D02*
X1171992Y-673517D01*
G01X1172976Y-674020D02*
X1171992Y-673517D01*
G01X1173469Y-674522D02*
X1172976Y-674020D01*
G01X1173469Y-674522D02*
X1172976Y-674020D01*
G01X1174453Y-672009D02*
X1175437Y-673014D01*
G01X1174453Y-672009D02*
X1175437Y-673014D01*
G01X1173961Y-675527D02*
X1173469Y-674522D01*
G01X1173961Y-675527D02*
X1173469Y-674522D01*
G01X1175437Y-673014D02*
X1176421Y-675527D01*
G01X1175437Y-673014D02*
X1176421Y-675527D01*
G01X1168547D02*
Y-687590D01*
G01Y-675527D02*
Y-687590D01*
G01X1173961D02*
Y-675527D01*
G01Y-687590D02*
Y-675527D01*
G01X1176421D02*
Y-687590D01*
G01Y-675527D02*
Y-687590D01*
G01X1169039Y-674522D02*
X1168547Y-675527D01*
G01X1169039Y-674522D02*
X1168547Y-675527D01*
G01X1168055Y-673517D02*
X1169531Y-672009D01*
G01X1168055Y-673517D02*
X1169531Y-672009D01*
G01Y-674020D02*
X1169039Y-674522D01*
G01X1169531Y-674020D02*
X1169039Y-674522D01*
G01X1170516Y-673517D02*
X1169531Y-674020D01*
G01X1170516Y-673517D02*
X1169531Y-674020D01*
G01Y-672009D02*
X1171008Y-671507D01*
G01X1169531Y-672009D02*
X1171008Y-671507D01*
G01X1168547Y-687590D02*
X1166087D01*
G01X1160673D02*
X1158213D01*
G01X1168547D02*
X1166087D01*
G01X1160673D02*
X1158213D01*
G01X1145417Y-685077D02*
X1147878Y-684574D01*
G01X1145417Y-685077D02*
X1147878Y-684574D01*
G01X1145417Y-687590D02*
X1148370Y-687087D01*
G01X1145417Y-687590D02*
X1148370Y-687087D01*
G01X1164118Y-673517D02*
X1163134D01*
G01X1164118D02*
X1163134D01*
G01X1158213Y-671507D02*
X1160673D01*
G01X1163134D02*
X1165102D01*
G01X1158213D02*
X1160673D01*
G01X1163134D02*
X1165102D01*
G01D02*
X1166579Y-672009D01*
G01X1165102Y-671507D02*
X1166579Y-672009D01*
G01X1165102Y-674020D02*
X1164118Y-673517D01*
G01X1165102Y-674020D02*
X1164118Y-673517D01*
G01X1165594Y-674522D02*
X1165102Y-674020D01*
G01X1165594Y-674522D02*
X1165102Y-674020D01*
G01X1166579Y-672009D02*
X1168055Y-673517D01*
G01X1166579Y-672009D02*
X1168055Y-673517D01*
G01X1151323Y-671004D02*
X1149354Y-667988D01*
G01X1151323Y-671004D02*
X1149354Y-667988D01*
G01X1153291Y-669496D02*
X1152307Y-667486D01*
G01X1153291Y-669496D02*
X1152307Y-667486D01*
G01X1166087Y-675527D02*
X1165594Y-674522D01*
G01X1166087Y-675527D02*
X1165594Y-674522D01*
G01X1153783Y-671004D02*
X1153291Y-669496D01*
G01X1153783Y-671004D02*
X1153291Y-669496D01*
G01X1154276Y-673517D02*
X1153783Y-671004D01*
G01X1154276Y-673517D02*
X1153783Y-671004D01*
G01X1151815Y-674020D02*
X1151323Y-671004D01*
G01X1151815Y-674020D02*
X1151323Y-671004D01*
G01X1151815Y-677538D02*
Y-674020D01*
G01Y-677538D02*
Y-674020D01*
G01X1154276Y-678040D02*
Y-673517D01*
G01Y-678040D02*
Y-673517D01*
G01X1158213Y-687590D02*
Y-671507D01*
G01Y-687590D02*
Y-671507D01*
G01X1160673D02*
Y-673014D01*
G01Y-675025D02*
Y-687590D01*
G01Y-671507D02*
Y-673014D01*
G01Y-675025D02*
Y-687590D01*
G01X1166087D02*
Y-675527D01*
G01Y-687590D02*
Y-675527D01*
G01X1151323Y-680553D02*
X1151815Y-677538D01*
G01X1151323Y-680553D02*
X1151815Y-677538D01*
G01X1153783Y-680553D02*
X1154276Y-678040D01*
G01X1153783Y-680553D02*
X1154276Y-678040D01*
G01X1153291Y-682061D02*
X1153783Y-680553D01*
G01X1153291Y-682061D02*
X1153783Y-680553D01*
G01X1152307Y-684071D02*
X1153291Y-682061D01*
G01X1152307Y-684071D02*
X1153291Y-682061D01*
G01X1149354Y-683569D02*
X1151323Y-680553D01*
G01X1149354Y-683569D02*
X1151323Y-680553D01*
G01X1160673Y-673014D02*
X1161657Y-672009D01*
G01X1160673Y-673014D02*
X1161657Y-672009D01*
G01Y-674020D02*
X1160673Y-675025D01*
G01X1161657Y-674020D02*
X1160673Y-675025D01*
G01X1150831Y-685579D02*
X1152307Y-684071D01*
G01X1150831Y-685579D02*
X1152307Y-684071D01*
G01X1147878Y-684574D02*
X1149354Y-683569D01*
G01X1147878Y-684574D02*
X1149354Y-683569D01*
G01X1148370Y-687087D02*
X1150831Y-685579D01*
G01X1148370Y-687087D02*
X1150831Y-685579D01*
G01X1161657Y-672009D02*
X1163134Y-671507D01*
G01X1161657Y-672009D02*
X1163134Y-671507D01*
G01Y-673517D02*
X1161657Y-674020D01*
G01X1163134Y-673517D02*
X1161657Y-674020D01*
G01X1157048Y-642708D02*
X1289141D01*
G01X1153111Y-638771D02*
Y-440451D01*
G01X1164800Y-638010D02*
X1192481Y-610329D01*
G01X1147878Y-666983D02*
X1145417Y-666481D01*
G01X1147878Y-666983D02*
X1145417Y-666481D01*
G01X1148370Y-664470D02*
X1145417Y-663968D01*
G01X1148370Y-664470D02*
X1145417Y-663968D01*
G01X1150831Y-665978D02*
X1148370Y-664470D01*
G01X1150831Y-665978D02*
X1148370Y-664470D01*
G01X1149354Y-667988D02*
X1147878Y-666983D01*
G01X1149354Y-667988D02*
X1147878Y-666983D01*
G01X1152307Y-667486D02*
X1150831Y-665978D01*
G01X1152307Y-667486D02*
X1150831Y-665978D01*
G01X1175031Y-595464D02*
X1169187Y-591494D01*
G01X1175031Y-595464D02*
X1169187Y-591494D01*
G01X1175031Y-595464D02*
X1169187Y-599442D01*
G01X1175031Y-595464D02*
X1169187Y-599442D01*
G01X1153111Y-569261D02*
X1149142Y-575105D01*
G01X1153111Y-569261D02*
X1149142Y-575105D01*
G01X1153111Y-595464D02*
X1175031D01*
G01X1153111D02*
X1175031D01*
G01X1153111D02*
Y-569261D01*
G01Y-595464D02*
Y-569261D01*
G01X1160887Y-569685D02*
Y-566991D01*
G01Y-569685D02*
Y-566991D01*
G01X1161546D02*
Y-569685D01*
G01Y-566991D02*
Y-569685D01*
G01D02*
X1160887D01*
G01X1161546D02*
X1160887D01*
G01X1153111Y-569261D02*
X1157090Y-575105D01*
G01X1153111Y-569261D02*
X1157090Y-575105D01*
G01X1157048Y-548220D02*
X1321274D01*
G01X1161217Y-566542D02*
X1162645Y-564409D01*
G01X1161217Y-566542D02*
X1162645Y-564409D01*
G01X1163305D02*
X1161546Y-566991D01*
G01X1163305Y-564409D02*
X1161546Y-566991D01*
G01X1159128Y-564409D02*
X1159788D01*
G01X1162645D02*
X1163305D01*
G01X1159128D02*
X1159788D01*
G01X1162645D02*
X1163305D01*
G01X1160887Y-566991D02*
X1159128Y-564409D01*
G01X1160887Y-566991D02*
X1159128Y-564409D01*
G01X1159788D02*
X1161217Y-566542D01*
G01X1159788Y-564409D02*
X1161217Y-566542D01*
G01X1161681Y-455673D02*
X1183208Y-457970D01*
G01X1192481Y-402323D02*
X1145237D01*
G01D02*
X1318773D01*
G01X1168631Y-109843D02*
Y-104069D01*
G01Y-105512D02*
X1169606Y-104069D01*
X1170580D01*
X1171555Y-105512D01*
Y-109843D01*
G01X1148656Y-101181D02*
Y-109843D01*
G01Y-107678D02*
X1147682Y-109121D01*
X1146707Y-109843D01*
X1145733Y-109121D01*
X1144759Y-107678D01*
Y-106234D01*
X1145733Y-104790D01*
X1146707Y-104069D01*
X1147682Y-104790D01*
X1148656Y-106234D01*
G01X1164247Y-107678D02*
X1163272Y-109121D01*
X1162298Y-109843D01*
X1161324Y-109121D01*
X1160349Y-107678D01*
Y-106234D01*
X1161324Y-104790D01*
X1162298Y-104069D01*
X1163272Y-104790D01*
X1164247Y-106234D01*
Y-107678D01*
G01X1186644Y-41835D02*
X1176644D01*
G01Y-41754D02*
X1186644D01*
G01X1186730Y-41635D02*
X1176558D01*
G01X1186644Y-41461D02*
X1176644D01*
G01Y-41403D02*
X1186644D01*
G01X1176644Y-41135D02*
X1186644D01*
G01Y-41107D02*
X1176644D01*
G01X1176329Y-34319D02*
X1186959D01*
G01X1180908Y-33775D02*
X1172710D01*
G01X1180894Y-33102D02*
X1172724D01*
G01Y-32967D02*
X1180894D01*
G01X1180893Y-31261D02*
X1172725D01*
G01X1172724Y-30829D02*
X1180894D01*
G01Y-30744D02*
X1172724D01*
G01X1171239Y-33775D02*
X1171233Y-33744D01*
X1171228Y-33713D01*
X1171226Y-33682D01*
G01Y-33663D02*
X1171228Y-33701D01*
X1171233Y-33738D01*
X1171239Y-33775D01*
G01X1171226Y-33682D02*
X1171224Y-33647D01*
G01Y-33621D02*
X1171226Y-33663D01*
G01X1167624Y-33339D02*
Y-38564D01*
G01X1167821Y-33839D02*
Y-38879D01*
G01X1171226Y-33682D02*
Y-33663D01*
G01X1171224Y-17548D02*
Y-33647D01*
G01X1172724D02*
Y-17548D01*
G01Y-33663D02*
Y-33682D01*
G01X1176329Y-34319D02*
Y-32749D01*
G01X1176644Y-40398D02*
Y-41835D01*
G01X1172724Y-33663D02*
Y-33621D01*
G01Y-33647D02*
Y-33682D01*
G01D02*
X1172721Y-33713D01*
X1172717Y-33744D01*
X1172710Y-33775D01*
G01D02*
X1172717Y-33738D01*
X1172721Y-33701D01*
X1172724Y-33663D01*
G01X1175851Y-41928D02*
X1175437Y-42342D01*
G01X1176558Y-41635D02*
G03X1175851Y-41928I0J-1000D01*
G01X1174730Y-42635D02*
G03X1175437Y-42342I0J1000D01*
G01X1177644Y-39440D02*
G03X1176644Y-40440I0J-1000D01*
G01X1174129Y-41435D02*
G03X1175087Y-40679I0J984D01*
G01X1177310Y-39467D02*
G03X1176644Y-40398I318J-931D01*
G01Y-40845D02*
G03X1175087Y-40679I-787J0D01*
G01X1171239Y-33775D02*
G03X1171974Y-34378I734J145D01*
G01D02*
G03X1172710Y-33775I2J748D01*
G01X1171974Y-32016D02*
G03X1172724Y-31261I2J748D01*
G01X1171225D02*
G03X1171974Y-32016I748J-7D01*
G01X1156925Y-31255D02*
X1148757Y-31261D01*
G01X1174730Y-42635D02*
X1145251D01*
G01X1174129Y-41435D02*
X1145852D01*
G01X1167230Y-39469D02*
X1163396D01*
G01X1156585D02*
X1152750D01*
G01X1167033Y-39154D02*
X1163396D01*
G01X1156388D02*
X1152160D01*
G01X1163027Y-38336D02*
X1159756D01*
G01Y-34399D02*
X1163027D01*
G01X1162563Y-34338D02*
X1162497D01*
G01X1157483D02*
X1157417D01*
G01X1171239Y-33775D02*
X1163055D01*
G01X1156925D02*
X1148742D01*
G01X1167230Y-33249D02*
X1163396D01*
G01X1156585D02*
X1152750D01*
G01X1171224Y-33102D02*
X1163055D01*
G01X1156925D02*
X1148756D01*
G01Y-32967D02*
X1156925D01*
G01X1163055D02*
X1171224D01*
G01X1202797Y-32749D02*
X1160490D01*
G01X1158975Y-32023D02*
X1161005D01*
G01X1148756Y-30829D02*
X1156925D01*
G01X1163055D02*
X1171224D01*
G01Y-30744D02*
X1163055D01*
G01X1156925D02*
X1148756D01*
G01X1171224Y-31261D02*
X1163055Y-31255D01*
G01X1202797Y-28812D02*
X1160490D01*
G01X1144544Y-42342D02*
X1144130Y-41928D01*
G01X1147270Y-33775D02*
X1147264Y-33744D01*
X1147260Y-33713D01*
X1147257Y-33682D01*
G01Y-33663D02*
X1147260Y-33701D01*
X1147264Y-33738D01*
X1147270Y-33775D01*
G01X1147257Y-33682D02*
X1147256Y-33647D01*
G01Y-33621D02*
X1147257Y-33663D01*
G01X1160490Y-32749D02*
X1160495Y-42635D01*
G01X1143337Y-40398D02*
Y-41832D01*
G01X1143652Y-32749D02*
Y-34319D01*
G01X1147257Y-33663D02*
Y-33682D01*
G01X1147256Y-17548D02*
Y-33647D01*
G01X1148756D02*
Y-17548D01*
G01X1148755Y-33663D02*
Y-33682D01*
G01X1152160Y-39154D02*
Y-33339D01*
G01X1156925Y-17548D02*
Y-33845D01*
G01X1156978Y-33339D02*
Y-38564D01*
G01X1157175Y-33839D02*
Y-38879D01*
G01X1157925Y-22238D02*
Y-31524D01*
G01X1157975Y-33023D02*
Y-33845D01*
G01X1159490Y-42635D02*
Y-32749D01*
G01Y-28812D02*
Y105958D01*
G01X1159756Y-34399D02*
Y-38336D01*
G01X1160490Y-42635D02*
Y-32749D01*
G01Y-28812D02*
Y105958D01*
G01X1161490Y-38336D02*
Y-34399D01*
G01X1162005Y-33023D02*
Y-33845D01*
G01X1162055Y-22238D02*
Y-31524D01*
G01X1162806Y-38879D02*
Y-33339D01*
G01X1163055Y-17548D02*
Y-33845D01*
G01X1164027Y-35399D02*
Y-37336D01*
G01X1160497Y-14225D02*
X1160490Y-28812D01*
G01X1148755Y-33663D02*
X1148756Y-33621D01*
G01Y-33647D02*
X1148755Y-33682D01*
G01D02*
X1148752Y-33713D01*
X1148748Y-33744D01*
X1148742Y-33775D01*
G01D02*
X1148748Y-33738D01*
X1148752Y-33701D01*
X1148755Y-33663D01*
G01X1144544Y-42342D02*
G03X1145251Y-42635I707J707D01*
G01X1144130Y-41928D02*
G03X1143422Y-41635I-707J-707D01*
G01X1144892Y-40670D02*
G03X1145852Y-41435I959J219D01*
G01X1144892Y-40670D02*
G03X1143337Y-40845I-768J-175D01*
G01X1163027Y-38336D02*
G03X1164027Y-37336I0J1000D01*
G01X1156585Y-39469D02*
G03X1157175Y-38879I0J590D01*
G01X1156388Y-39154D02*
G03X1156978Y-38564I0J590D01*
G01X1152160Y-38879D02*
G03X1152750Y-39469I590J0D01*
G01X1162806Y-38879D02*
G03X1163396Y-39469I590J0D01*
G01X1162806Y-38564D02*
G03X1163396Y-39154I590J0D01*
G01X1147270Y-33775D02*
G03X1148006Y-34378I734J145D01*
G01D02*
G03X1148742Y-33775I2J748D01*
G01X1152750Y-32749D02*
G03X1152160Y-33339I0J-590D01*
G01X1152750Y-33249D02*
G03X1152160Y-33839I0J-590D01*
G01X1148006Y-32016D02*
G03X1148756Y-31261I2J748D01*
G01X1147256D02*
G03X1148006Y-32016I748J-7D01*
G01X1164027Y-35399D02*
G03X1163027Y-34399I-1000J0D01*
G01X1156978Y-33339D02*
G03X1156388Y-32749I-590J0D01*
G01X1157175Y-33839D02*
G03X1156585Y-33249I-590J0D01*
G01X1156978Y-33839D02*
G03X1156388Y-33249I-590J0D01*
G01X1163396Y-32749D02*
G03X1162806Y-33339I0J-590D01*
G01X1163396Y-33249D02*
G03X1162806Y-33839I0J-590D01*
G01X1156925Y-33845D02*
G03X1157417Y-34338I492J-1D01*
G01X1157483D02*
G03X1157975Y-33845I0J492D01*
G01X1162005D02*
G03X1162497Y-34338I492J-1D01*
G01X1162563D02*
G03X1163055Y-33845I0J492D01*
G01X1158975Y-32023D02*
G03X1157975Y-33023I0J-1000D01*
G01X1162005D02*
G03X1161005Y-32023I-1000J0D01*
G01X1162555Y-32016D02*
G03X1163055Y-31524I8J492D01*
G01X1162055D02*
G03X1162555Y-32016I492J0D01*
G01X1157425D02*
G03X1157925Y-31524I8J492D01*
G01X1156925D02*
G03X1157425Y-32016I492J0D01*
G01X1167033Y-39154D02*
G03X1167624Y-38564I1J590D01*
G01X1167230Y-39469D02*
G03X1167821Y-38879I0J591D01*
G01X1167624Y-33339D02*
G03X1167033Y-32749I-590J0D01*
G01X1167624Y-33839D02*
G03X1167033Y-33249I-590J0D01*
G01X1167821Y-33839D02*
G03X1167230Y-33249I-591J-1D01*
G01X1173512Y-16798D02*
X1173359Y-16813D01*
X1173212Y-16857D01*
X1173076Y-16929D01*
X1172955Y-17028D01*
X1172857Y-17146D01*
X1172785Y-17281D01*
X1172740Y-17427D01*
X1172724Y-17582D01*
G01X1173512Y-16904D02*
X1173359Y-16917D01*
X1173212Y-16954D01*
X1173076Y-17015D01*
X1172955Y-17099D01*
X1172857Y-17199D01*
X1172785Y-17313D01*
X1172740Y-17437D01*
X1172724Y-17568D01*
G01X1180894Y-18862D02*
X1172724D01*
G01Y-18845D02*
X1180894D01*
G01Y-18516D02*
X1172724D01*
G01Y-18481D02*
X1180894D01*
G01Y-18138D02*
X1172724D01*
G01Y-18104D02*
X1180894D01*
G01X1172724Y-17890D02*
X1180894D01*
G01Y-17679D02*
X1172724D01*
G01X1173094Y-17318D02*
X1168173D01*
G01X1173512Y-17116D02*
X1180106D01*
G01Y-16904D02*
X1173512D01*
G01Y-16798D02*
X1180106D01*
G01Y-16764D02*
X1173512D01*
G01X1173094Y-14786D02*
X1168173D01*
G01Y-14307D02*
X1173094D01*
G01Y-9699D02*
X1168173D01*
G01Y-9220D02*
X1173094D01*
G01X1168173Y-6688D02*
X1173094D01*
G01Y-1570D02*
X1168173D01*
G01X1173094Y962D02*
X1168173D01*
G01Y1441D02*
X1173094D01*
G01Y6049D02*
X1168173D01*
G01X1168130Y-17116D02*
X1168288Y-17129D01*
X1168440Y-17170D01*
X1168579Y-17234D01*
X1168702Y-17323D01*
X1168799Y-17430D01*
X1168870Y-17553D01*
G01X1170437Y-16764D02*
X1170590Y-16779D01*
X1170737Y-16823D01*
X1170873Y-16895D01*
X1170994Y-16994D01*
X1171091Y-17112D01*
X1171164Y-17247D01*
X1171209Y-17393D01*
X1171224Y-17548D01*
G01X1168870Y-17341D02*
X1168800Y-17220D01*
X1168704Y-17114D01*
X1168584Y-17025D01*
X1168443Y-16959D01*
X1168291Y-16918D01*
X1168130Y-16904D01*
G01X1169016Y-17890D02*
X1169153Y-18195D01*
X1169291Y-18522D01*
X1169428Y-18862D01*
G01X1168870Y-17553D02*
X1169016Y-17890D01*
G01Y-17679D02*
X1168870Y-17341D01*
G01X1169428Y-18845D02*
X1169291Y-18437D01*
X1169153Y-18044D01*
X1169016Y-17679D01*
G01X1171224Y-17582D02*
X1171209Y-17430D01*
X1171165Y-17284D01*
X1171093Y-17149D01*
X1170994Y-17028D01*
X1170875Y-16931D01*
X1170740Y-16858D01*
X1170593Y-16814D01*
X1170437Y-16798D01*
G01X1168130Y-17116D02*
Y-16904D01*
G01X1168173Y9060D02*
Y-1570D01*
G01Y-6688D02*
Y-17318D01*
G01X1168870Y-17341D02*
Y-17553D01*
G01X1169016Y-17890D02*
Y-17679D01*
G01X1169428Y-18845D02*
Y-18862D01*
G01X1170437Y-16764D02*
Y-16798D01*
G01X1173094Y-17318D02*
Y-6688D01*
G01Y-1570D02*
Y9060D01*
G01X1173512Y-16904D02*
Y-17116D01*
G01Y-16798D02*
Y-16764D01*
G01X1172724Y-17548D02*
X1172740Y-17396D01*
X1172784Y-17249D01*
X1172856Y-17114D01*
X1172955Y-16994D01*
X1173074Y-16896D01*
X1173209Y-16824D01*
X1173356Y-16779D01*
X1173512Y-16764D01*
G01X1172724Y-17780D02*
X1172740Y-17651D01*
X1172784Y-17527D01*
X1172856Y-17412D01*
X1172955Y-17310D01*
X1173074Y-17228D01*
X1173209Y-17167D01*
X1173356Y-17129D01*
X1173512Y-17116D01*
G01X1172724Y-24077D02*
X1180894D01*
G01Y-23942D02*
X1172724D01*
G01X1180894Y-23756D02*
X1172724D01*
G01Y-23671D02*
X1180894D01*
G01X1172724Y-23348D02*
X1180894D01*
G01Y-23331D02*
X1172724D01*
G01Y-23097D02*
X1180894D01*
G01Y-23063D02*
X1172724D01*
G01X1171177Y-23615D02*
X1171063Y-23331D01*
G01X1169428Y-18862D02*
X1171063Y-23348D01*
G01Y-23331D02*
X1169428Y-18845D01*
G01X1171063Y-23348D02*
X1171177Y-23689D01*
G01D02*
X1171184Y-23711D01*
X1171191Y-23734D01*
X1171197Y-23756D01*
G01Y-23671D02*
X1171191Y-23652D01*
X1171184Y-23633D01*
X1171177Y-23615D01*
G01X1171197Y-23756D02*
X1171205Y-23787D01*
X1171212Y-23821D01*
X1171217Y-23853D01*
X1171221Y-23888D01*
X1171224Y-23923D01*
Y-23958D01*
G01Y-23872D02*
Y-23840D01*
X1171222Y-23805D01*
X1171218Y-23773D01*
X1171213Y-23739D01*
X1171206Y-23705D01*
X1171197Y-23671D01*
G01X1171177Y-23689D02*
Y-23615D01*
G01X1171197Y-23671D02*
Y-23756D01*
G01X1171063Y-23348D02*
Y-23331D01*
G01X1163843Y-16798D02*
X1163690Y-16813D01*
X1163543Y-16857D01*
X1163407Y-16929D01*
X1163286Y-17028D01*
X1163188Y-17146D01*
X1163116Y-17281D01*
X1163071Y-17427D01*
X1163055Y-17582D01*
G01X1149543Y-16798D02*
X1149391Y-16813D01*
X1149243Y-16857D01*
X1149108Y-16929D01*
X1148987Y-17028D01*
X1148889Y-17146D01*
X1148817Y-17281D01*
X1148772Y-17427D01*
X1148756Y-17582D01*
G01X1166150Y-16904D02*
X1165992Y-16918D01*
X1165840Y-16958D01*
X1165701Y-17023D01*
X1165578Y-17112D01*
X1165481Y-17218D01*
X1165410Y-17341D01*
G01X1151851Y-16904D02*
X1151693Y-16918D01*
X1151541Y-16958D01*
X1151402Y-17023D01*
X1151279Y-17112D01*
X1151181Y-17218D01*
X1151111Y-17341D01*
G01X1169428Y-18862D02*
X1164852D01*
G01X1155129D02*
X1150552D01*
G01Y-18845D02*
X1155129D01*
G01X1164852D02*
X1169428D01*
G01X1171224Y-18516D02*
X1163055D01*
G01X1156925D02*
X1148756D01*
G01Y-18481D02*
X1156925D01*
G01X1163055D02*
X1171224D01*
G01Y-18138D02*
X1163055D01*
G01X1156925D02*
X1148756D01*
G01X1163055Y-18104D02*
X1171224D01*
G01X1148756D02*
X1156925D01*
G01X1150965Y-17890D02*
X1154717D01*
G01X1165264D02*
X1169016D01*
G01Y-17679D02*
X1165264D01*
G01X1154717D02*
X1150965D01*
G01X1151807Y-17318D02*
X1146886D01*
G01X1159758Y-17178D02*
X1163618D01*
G01X1151851Y-17116D02*
X1153831D01*
G01X1166150D02*
X1168130D01*
G01Y-16904D02*
X1166150D01*
G01X1153831D02*
X1151851D01*
G01X1149543Y-16798D02*
X1156138D01*
G01X1163843D02*
X1170437D01*
G01Y-16764D02*
X1163843D01*
G01X1156138D02*
X1149543D01*
G01X1159758Y-15934D02*
X1165002D01*
G01X1151807Y-14786D02*
X1146886D01*
G01Y-14307D02*
X1151807D01*
G01X1163618Y-11273D02*
X1159758D01*
G01X1151807Y-9699D02*
X1146886D01*
G01Y-9220D02*
X1151807D01*
G01X1163947Y-8741D02*
X1156034D01*
G01X1165002Y-8060D02*
X1159758D01*
G01X1146886Y-6688D02*
X1151807D01*
G01X1160490Y-2525D02*
X1159490D01*
G01Y-1874D02*
X1160490D01*
G01X1159490Y-1777D02*
X1160490D01*
G01X1151807Y-1570D02*
X1146886D01*
G01X1159490Y-1273D02*
X1160490D01*
G01X1159490Y-1244D02*
X1160490D01*
G01Y-832D02*
X1159490D01*
G01Y153D02*
X1160490D01*
G01X1159490Y560D02*
X1160490D01*
G01X1159490Y590D02*
X1160490D01*
G01X1151807Y962D02*
X1146886D01*
G01X1159490Y1097D02*
X1160490D01*
G01Y1190D02*
X1159490D01*
G01X1146886Y1441D02*
X1151807D01*
G01X1160490Y1845D02*
X1159490D01*
G01X1160490Y3845D02*
X1159490D01*
G01X1160490Y4436D02*
X1159490D01*
G01X1151807Y6049D02*
X1146886D01*
G01X1146469Y-17116D02*
X1146622Y-17128D01*
X1146769Y-17166D01*
X1146904Y-17227D01*
X1147026Y-17310D01*
X1147123Y-17410D01*
X1147196Y-17525D01*
X1147241Y-17649D01*
X1147256Y-17780D01*
G01X1153831Y-17116D02*
X1153989Y-17129D01*
X1154141Y-17170D01*
X1154280Y-17234D01*
X1154403Y-17323D01*
X1154500Y-17430D01*
X1154570Y-17553D01*
G01X1146469Y-16764D02*
X1146622Y-16779D01*
X1146769Y-16823D01*
X1146904Y-16895D01*
X1147026Y-16994D01*
X1147123Y-17112D01*
X1147196Y-17247D01*
X1147241Y-17393D01*
X1147256Y-17548D01*
G01X1156138Y-16764D02*
X1156291Y-16779D01*
X1156438Y-16823D01*
X1156574Y-16895D01*
X1156695Y-16994D01*
X1156792Y-17112D01*
X1156865Y-17247D01*
X1156910Y-17393D01*
X1156925Y-17548D01*
G01X1154570Y-17341D02*
X1154501Y-17220D01*
X1154405Y-17114D01*
X1154285Y-17025D01*
X1154143Y-16959D01*
X1153992Y-16918D01*
X1153831Y-16904D01*
G01X1154717Y-17890D02*
X1154854Y-18195D01*
X1154991Y-18522D01*
X1155129Y-18862D01*
G01X1154570Y-17553D02*
X1154717Y-17890D01*
G01Y-17679D02*
X1154570Y-17341D01*
G01X1155109Y-14327D02*
X1157866Y-21902D01*
G01X1155129Y-18845D02*
X1154991Y-18437D01*
X1154854Y-18044D01*
X1154717Y-17679D01*
G01X1147256Y-17582D02*
X1147241Y-17430D01*
X1147197Y-17284D01*
X1147124Y-17149D01*
X1147026Y-17028D01*
X1146907Y-16931D01*
X1146771Y-16858D01*
X1146624Y-16814D01*
X1146469Y-16798D01*
G01X1156925Y-17582D02*
X1156910Y-17430D01*
X1156866Y-17284D01*
X1156794Y-17149D01*
X1156695Y-17028D01*
X1156576Y-16931D01*
X1156441Y-16858D01*
X1156294Y-16814D01*
X1156138Y-16798D01*
G01X1147256Y-17568D02*
X1147241Y-17439D01*
X1147197Y-17315D01*
X1147124Y-17201D01*
X1147026Y-17099D01*
X1146907Y-17016D01*
X1146771Y-16955D01*
X1146624Y-16917D01*
X1146469Y-16904D01*
G01Y-16764D02*
Y-16798D01*
G01Y-17116D02*
Y-16904D01*
G01X1146886Y9060D02*
Y-1570D01*
G01Y-6688D02*
Y-17318D01*
G01X1149543Y-16798D02*
Y-16764D01*
G01X1150552Y-18862D02*
Y-18845D01*
G01X1150965Y-17679D02*
Y-17890D01*
G01X1151111Y-17553D02*
Y-17341D01*
G01X1151807Y-17318D02*
Y-6688D01*
G01Y-1570D02*
Y9060D01*
G01X1151851Y-16904D02*
Y-17116D01*
G01X1153831D02*
Y-16904D01*
G01X1154570Y-17341D02*
Y-17553D01*
G01X1154717Y-17890D02*
Y-17679D01*
G01X1155050Y-9725D02*
Y-13990D01*
G01X1155129Y-18845D02*
Y-18862D01*
G01X1156138Y-16764D02*
Y-16798D01*
G01X1159758Y-8060D02*
Y-17178D01*
G01X1160495Y31917D02*
X1160497Y-6351D01*
G01X1160508Y-14225D02*
Y-6351D01*
G01X1161490Y-15934D02*
Y-8060D01*
G01X1161494Y-11273D02*
Y-17178D01*
G01X1163843Y-16798D02*
Y-16764D01*
G01X1164618Y-12273D02*
Y-16178D01*
G01X1164852Y-18862D02*
Y-18845D01*
G01X1164931Y-9725D02*
Y-13990D01*
G01X1165264Y-17679D02*
Y-17890D01*
G01X1165410Y-17553D02*
Y-17341D01*
G01X1166002Y-9060D02*
Y-14934D01*
G01X1166150Y-16904D02*
Y-17116D01*
G01X1148756Y-17548D02*
X1148771Y-17396D01*
X1148815Y-17249D01*
X1148888Y-17114D01*
X1148987Y-16994D01*
X1149106Y-16896D01*
X1149241Y-16824D01*
X1149388Y-16779D01*
X1149543Y-16764D01*
G01X1163055Y-17548D02*
X1163070Y-17396D01*
X1163115Y-17249D01*
X1163187Y-17114D01*
X1163286Y-16994D01*
X1163405Y-16896D01*
X1163540Y-16824D01*
X1163687Y-16779D01*
X1163843Y-16764D01*
G01X1164872Y-14327D02*
X1162115Y-21902D01*
G01X1150965Y-17679D02*
X1150828Y-18044D01*
X1150690Y-18437D01*
X1150552Y-18845D01*
G01Y-18862D02*
X1150690Y-18522D01*
X1150828Y-18195D01*
X1150965Y-17890D01*
G01X1165264Y-17679D02*
X1165127Y-18044D01*
X1164989Y-18437D01*
X1164852Y-18845D01*
G01Y-18862D02*
X1164989Y-18522D01*
X1165127Y-18195D01*
X1165264Y-17890D01*
G01X1151111Y-17341D02*
X1150965Y-17679D01*
G01Y-17890D02*
X1151111Y-17553D01*
G01X1165410Y-17341D02*
X1165264Y-17679D01*
G01Y-17890D02*
X1165410Y-17553D01*
G01X1151111D02*
X1151180Y-17432D01*
X1151277Y-17325D01*
X1151397Y-17237D01*
X1151538Y-17170D01*
X1151690Y-17130D01*
X1151851Y-17116D01*
G01X1165410Y-17553D02*
X1165480Y-17432D01*
X1165576Y-17325D01*
X1165696Y-17237D01*
X1165837Y-17170D01*
X1165989Y-17130D01*
X1166150Y-17116D01*
G01X1164618Y-12273D02*
G03X1163618Y-11273I-1000J0D01*
G01Y-17178D02*
G03X1164618Y-16178I0J1000D01*
G01X1165002Y-15934D02*
G03X1166002Y-14934I0J1000D01*
G01Y-9060D02*
G03X1165002Y-8060I-1000J0D01*
G01X1162115Y-21902D02*
G03X1162055Y-22238I924J-338D01*
G01X1164872Y-14327D02*
G03X1164931Y-13990I-925J336D01*
G01Y-9725D02*
G03X1163947Y-8741I-984J0D01*
G01X1156034D02*
G03X1155050Y-9725I0J-984D01*
G01Y-13990D02*
G03X1155109Y-14327I984J-1D01*
G01X1157925Y-22238D02*
G03X1157866Y-21902I-984J0D01*
G01X1148756Y-24077D02*
X1156925D01*
G01X1163055D02*
X1171224D01*
G01Y-23942D02*
X1163055D01*
G01X1156925D02*
X1148756D01*
G01X1171197Y-23756D02*
X1163083D01*
G01X1156898D02*
X1148783D01*
G01Y-23671D02*
X1156898D01*
G01X1163083D02*
X1171197D01*
G01X1148918Y-23348D02*
X1156763D01*
G01X1163217D02*
X1171063D01*
G01Y-23331D02*
X1163217D01*
G01X1156763D02*
X1148918D01*
G01X1148756Y-23097D02*
X1156925D01*
G01X1163055D02*
X1171224D01*
G01X1160490Y-23095D02*
X1202797D01*
G01X1171224Y-23063D02*
X1163055D01*
G01X1156925D02*
X1148756D01*
G01X1202797Y-22468D02*
X1160490D01*
G01X1156878Y-23615D02*
X1156763Y-23331D01*
G01X1155129Y-18862D02*
X1156763Y-23348D01*
G01Y-23331D02*
X1155129Y-18845D01*
G01X1156763Y-23348D02*
X1156878Y-23689D01*
G01D02*
X1156885Y-23711D01*
X1156892Y-23734D01*
X1156898Y-23756D01*
G01Y-23671D02*
X1156892Y-23652D01*
X1156885Y-23633D01*
X1156878Y-23615D01*
G01X1156898Y-23756D02*
X1156906Y-23787D01*
X1156913Y-23821D01*
X1156918Y-23853D01*
X1156922Y-23888D01*
X1156924Y-23923D01*
X1156925Y-23958D01*
G01Y-23872D02*
Y-23840D01*
X1156922Y-23805D01*
X1156919Y-23773D01*
X1156913Y-23739D01*
X1156906Y-23705D01*
X1156898Y-23671D01*
G01X1148783Y-23756D02*
Y-23671D01*
G01X1148804Y-23615D02*
Y-23689D01*
G01X1148918Y-23331D02*
Y-23339D01*
G01D02*
Y-23348D01*
G01X1156878Y-23689D02*
Y-23615D01*
G01X1156898Y-23671D02*
Y-23756D01*
G01X1163083D02*
Y-23671D01*
G01X1163103Y-23615D02*
Y-23689D01*
G01X1163217Y-23331D02*
Y-23339D01*
G01D02*
Y-23348D01*
G01X1156763D02*
Y-23331D01*
G01X1148756Y-23958D02*
X1148757Y-23925D01*
X1148759Y-23891D01*
X1148763Y-23858D01*
X1148768Y-23824D01*
X1148775Y-23790D01*
X1148783Y-23756D01*
G01X1163055Y-23958D02*
X1163056Y-23925D01*
X1163058Y-23891D01*
X1163062Y-23858D01*
X1163067Y-23824D01*
X1163074Y-23790D01*
X1163083Y-23756D01*
G01X1148783Y-23671D02*
X1148776Y-23702D01*
X1148769Y-23736D01*
X1148763Y-23768D01*
X1148759Y-23803D01*
X1148757Y-23838D01*
X1148756Y-23872D01*
G01X1163083Y-23671D02*
X1163075Y-23702D01*
X1163068Y-23736D01*
X1163063Y-23768D01*
X1163059Y-23803D01*
X1163056Y-23838D01*
X1163055Y-23872D01*
G01X1148783Y-23756D02*
X1148790Y-23734D01*
X1148796Y-23711D01*
X1148804Y-23689D01*
G01X1163083Y-23756D02*
X1163089Y-23734D01*
X1163096Y-23711D01*
X1163103Y-23689D01*
G01X1148804D02*
X1148918Y-23348D01*
G01X1163103Y-23689D02*
X1163217Y-23348D01*
G01X1150552Y-18845D02*
X1148918Y-23331D01*
G01Y-23348D02*
X1150552Y-18862D01*
G01X1148804Y-23615D02*
X1148796Y-23633D01*
X1148790Y-23652D01*
X1148783Y-23671D01*
G01X1148918Y-23331D02*
X1148804Y-23615D01*
G01X1164852Y-18845D02*
X1163217Y-23331D01*
G01Y-23348D02*
X1164852Y-18862D01*
G01X1163103Y-23615D02*
X1163096Y-23633D01*
X1163089Y-23652D01*
X1163083Y-23671D01*
G01X1163217Y-23331D02*
X1163103Y-23615D01*
G01X1172109Y38588D02*
X1171828Y38547D01*
X1171595Y38441D01*
X1171433Y38279D01*
X1171376Y38088D01*
G01X1172412Y18393D02*
X1173112D01*
G01X1169459D02*
X1170159D01*
G01X1175364D02*
X1176064D01*
G01Y21371D02*
X1175364D01*
G01X1173112D02*
X1172412D01*
G01X1170159D02*
X1169459D01*
G01X1176064Y24336D02*
X1175364D01*
G01X1173112D02*
X1172412D01*
G01X1170159D02*
X1169459D01*
G01X1176064Y24561D02*
X1175364D01*
G01X1173112D02*
X1172412D01*
G01X1170159D02*
X1169459D01*
G01X1189831Y35857D02*
X1173408D01*
G01X1173770Y37588D02*
X1171876D01*
G01X1171743Y38588D02*
X1176211D01*
G01X1175518Y39032D02*
X1175491D01*
G01X1173376Y39392D02*
X1171407D01*
G01X1178382Y29645D02*
X1173770Y34257D01*
G01X1169459Y24561D02*
Y18393D01*
G01X1170159Y24561D02*
Y18393D01*
G01X1171376Y43930D02*
Y38088D01*
G01X1171407Y44408D02*
Y36767D01*
G01X1172376Y43930D02*
Y38588D01*
G01X1172412Y24561D02*
Y18393D01*
G01X1173112Y24561D02*
Y18393D01*
G01X1173376Y44408D02*
Y36767D01*
G01X1173626Y43930D02*
Y38588D01*
G01X1173770Y34257D02*
Y40780D01*
G01X1174652Y44408D02*
Y36569D01*
G01X1174793Y44408D02*
Y37242D01*
G01X1175364Y24561D02*
Y18393D01*
G01X1175491Y37940D02*
Y44408D01*
G01X1175518Y38069D02*
Y44408D01*
G01X1176064Y24561D02*
Y18393D01*
G01X1176801Y43339D02*
Y39178D01*
G01X1171376Y38088D02*
X1171407Y38288D01*
X1171491Y38447D01*
X1171610Y38552D01*
X1171743Y38588D01*
G01X1174454Y36767D02*
X1173588Y35267D01*
G01X1174652Y36569D02*
X1175518Y38069D01*
G01X1174454Y36767D02*
X1175518Y38069D01*
G01X1173588Y35267D02*
X1174652Y36569D01*
G01X1178470Y41985D02*
X1175518Y39032D01*
G01X1175491Y37940D02*
X1173408Y35857D01*
G01X1176211Y38588D02*
G03X1176801Y39178I0J590D01*
G01X1171376Y38088D02*
G03X1171876Y37588I500J0D01*
G01X1168173Y6528D02*
X1173094D01*
G01X1168173Y9060D02*
X1173094D01*
G01X1199238Y12019D02*
X1164002D01*
G01X1197073Y14955D02*
X1166167D01*
G01X1165002Y18242D02*
X1159758D01*
G01X1143869Y18393D02*
X1144569D01*
G01X1146821D02*
X1147521D01*
G01X1149774D02*
X1150474D01*
G01X1147521Y21371D02*
X1146821D01*
G01X1150474D02*
X1149774D01*
G01X1144569D02*
X1143869D01*
G01X1147521Y24336D02*
X1146821D01*
G01X1150474D02*
X1149774D01*
G01X1144569D02*
X1143869D01*
G01X1147521Y24561D02*
X1146821D01*
G01X1150474D02*
X1149774D01*
G01X1144569D02*
X1143869D01*
G01X1159758Y26116D02*
X1165002D01*
G01X1160683Y31917D02*
X1160490D01*
G01X1166167Y34353D02*
X1197073D01*
G01Y35141D02*
X1166167D01*
G01X1199238Y35267D02*
X1164002D01*
G01X1174454Y36767D02*
X1164002D01*
G01X1155931D02*
X1145478D01*
G01X1148104Y37588D02*
X1146211D01*
G01X1143770Y38588D02*
X1148238D01*
G01X1159758Y38853D02*
X1163618D01*
G01X1144442Y39032D02*
X1144415D01*
G01X1160490Y39791D02*
X1160683D01*
G01X1148238Y38588D02*
X1148371Y38552D01*
X1148490Y38447D01*
X1148573Y38288D01*
X1148604Y38088D01*
G01X1146524Y35857D02*
X1144442Y37940D01*
G01X1145281Y36569D02*
X1146344Y35267D01*
G01X1144415Y38069D02*
X1145478Y36767D01*
G01X1144415Y38069D02*
X1145281Y36569D01*
G01X1146344Y35267D02*
X1145478Y36767D01*
G01X1148604Y38088D02*
X1148594Y38173D01*
X1148559Y38258D01*
X1148501Y38341D01*
X1148419Y38418D01*
X1148313Y38484D01*
X1148184Y38538D01*
X1148036Y38574D01*
X1147872Y38588D01*
G01X1143869Y24561D02*
Y18393D01*
G01X1144415Y44408D02*
Y38069D01*
G01X1144442Y44408D02*
Y37940D01*
G01X1144569Y24561D02*
Y18393D01*
G01X1145140Y44408D02*
Y37242D01*
G01X1145281Y36569D02*
Y44408D01*
G01X1146211Y40780D02*
Y34257D01*
G01X1146354Y43930D02*
Y38588D01*
G01X1146604Y44408D02*
Y38588D01*
G01X1146821Y24561D02*
Y18393D01*
G01X1147521Y24561D02*
Y18393D01*
G01X1147604Y43930D02*
Y38588D01*
G01X1148573Y36767D02*
Y44408D01*
G01X1148604Y43930D02*
Y38088D01*
G01X1149774Y24561D02*
Y18393D01*
G01X1150474Y24561D02*
Y18393D01*
G01X1153766Y35141D02*
Y14955D01*
G01X1159758Y26116D02*
Y18242D01*
G01Y38853D02*
Y44759D01*
G01X1160683Y31917D02*
Y39791D01*
G01X1161490Y44759D02*
Y38853D01*
G01Y18242D02*
Y26116D01*
G01X1164618Y43759D02*
Y39853D01*
G01X1166002Y19242D02*
Y25116D01*
G01X1166167Y35141D02*
Y14955D01*
G01X1165002Y18242D02*
G03X1166002Y19242I0J1000D01*
G01Y25116D02*
G03X1165002Y26116I-1000J0D01*
G01X1148104Y37588D02*
G03X1148604Y38088I0J500D01*
G01X1163618Y38853D02*
G03X1164618Y39853I0J1000D01*
G01X1146886Y6528D02*
X1151807D01*
G01X1159490Y6877D02*
X1160490D01*
G01Y7468D02*
X1159490D01*
G01X1146886Y9060D02*
X1151807D01*
G01X1164002Y11019D02*
X1199238D01*
G01X1153766Y14955D02*
X1154947Y11019D01*
G01X1153766Y14955D02*
X1154947Y11019D01*
G01X1155931D02*
Y44408D01*
G01X1164002D02*
Y11019D01*
G01X1166167Y14955D02*
X1164986Y11019D01*
G01X1166167Y14955D02*
X1164986Y11019D01*
G01X1169966Y54560D02*
X1169900Y54546D01*
G01X1186541Y45528D02*
X1176699D01*
G01X1186541Y46512D02*
X1176699D01*
G01X1172412Y48355D02*
X1173112D01*
G01Y48571D02*
X1172412D01*
G01X1173112Y48667D02*
X1172412D01*
G01X1173112Y48729D02*
X1172412D01*
G01X1173112Y48827D02*
X1172412D01*
G01X1173112Y49812D02*
X1172412D01*
G01X1173112Y49910D02*
X1172412D01*
G01X1173112Y49973D02*
X1172412D01*
G01X1173112Y50068D02*
X1172412D01*
G01Y50284D02*
X1173112D01*
G01X1175364Y51111D02*
X1176064D01*
G01Y51327D02*
X1175364D01*
G01X1176064Y51423D02*
X1175364D01*
G01X1176064Y51485D02*
X1175364D01*
G01X1176064Y51583D02*
X1175364D01*
G01X1176065Y52568D02*
X1175365D01*
G01X1176064Y52666D02*
X1175364D01*
G01X1176064Y52729D02*
X1175364D01*
G01X1176064Y52823D02*
X1175364D01*
G01Y53040D02*
X1176064D01*
G01X1170159Y53867D02*
X1169459D01*
G01Y54083D02*
X1170159D01*
G01X1169459Y54179D02*
X1170159D01*
G01X1169459Y54241D02*
X1170159D01*
G01Y54339D02*
X1169459D01*
G01X1169900Y54546D02*
X1169585D01*
G01X1170255D02*
X1170176D01*
G01X1170701D02*
X1170622D01*
G01X1170963D02*
X1170885D01*
G01X1169913Y54627D02*
X1169664D01*
G01X1170570Y54707D02*
X1170307D01*
G01X1170557Y54761D02*
X1170320D01*
G01X1169664Y54828D02*
X1169913D01*
G01X1169664Y54908D02*
X1169913D01*
G01Y55096D02*
X1169664D01*
G01X1169585Y55176D02*
X1169900D01*
G01X1170386D02*
X1170491D01*
G01X1170885D02*
X1170963D01*
G01X1170159Y55323D02*
X1169459D01*
G01X1170159Y55422D02*
X1169459D01*
G01Y55484D02*
X1170159D01*
G01X1169459Y55579D02*
X1170159D01*
G01Y55796D02*
X1169459D01*
G01X1172412Y63316D02*
X1173112D01*
G01Y63532D02*
X1172412D01*
G01X1173112Y63627D02*
X1172412D01*
G01X1173112Y63690D02*
X1172412D01*
G01X1173112Y63788D02*
X1172412D01*
G01X1173112Y64772D02*
X1172412D01*
G01X1173112Y64871D02*
X1172412D01*
G01X1173112Y64933D02*
X1172412D01*
G01X1173112Y65028D02*
X1172412D01*
G01Y65245D02*
X1173112D01*
G01X1175364Y66071D02*
X1176064D01*
G01Y66288D02*
X1175364D01*
G01X1176064Y66383D02*
X1175364D01*
G01X1176064Y66445D02*
X1175364D01*
G01X1176064Y66544D02*
X1175364D01*
G01X1176065Y67528D02*
X1175365D01*
G01X1176064Y67627D02*
X1175364D01*
G01X1176064Y67689D02*
X1175364D01*
G01X1176064Y67784D02*
X1175364D01*
G01Y68001D02*
X1176064D01*
G01X1170159Y68827D02*
X1169459D01*
G01Y69044D02*
X1170159D01*
G01X1169459Y69139D02*
X1170159D01*
G01X1169459Y69201D02*
X1170159D01*
G01Y69300D02*
X1169459D01*
G01X1170159Y70284D02*
X1169459D01*
G01X1170159Y70382D02*
X1169459D01*
G01Y70445D02*
X1170159D01*
G01Y70540D02*
X1169459D01*
G01X1170159Y70756D02*
X1169459D01*
G01X1169900Y55176D02*
X1169966Y55163D01*
G01X1169913Y54828D02*
X1169953Y54814D01*
G01Y55082D02*
X1169913Y55096D01*
G01X1169992Y54868D02*
X1170019Y54855D01*
G01X1169966Y55163D02*
X1170019Y55123D01*
G01X1169953Y54814D02*
X1169979Y54788D01*
G01Y55056D02*
X1169953Y55082D01*
G01X1170019Y54855D02*
X1170058Y54801D01*
G01X1170019Y55123D02*
X1170058Y55069D01*
G01X1170491Y55176D02*
X1170701Y54546D01*
G01X1169979Y54788D02*
X1169992Y54747D01*
G01X1170058Y54801D02*
X1170071Y54761D01*
G01X1169992Y55015D02*
X1169979Y55056D01*
G01X1170058Y55069D02*
X1170071Y55029D01*
G01X1170622Y54546D02*
X1170570Y54707D01*
G01X1170439Y55123D02*
X1170557Y54761D01*
G01X1169459Y53868D02*
Y55794D01*
G01Y68829D02*
Y70755D01*
G01X1169585Y54546D02*
Y55176D01*
G01X1169664Y55096D02*
Y54908D01*
G01Y54627D02*
Y54828D01*
G01X1169992Y54747D02*
Y54707D01*
G01Y54988D02*
Y55015D01*
G01X1170071Y55029D02*
Y54975D01*
G01Y54761D02*
Y54693D01*
G01X1170159Y53869D02*
Y55795D01*
G01Y68829D02*
Y70755D01*
G01X1170806Y54975D02*
Y55082D01*
G01X1170885Y54546D02*
Y55069D01*
G01X1170963Y55176D02*
Y54546D01*
G01X1172412Y48356D02*
Y50282D01*
G01Y63317D02*
Y65243D01*
G01X1173112Y48357D02*
Y50283D01*
G01Y63318D02*
Y65243D01*
G01X1175364Y51112D02*
Y53038D01*
G01Y66073D02*
Y67999D01*
G01X1176064Y51113D02*
Y53039D01*
G01Y66073D02*
Y67999D01*
G01X1169913Y54908D02*
X1169953Y54921D01*
G01Y54640D02*
X1169913Y54627D01*
G01X1169979Y54948D02*
X1169992Y54988D01*
G01X1170071Y54975D02*
X1170058Y54935D01*
G01X1169992Y54707D02*
X1169979Y54667D01*
G01X1170071Y54693D02*
X1170058Y54653D01*
G01X1170320Y54761D02*
X1170439Y55123D01*
G01X1170307Y54707D02*
X1170255Y54546D01*
G01X1170176D02*
X1170386Y55176D01*
G01X1170019Y54600D02*
X1169966Y54560D01*
G01X1170019Y54881D02*
X1169992Y54868D01*
G01X1170058Y54935D02*
X1170019Y54881D01*
G01X1170058Y54653D02*
X1170019Y54600D01*
G01X1170806Y55082D02*
X1170885Y55176D01*
G01Y55069D02*
X1170806Y54975D01*
G01X1169953Y54921D02*
X1169979Y54948D01*
G01Y54667D02*
X1169953Y54640D01*
G01X1173376Y41062D02*
X1171407D01*
G01X1176699Y46512D02*
Y44408D01*
G01X1178382Y45393D02*
X1173770Y40780D01*
G01X1176801Y43339D02*
G03X1176211Y43930I-591J0D01*
G01X1160490Y45223D02*
X1159490D01*
G01Y46475D02*
X1160490D01*
G01Y47182D02*
X1159490D01*
G01X1146821Y48355D02*
X1147521D01*
G01Y48571D02*
X1146821D01*
G01X1147521Y48667D02*
X1146821D01*
G01X1147521Y48729D02*
X1146821D01*
G01X1147521Y48827D02*
X1146821D01*
G01X1147521Y49812D02*
X1146821D01*
G01X1147521Y49910D02*
X1146821D01*
G01X1147521Y49973D02*
X1146821D01*
G01X1147521Y50068D02*
X1146821D01*
G01Y50284D02*
X1147521D01*
G01X1159490Y50541D02*
X1160490D01*
G01X1159490Y50638D02*
X1160490D01*
G01X1149774Y51111D02*
X1150474D01*
G01X1159490Y51142D02*
X1160490D01*
G01X1159490Y51171D02*
X1160490D01*
G01X1150474Y51327D02*
X1149774D01*
G01X1150474Y51423D02*
X1149774D01*
G01X1150474Y51485D02*
X1149774D01*
G01X1150474Y51583D02*
X1149774D01*
G01X1160490D02*
X1159490D01*
G01X1150474Y52568D02*
X1149774D01*
G01X1159490D02*
X1160490D01*
G01X1150474Y52666D02*
X1149774D01*
G01X1150474Y52729D02*
X1149774D01*
G01X1150474Y52823D02*
X1149774D01*
G01X1159490Y52975D02*
X1160490D01*
G01X1159490Y53005D02*
X1160490D01*
G01X1149774Y53040D02*
X1150474D01*
G01X1159490Y53512D02*
X1160490D01*
G01Y53605D02*
X1159490D01*
G01X1144569Y53867D02*
X1143869D01*
G01Y54083D02*
X1144569D01*
G01X1143869Y54179D02*
X1144569D01*
G01X1143869Y54241D02*
X1144569D01*
G01X1160490Y54260D02*
X1159490D01*
G01X1160490Y54275D02*
X1159490D01*
G01X1144569Y54339D02*
X1143869D01*
G01X1144569Y55323D02*
X1143869D01*
G01X1144569Y55422D02*
X1143869D01*
G01Y55484D02*
X1144569D01*
G01X1143869Y55579D02*
X1144569D01*
G01Y55796D02*
X1143869D01*
G01X1160490Y56275D02*
X1155970D01*
G01X1146821Y63316D02*
X1147521D01*
G01Y63532D02*
X1146821D01*
G01X1147521Y63627D02*
X1146821D01*
G01X1147521Y63690D02*
X1146821D01*
G01X1147521Y63788D02*
X1146821D01*
G01X1147521Y64772D02*
X1146821D01*
G01X1147521Y64871D02*
X1146821D01*
G01X1147521Y64933D02*
X1146821D01*
G01X1147521Y65028D02*
X1146821D01*
G01Y65245D02*
X1147521D01*
G01X1155970Y66043D02*
X1160490D01*
G01X1149774Y66071D02*
X1150474D01*
G01Y66288D02*
X1149774D01*
G01X1150474Y66383D02*
X1149774D01*
G01X1150474Y66445D02*
X1149774D01*
G01X1150474Y66544D02*
X1149774D01*
G01X1150474Y67528D02*
X1149774D01*
G01X1150474Y67627D02*
X1149774D01*
G01X1150474Y67689D02*
X1149774D01*
G01X1150474Y67784D02*
X1149774D01*
G01Y68001D02*
X1150474D01*
G01X1164010Y68043D02*
X1159490D01*
G01X1144569Y68827D02*
X1143869D01*
G01Y69044D02*
X1144569D01*
G01X1143869Y69139D02*
X1144569D01*
G01X1143869Y69201D02*
X1144569D01*
G01Y69300D02*
X1143869D01*
G01X1144569Y70284D02*
X1143869D01*
G01X1144569Y70382D02*
X1143869D01*
G01Y70445D02*
X1144569D01*
G01Y70540D02*
X1143869D01*
G01X1144569Y70756D02*
X1143869D01*
G01Y53868D02*
Y55794D01*
G01Y68829D02*
Y70755D01*
G01X1144569Y53869D02*
Y55795D01*
G01Y68829D02*
Y70755D01*
G01X1146821Y48356D02*
Y50282D01*
G01Y63317D02*
Y65243D01*
G01X1147521Y48357D02*
Y50283D01*
G01Y63318D02*
Y65243D01*
G01X1149774Y51112D02*
Y53038D01*
G01Y66073D02*
Y67999D01*
G01X1150474Y51113D02*
Y53039D01*
G01Y66073D02*
Y67999D01*
G01X1154970Y65043D02*
Y57275D01*
G01X1156506Y66043D02*
Y86182D01*
G01X1156843Y66043D02*
Y56275D01*
G01X1158490Y66043D02*
Y56275D01*
G01X1159285D02*
Y66043D01*
G01X1160695Y77812D02*
Y68043D01*
G01X1161490D02*
Y77812D01*
G01X1163089Y68043D02*
Y77812D01*
G01X1165010Y76812D02*
Y69043D01*
G01X1154970Y57275D02*
G03X1155970Y56275I1000J0D01*
G01Y66043D02*
G03X1154970Y65043I0J-1000D01*
G01X1164010Y68043D02*
G03X1165010Y69043I0J1000D01*
G01X1162427Y44408D02*
X1200813D01*
G01X1159490Y44516D02*
X1160490D01*
G01X1159758Y44759D02*
X1163618D01*
G01X1143234Y46512D02*
Y44408D01*
G01X1154465Y105171D02*
Y44408D01*
G01X1155878Y105171D02*
Y44408D01*
G01X1156506D02*
Y56275D01*
G01X1157506Y44408D02*
Y105171D01*
G01X1162427D02*
Y44408D01*
G01X1163427D02*
Y68043D01*
G01X1164055Y105171D02*
Y44408D01*
G01X1165469Y105171D02*
Y44408D01*
G01X1164618Y43759D02*
G03X1163618Y44759I-1000J0D01*
G01X1173112Y79733D02*
X1172412D01*
G01X1173112Y79831D02*
X1172412D01*
G01X1173112Y79894D02*
X1172412D01*
G01X1173112Y79989D02*
X1172412D01*
G01Y80205D02*
X1173112D01*
G01X1175364Y81032D02*
X1176064D01*
G01Y81249D02*
X1175364D01*
G01X1176064Y81344D02*
X1175364D01*
G01X1176064Y81406D02*
X1175364D01*
G01X1176064Y81505D02*
X1175364D01*
G01X1176065Y82489D02*
X1175365D01*
G01X1176064Y82587D02*
X1175364D01*
G01X1176064Y82650D02*
X1175364D01*
G01X1176064Y82745D02*
X1175364D01*
G01Y82961D02*
X1176064D01*
G01X1170159Y83788D02*
X1169459D01*
G01Y84005D02*
X1170159D01*
G01X1169459Y84100D02*
X1170159D01*
G01X1169459Y84162D02*
X1170159D01*
G01Y84260D02*
X1169459D01*
G01X1170159Y85245D02*
X1169459D01*
G01X1170159Y85343D02*
X1169459D01*
G01Y85406D02*
X1170159D01*
G01Y85501D02*
X1169459D01*
G01X1170159Y85717D02*
X1169459D01*
G01X1172412Y93237D02*
X1173112D01*
G01Y93453D02*
X1172412D01*
G01X1173112Y93549D02*
X1172412D01*
G01X1173112Y93611D02*
X1172412D01*
G01X1173112Y93709D02*
X1172412D01*
G01X1173112Y94693D02*
X1172412D01*
G01X1173112Y94792D02*
X1172412D01*
G01X1173112Y94855D02*
X1172412D01*
G01X1173112Y94949D02*
X1172412D01*
G01Y95166D02*
X1173112D01*
G01X1175364Y95993D02*
X1176064D01*
G01Y96209D02*
X1175364D01*
G01X1176064Y96305D02*
X1175364D01*
G01X1176064Y96367D02*
X1175364D01*
G01X1176064Y96465D02*
X1175364D01*
G01X1176065Y97449D02*
X1175365D01*
G01X1176064Y97548D02*
X1175364D01*
G01X1176064Y97610D02*
X1175364D01*
G01X1176064Y97705D02*
X1175364D01*
G01Y97922D02*
X1176064D01*
G01X1170159Y98749D02*
X1169459D01*
G01Y98965D02*
X1170159D01*
G01X1169459Y99060D02*
X1170159D01*
G01X1169459Y99123D02*
X1170159D01*
G01Y99221D02*
X1169459D01*
G01X1170159Y100205D02*
X1169459D01*
G01X1170159Y100304D02*
X1169459D01*
G01Y100366D02*
X1170159D01*
G01Y100461D02*
X1169459D01*
G01X1170159Y100678D02*
X1169459D01*
G01X1168234Y102336D02*
X1195006D01*
G01X1168014Y105958D02*
Y106958D01*
G01X1168234Y105171D02*
Y102336D01*
G01X1169014Y106958D02*
Y105958D01*
G01X1169459Y83790D02*
Y85716D01*
G01Y98750D02*
Y100676D01*
G01X1170159Y83790D02*
Y85716D01*
G01Y98751D02*
Y100677D01*
G01X1171010Y106958D02*
Y105958D01*
G01X1171014Y105171D02*
Y106958D01*
G01X1172030D02*
Y105958D01*
G01X1172412Y93238D02*
Y95164D01*
G01X1173112Y93239D02*
Y95165D01*
G01X1173373Y105958D02*
Y106958D01*
G01X1174185D02*
Y105958D01*
G01X1174278D02*
Y106958D01*
G01X1174763Y105958D02*
Y106958D01*
G01X1174815Y105958D02*
Y106958D01*
G01X1175222Y105958D02*
Y106958D01*
G01X1175364Y81034D02*
Y82960D01*
G01Y95994D02*
Y97920D01*
G01X1176064Y81034D02*
Y82960D01*
G01Y95995D02*
Y97921D01*
G01X1176207Y106958D02*
Y105958D01*
G01X1176619D02*
Y106958D01*
G01X1176670Y105958D02*
Y106958D01*
G01X1172412Y78276D02*
X1173112D01*
G01Y78493D02*
X1172412D01*
G01X1173112Y78588D02*
X1172412D01*
G01X1173112Y78650D02*
X1172412D01*
G01X1173112Y78749D02*
X1172412D01*
G01Y78278D02*
Y80204D01*
G01X1173112Y78278D02*
Y80204D01*
G01X1147521Y79733D02*
X1146821D01*
G01X1147521Y79831D02*
X1146821D01*
G01X1147521Y79894D02*
X1146821D01*
G01X1147521Y79989D02*
X1146821D01*
G01Y80205D02*
X1147521D01*
G01X1149774Y81032D02*
X1150474D01*
G01Y81249D02*
X1149774D01*
G01X1150474Y81344D02*
X1149774D01*
G01X1150474Y81406D02*
X1149774D01*
G01X1150474Y81505D02*
X1149774D01*
G01X1150474Y82489D02*
X1149774D01*
G01X1150474Y82587D02*
X1149774D01*
G01X1150474Y82650D02*
X1149774D01*
G01X1150474Y82745D02*
X1149774D01*
G01Y82961D02*
X1150474D01*
G01X1144569Y83788D02*
X1143869D01*
G01Y84005D02*
X1144569D01*
G01X1143869Y84100D02*
X1144569D01*
G01X1143869Y84162D02*
X1144569D01*
G01Y84260D02*
X1143869D01*
G01X1159490Y85182D02*
X1160490D01*
G01X1144569Y85245D02*
X1143869D01*
G01X1144569Y85343D02*
X1143869D01*
G01Y85406D02*
X1144569D01*
G01Y85501D02*
X1143869D01*
G01X1144569Y85717D02*
X1143869D01*
G01X1160490Y86182D02*
X1155970D01*
G01X1159758Y91636D02*
X1163618D01*
G01X1146821Y93237D02*
X1147521D01*
G01Y93453D02*
X1146821D01*
G01X1147521Y93549D02*
X1146821D01*
G01X1147521Y93611D02*
X1146821D01*
G01X1147521Y93709D02*
X1146821D01*
G01X1155970Y94578D02*
X1160490D01*
G01X1147521Y94693D02*
X1146821D01*
G01X1147521Y94792D02*
X1146821D01*
G01X1147521Y94855D02*
X1146821D01*
G01X1147521Y94949D02*
X1146821D01*
G01Y95166D02*
X1147521D01*
G01X1149774Y95993D02*
X1150474D01*
G01Y96209D02*
X1149774D01*
G01X1150474Y96305D02*
X1149774D01*
G01X1150474Y96367D02*
X1149774D01*
G01X1150474Y96465D02*
X1149774D01*
G01X1164010Y96578D02*
X1159490D01*
G01X1150474Y97449D02*
X1149774D01*
G01X1163618Y97542D02*
X1159758D01*
G01X1150474Y97548D02*
X1149774D01*
G01X1150474Y97610D02*
X1149774D01*
G01X1150474Y97705D02*
X1149774D01*
G01Y97922D02*
X1150474D01*
G01X1144569Y98749D02*
X1143869D01*
G01Y98965D02*
X1144569D01*
G01X1143869Y99060D02*
X1144569D01*
G01X1143869Y99123D02*
X1144569D01*
G01Y99221D02*
X1143869D01*
G01X1144569Y100205D02*
X1143869D01*
G01X1144569Y100304D02*
X1143869D01*
G01Y100366D02*
X1144569D01*
G01Y100461D02*
X1143869D01*
G01X1144569Y100678D02*
X1143869D01*
G01X1159490Y103048D02*
X1160490D01*
G01Y103974D02*
X1159490D01*
G01X1160490Y104974D02*
X1159490D01*
G01X1159671Y105169D02*
X1160262D01*
G01X1143869Y83790D02*
Y85716D01*
G01Y98750D02*
Y100676D01*
G01X1144569Y83790D02*
Y85716D01*
G01Y98751D02*
Y100677D01*
G01X1145793Y105171D02*
Y102336D01*
G01X1146439Y106958D02*
Y105958D01*
G01X1146821Y93238D02*
Y95164D01*
G01X1147171Y105171D02*
Y102336D01*
G01X1147521Y93239D02*
Y95165D01*
G01X1147939Y105958D02*
Y106958D01*
G01X1148594D02*
Y105958D01*
G01X1148687D02*
Y106958D01*
G01X1148947D02*
Y105958D01*
G01X1148951Y105171D02*
Y106958D01*
G01X1149173Y105958D02*
Y106958D01*
G01X1149224Y105958D02*
Y106958D01*
G01X1149632Y105958D02*
Y106958D01*
G01X1149774Y81034D02*
Y82960D01*
G01Y95994D02*
Y97920D01*
G01X1150474Y81034D02*
Y82960D01*
G01Y95995D02*
Y97921D01*
G01X1150616Y106958D02*
Y105958D01*
G01X1150947Y106958D02*
Y105958D01*
G01X1151028D02*
Y106958D01*
G01X1151079Y105958D02*
Y106958D01*
G01X1151561Y105958D02*
Y106958D01*
G01X1151658Y105958D02*
Y106958D01*
G01X1151699Y105171D02*
Y102336D01*
G01X1151947Y106958D02*
Y105958D01*
G01X1152465Y106958D02*
Y105958D01*
G01X1153809D02*
Y106958D01*
G01X1154970Y93578D02*
Y87182D01*
G01X1156506Y94578D02*
Y105171D01*
G01X1156843Y94578D02*
Y86182D01*
G01X1158490Y94578D02*
Y86182D01*
G01X1159285D02*
Y94578D01*
G01X1159758Y91636D02*
Y97542D01*
G01X1160695Y105171D02*
Y96578D01*
G01X1161490Y91636D02*
Y105171D01*
G01X1163089Y96578D02*
Y105171D01*
G01X1164411Y107942D02*
Y106958D01*
G01X1164618Y92636D02*
Y96542D01*
G01X1165010Y104171D02*
Y97578D01*
G01X1165411Y107942D02*
Y106958D01*
G01X1161490Y107942D02*
G03X1159767Y106958I0J-2000D01*
G01X1164010Y96578D02*
G03X1165010Y97578I0J1000D01*
G01Y104171D02*
G03X1164010Y105171I-1000J0D01*
G01X1155970Y94578D02*
G03X1154970Y93578I0J-1000D01*
G01Y87182D02*
G03X1155970Y86182I1000J0D01*
G01X1164618Y96542D02*
G03X1163618Y97542I-1000J0D01*
G01Y91636D02*
G03X1164618Y92636I0J1000D01*
G01X1159490Y77812D02*
X1164010D01*
G01X1146821Y78276D02*
X1147521D01*
G01Y78493D02*
X1146821D01*
G01X1147521Y78588D02*
X1146821D01*
G01X1147521Y78650D02*
X1146821D01*
G01X1147521Y78749D02*
X1146821D01*
G01X1160490Y78812D02*
X1159490D01*
G01X1162427Y75643D02*
X1160490Y77580D01*
G01X1146821Y78278D02*
Y80204D01*
G01X1147521Y78278D02*
Y80204D01*
G01X1163427Y77812D02*
Y96578D01*
G01X1159490Y77628D02*
X1157506Y75643D01*
G01X1165010Y76812D02*
G03X1164010Y77812I-1000J0D01*
G01X1165411Y107942D02*
X1161490D01*
G01X1171630Y647834D02*
Y656495D01*
X1168219Y649999D01*
X1172604D01*
G01X1160424Y650721D02*
X1160911Y652164D01*
X1162373Y652886D01*
X1163834Y652164D01*
X1164322Y650721D01*
X1163834Y649277D01*
X1163347Y648555D01*
X1162373Y647834D01*
X1161398Y648555D01*
X1160911Y649277D01*
X1160424Y650721D01*
Y653608D01*
X1160911Y655051D01*
X1161398Y655773D01*
X1162373Y656495D01*
X1163347Y655773D01*
X1163834Y655051D01*
G01X1154577Y656495D02*
Y647834D01*
G01X1173071Y861254D02*
X1173809Y861505D01*
G01Y860500D02*
X1173071Y860249D01*
G01X1172579Y860751D02*
X1173071Y861254D01*
G01Y860249D02*
X1172579Y859746D01*
G01X1176270Y860500D02*
X1177008Y861254D01*
G01Y860249D02*
X1176762Y859997D01*
G01D02*
X1176516Y859495D01*
G01X1168406Y892519D02*
Y883464D01*
G01X1169390D02*
Y892519D01*
G01X1171555D02*
Y883464D01*
G01X1174301Y860500D02*
X1173809D01*
G01X1171348Y861505D02*
X1172579D01*
G01X1173809D02*
X1174793D01*
G01X1177854Y883464D02*
X1175689D01*
G01X1174705D02*
X1172539D01*
G01X1171555D02*
X1169390D01*
G01X1172539D02*
Y892519D01*
G01X1172579Y861505D02*
Y860751D01*
G01X1174705Y892519D02*
Y883464D01*
G01X1175689D02*
Y892519D01*
G01X1167657Y861505D02*
X1168396Y861254D01*
G01X1174793Y861505D02*
X1175531Y861254D01*
G01X1174793Y860249D02*
X1174301Y860500D01*
G01X1167904Y859997D02*
X1167657Y860249D01*
G01X1168396Y861254D02*
X1168888Y860751D01*
G01X1175039Y859997D02*
X1174793Y860249D01*
G01X1175531Y861254D02*
X1176270Y860500D01*
G01X1168150Y859495D02*
X1167904Y859997D01*
G01X1175285Y859495D02*
X1175039Y859997D01*
G01X1168888Y860751D02*
X1169380Y859495D01*
G01X1168150Y853464D02*
Y859495D01*
G01X1169380D02*
Y853464D01*
G01X1171348D02*
Y861505D01*
G01X1176516Y853464D02*
X1175285D01*
G01X1172579D02*
X1171348D01*
G01X1169380D02*
X1168150D01*
G01X1172579Y859746D02*
Y853464D01*
G01X1175285D02*
Y859495D01*
G01X1176516D02*
Y853464D01*
G01X1161998Y861254D02*
X1162736Y861505D01*
G01Y860500D02*
X1161998Y860249D01*
G01X1165935Y861254D02*
X1166673Y861505D01*
G01X1166427Y860500D02*
X1165935Y860249D01*
G01X1152402Y865023D02*
X1151171Y864269D01*
G01X1152648Y863767D02*
X1151909Y863264D01*
G01X1155108Y854971D02*
X1155846Y855474D01*
G01X1151171Y864269D02*
X1150433Y863516D01*
G01X1161506Y860751D02*
X1161998Y861254D01*
G01Y860249D02*
X1161506Y859746D01*
G01X1165197Y860500D02*
X1165935Y861254D01*
G01Y860249D02*
X1165689Y859997D01*
G01X1151909Y863264D02*
X1150925Y861756D01*
G01X1155846Y855474D02*
X1156831Y856982D01*
G01X1150433Y863516D02*
X1149941Y862510D01*
G01X1157323Y855223D02*
X1157815Y856228D01*
G01X1165689Y859997D02*
X1165443Y859495D01*
G01X1149941Y862510D02*
X1149695Y861756D01*
G01X1157815Y856228D02*
X1158061Y856982D01*
G01X1153878Y864018D02*
X1152648Y863767D01*
G01X1153878Y865275D02*
X1152402Y865023D01*
G01X1150925Y861756D02*
X1150679Y860249D01*
G01X1156831Y856982D02*
X1157077Y858490D01*
G01X1149695Y861756D02*
X1149449Y860500D01*
G01X1158061Y856982D02*
X1158307Y858238D01*
G01X1143209Y892519D02*
Y883464D01*
G01X1143543Y860500D02*
Y861505D01*
G01Y857484D02*
Y858490D01*
G01X1144193Y883464D02*
Y892519D01*
G01X1146358D02*
Y883464D01*
G01X1147343D02*
Y892519D01*
G01X1147480Y861505D02*
Y860500D01*
G01Y858490D02*
Y857484D01*
G01X1149449Y860500D02*
Y858238D01*
G01X1149508Y892519D02*
Y883464D01*
G01X1150492D02*
Y892519D01*
G01X1150679Y860249D02*
Y858490D01*
G01X1152657Y892519D02*
Y883464D01*
G01X1153642D02*
Y892519D01*
G01X1155807D02*
Y883464D01*
G01X1156791D02*
Y892519D01*
G01X1157077Y858490D02*
Y860249D01*
G01X1158307Y858238D02*
Y860500D01*
G01X1158957Y892519D02*
Y883464D01*
G01X1159941D02*
Y892519D01*
G01X1161506Y861505D02*
Y860751D01*
G01X1162106Y892519D02*
Y883464D01*
G01X1163091D02*
Y892519D01*
G01X1165256D02*
Y883464D01*
G01X1166240D02*
Y892519D01*
G01X1147480Y857484D02*
X1143543D01*
G01Y858490D02*
X1147480D01*
G01X1167165Y860500D02*
X1166427D01*
G01X1163228D02*
X1162736D01*
G01X1147480D02*
X1143543D01*
G01Y861505D02*
X1147480D01*
G01X1160276D02*
X1161506D01*
G01X1162736D02*
X1163720D01*
G01X1166673D02*
X1167657D01*
G01X1168406Y883464D02*
X1166240D01*
G01X1165256D02*
X1163091D01*
G01X1162106D02*
X1159941D01*
G01X1158957D02*
X1156791D01*
G01X1155807D02*
X1153642D01*
G01X1152657D02*
X1150492D01*
G01X1149508D02*
X1147343D01*
G01X1146358D02*
X1144193D01*
G01X1155354Y865023D02*
X1153878Y865275D01*
G01X1155108Y863767D02*
X1153878Y864018D01*
G01X1149449Y858238D02*
X1149695Y856982D01*
G01X1150679Y858490D02*
X1150925Y856982D01*
G01X1157077Y860249D02*
X1156831Y861756D01*
G01X1163720Y861505D02*
X1164459Y861254D01*
G01X1149695Y856982D02*
X1149941Y856228D01*
G01X1158061Y861756D02*
X1157815Y862510D01*
G01X1158307Y860500D02*
X1158061Y861756D01*
G01X1163720Y860249D02*
X1163228Y860500D01*
G01X1167657Y860249D02*
X1167165Y860500D01*
G01X1156585Y864269D02*
X1155354Y865023D01*
G01X1151909Y855474D02*
X1152648Y854971D01*
G01X1155846Y863264D02*
X1155108Y863767D01*
G01X1157323Y863516D02*
X1156585Y864269D01*
G01X1163967Y859997D02*
X1163720Y860249D01*
G01X1164459Y861254D02*
X1165197Y860500D01*
G01X1150925Y856982D02*
X1151909Y855474D01*
G01X1156831Y861756D02*
X1155846Y863264D01*
G01X1149941Y856228D02*
X1150433Y855223D01*
G01X1157815Y862510D02*
X1157323Y863516D01*
G01X1164213Y859495D02*
X1163967Y859997D01*
G01X1155354Y853715D02*
X1156585Y854469D01*
G01D02*
X1157323Y855223D01*
G01X1153878Y854720D02*
X1155108Y854971D01*
G01X1153878Y853464D02*
X1155354Y853715D01*
G01X1160276Y853464D02*
Y861505D01*
G01X1161506Y859746D02*
Y853464D01*
G01X1164213D02*
Y859495D01*
G01X1165443D02*
Y853464D01*
G01D02*
X1164213D01*
G01X1161506D02*
X1160276D01*
G01X1152402Y853715D02*
X1153878Y853464D01*
G01X1152648Y854971D02*
X1153878Y854720D01*
G01X1151171Y854469D02*
X1152402Y853715D01*
G01X1150433Y855223D02*
X1151171Y854469D01*
G01X1172539Y892519D02*
X1174705D01*
G01X1169390D02*
X1171555D01*
G01X1175689D02*
X1177854D01*
G01X1144193D02*
X1146358D01*
G01X1147343D02*
X1149508D01*
G01X1153642D02*
X1155807D01*
G01X1150492D02*
X1152657D01*
G01X1156791D02*
X1158957D01*
G01X1163091D02*
X1165256D01*
G01X1159941D02*
X1162106D01*
G01X1166240D02*
X1168406D01*
G01X1170264Y941519D02*
X1169289Y942241D01*
X1168802Y942963D01*
X1168315Y944406D01*
Y947293D01*
X1168802Y948737D01*
X1169289Y949459D01*
X1170264Y950180D01*
X1171238Y949459D01*
X1171726Y948737D01*
X1172213Y947293D01*
Y944406D01*
X1171726Y942963D01*
X1171238Y942241D01*
X1170264Y941519D01*
G01X1162469Y950180D02*
Y941519D01*
G01X1154673D02*
X1154186D01*
Y942241D01*
X1154673Y941519D01*
G01X1146878D02*
X1145904Y942241D01*
X1145417Y942963D01*
X1144929Y944406D01*
Y947293D01*
X1145417Y948737D01*
X1145904Y949459D01*
X1146878Y950180D01*
X1147852Y949459D01*
X1148340Y948737D01*
X1148827Y947293D01*
Y944406D01*
X1148340Y942963D01*
X1147852Y942241D01*
X1146878Y941519D01*
G01X1171354Y2158744D02*
Y2159695D01*
X1172067Y2160645D01*
X1172780Y2161596D01*
X1174206Y2162547D01*
X1175631D01*
X1177057Y2161596D01*
G01D02*
X1178483Y2159695D01*
Y2158744D01*
X1177770Y2157793D01*
X1177057Y2156843D01*
X1175631Y2155892D01*
X1174206D01*
G01D02*
X1172780Y2156843D01*
X1171354Y2158744D01*
G01X1174206Y2162547D02*
X1172780Y2163497D01*
X1172067Y2164448D01*
Y2165399D01*
X1172780Y2166349D01*
X1174206Y2167300D01*
X1175631D01*
X1177057Y2166349D01*
X1177770Y2165399D01*
Y2164448D01*
X1177057Y2163497D01*
X1175631Y2162547D01*
G01X1221100Y-702854D02*
X1207579Y-711364D01*
G01X1180496Y-723414D02*
Y-697826D01*
G01Y-723414D02*
Y-697826D01*
G01X1207579Y-711364D02*
X1191507Y-719139D01*
G01X1208213Y-508849D02*
Y-697826D01*
G01Y-508849D02*
Y-697826D01*
G01X1196418Y-682078D02*
X1289141D01*
G01X1196418D02*
X1321274D01*
G01X1196418D02*
X1352549D01*
G01X1198567Y-687590D02*
X1196106D01*
G01X1190693D02*
X1188232D01*
G01X1182819D02*
X1180358D01*
G01X1198567D02*
X1196106D01*
G01X1190693D02*
X1188232D01*
G01X1182819D02*
X1180358D01*
G01X1194138Y-673517D02*
X1192661D01*
G01X1186264D02*
X1185280D01*
G01X1194138D02*
X1192661D01*
G01X1186264D02*
X1185280D01*
G01X1180358Y-671507D02*
X1182819D01*
G01X1185280D02*
X1187248D01*
G01X1193154D02*
X1195122D01*
G01X1180358D02*
X1182819D01*
G01X1185280D02*
X1187248D01*
G01X1193154D02*
X1195122D01*
G01X1187248D02*
X1188724Y-672009D01*
G01X1187248Y-671507D02*
X1188724Y-672009D01*
G01X1195122Y-671507D02*
X1196598Y-672009D01*
G01X1195122Y-671507D02*
X1196598Y-672009D01*
G01X1187248Y-674020D02*
X1186264Y-673517D01*
G01X1187248Y-674020D02*
X1186264Y-673517D01*
G01X1195122Y-674020D02*
X1194138Y-673517D01*
G01X1195122Y-674020D02*
X1194138Y-673517D01*
G01X1187740Y-674522D02*
X1187248Y-674020D01*
G01X1187740Y-674522D02*
X1187248Y-674020D01*
G01X1188724Y-672009D02*
X1190201Y-673517D01*
G01X1188724Y-672009D02*
X1190201Y-673517D01*
G01X1196598Y-672009D02*
X1197583Y-673014D01*
G01X1195614Y-674522D02*
X1195122Y-674020D01*
G01X1195614Y-674522D02*
X1195122Y-674020D01*
G01X1196598Y-672009D02*
X1197583Y-673014D01*
G01X1188232Y-675527D02*
X1187740Y-674522D01*
G01X1188232Y-675527D02*
X1187740Y-674522D01*
G01X1196106Y-675527D02*
X1195614Y-674522D01*
G01X1196106Y-675527D02*
X1195614Y-674522D01*
G01X1197583Y-673014D02*
X1198567Y-675527D01*
G01X1197583Y-673014D02*
X1198567Y-675527D01*
G01X1180358Y-687590D02*
Y-671507D01*
G01Y-687590D02*
Y-671507D01*
G01X1182819D02*
Y-673014D01*
G01Y-675025D02*
Y-687590D01*
G01Y-671507D02*
Y-673014D01*
G01Y-675025D02*
Y-687590D01*
G01X1188232D02*
Y-675527D01*
G01Y-687590D02*
Y-675527D01*
G01X1190693D02*
Y-687590D01*
G01Y-675527D02*
Y-687590D01*
G01X1196106D02*
Y-675527D01*
G01Y-687590D02*
Y-675527D01*
G01X1198567D02*
Y-687590D01*
G01Y-675527D02*
Y-687590D01*
G01X1191185Y-674522D02*
X1190693Y-675527D01*
G01X1191185Y-674522D02*
X1190693Y-675527D01*
G01X1182819Y-673014D02*
X1183803Y-672009D01*
G01X1182819Y-673014D02*
X1183803Y-672009D01*
G01Y-674020D02*
X1182819Y-675025D01*
G01X1183803Y-674020D02*
X1182819Y-675025D01*
G01X1190201Y-673517D02*
X1191677Y-672009D01*
G01X1190201Y-673517D02*
X1191677Y-672009D01*
G01Y-674020D02*
X1191185Y-674522D01*
G01X1191677Y-674020D02*
X1191185Y-674522D01*
G01X1192661Y-673517D02*
X1191677Y-674020D01*
G01X1192661Y-673517D02*
X1191677Y-674020D01*
G01X1183803Y-672009D02*
X1185280Y-671507D01*
G01X1183803Y-672009D02*
X1185280Y-671507D01*
G01Y-673517D02*
X1183803Y-674020D01*
G01X1185280Y-673517D02*
X1183803Y-674020D01*
G01X1191677Y-672009D02*
X1193154Y-671507D01*
G01X1191677Y-672009D02*
X1193154Y-671507D01*
G01X1192481Y-682078D02*
Y-508849D01*
G01X1219079Y-593495D02*
X1204984D01*
G01X1202307Y-591527D02*
X1221756D01*
G01X1206638Y-574873D02*
X1202307Y-576842D01*
G01X1206559Y-590660D02*
X1202622D01*
G01X1214551Y-586999D02*
X1209512D01*
G01X1206559Y-586723D02*
X1202622D01*
G01X1214551Y-581960D02*
X1209512D01*
G01X1206559D02*
X1202622D01*
G01X1206559Y-578023D02*
X1202622D01*
G01X1221756Y-576842D02*
X1202307D01*
G01X1206638Y-574873D02*
X1217425D01*
G01Y-574086D02*
X1206638D01*
G01X1202307Y-572117D02*
X1221756D01*
G01X1206559Y-570975D02*
X1202622D01*
G01X1202307Y-591527D02*
X1204984Y-593495D01*
G01X1211087Y-585424D02*
X1209512Y-586999D01*
G01X1202307Y-572117D02*
X1206638Y-574086D01*
G01X1202307Y-556842D02*
Y-572117D01*
G01Y-576842D02*
Y-591527D01*
G01X1202622Y-567038D02*
Y-570975D01*
G01Y-578023D02*
Y-581960D01*
G01Y-586723D02*
Y-590660D01*
G01X1206559Y-567038D02*
Y-570975D01*
G01Y-578023D02*
Y-581960D01*
G01Y-586723D02*
Y-590660D01*
G01X1206638Y-574086D02*
Y-574873D01*
G01X1209512Y-581960D02*
X1211087Y-583534D01*
G01X1209512Y-541960D02*
Y-586999D01*
G01X1182151Y-591877D02*
X1182810D01*
G01X1178414D02*
X1179073D01*
G01X1182151D02*
X1182810D01*
G01X1178414D02*
X1179073D01*
G01X1180612Y-594009D02*
X1182151Y-591877D01*
G01X1180612Y-594009D02*
X1182151Y-591877D01*
G01X1182810D02*
X1180942Y-594458D01*
G01X1182810Y-591877D02*
X1180942Y-594458D01*
G01X1180282D02*
X1178414Y-591877D01*
G01X1180282Y-594458D02*
X1178414Y-591877D01*
G01X1179073D02*
X1180612Y-594009D01*
G01X1179073Y-591877D02*
X1180612Y-594009D01*
G01X1182810Y-597152D02*
X1182151D01*
G01X1179073D02*
X1178414D01*
G01X1182810D02*
X1182151D01*
G01X1179073D02*
X1178414D01*
G01D02*
X1180282Y-594458D01*
G01X1178414Y-597152D02*
X1180282Y-594458D01*
G01X1180612Y-595020D02*
X1179073Y-597152D01*
G01X1180612Y-595020D02*
X1179073Y-597152D01*
G01X1182151D02*
X1180612Y-595020D01*
G01X1182151Y-597152D02*
X1180612Y-595020D01*
G01X1180942Y-594458D02*
X1182810Y-597152D01*
G01X1180942Y-594458D02*
X1182810Y-597152D01*
G01X1204984Y-535464D02*
X1202307Y-537432D01*
G01X1206638Y-554873D02*
X1202307Y-556842D01*
G01X1211087Y-545424D02*
X1209512Y-546999D01*
G01X1206559Y-562117D02*
X1202622D01*
G01X1214551Y-561960D02*
X1209512D01*
G01X1206559Y-558180D02*
X1202622D01*
G01X1221756Y-556842D02*
X1202307D01*
G01X1206638Y-554873D02*
X1217425D01*
G01Y-554086D02*
X1206638D01*
G01X1202307Y-552117D02*
X1221756D01*
G01X1206559Y-551290D02*
X1202622D01*
G01X1206559Y-547353D02*
X1202622D01*
G01X1214551Y-546999D02*
X1209512D01*
G01X1202307Y-537432D02*
Y-552117D01*
G01X1202622Y-538338D02*
Y-542275D01*
G01Y-547353D02*
Y-551290D01*
G01Y-558180D02*
Y-562117D01*
G01X1206559Y-538338D02*
Y-542275D01*
G01Y-547353D02*
Y-551290D01*
G01Y-558180D02*
Y-562117D01*
G01X1206638Y-554086D02*
Y-554873D01*
G01X1206559Y-542275D02*
X1202622D01*
G01X1214551Y-541960D02*
X1209512D01*
G01X1206559Y-538338D02*
X1202622D01*
G01X1221756Y-537432D02*
X1202307D01*
G01X1204984Y-535464D02*
X1219079D01*
G01X1206638Y-554086D02*
X1202307Y-552117D01*
G01X1209512Y-541960D02*
X1211087Y-543534D01*
G01X1206559Y-567038D02*
X1202622D01*
G01X1214551Y-566999D02*
X1209512D01*
G01X1192481Y-504912D02*
Y-398386D01*
G01X1196418Y-508849D02*
X1352549D01*
G01X1203411Y-462697D02*
X1221333Y-471414D01*
G01X1183208Y-457970D02*
X1203411Y-462697D01*
G01X1201274Y-101181D02*
Y-109843D01*
G01X1207121Y-106956D02*
X1207608Y-105512D01*
X1209070Y-104790D01*
X1210531Y-105512D01*
X1211019Y-106956D01*
X1210531Y-108399D01*
X1210044Y-109121D01*
X1209070Y-109843D01*
X1208095Y-109121D01*
X1207608Y-108399D01*
X1207121Y-106956D01*
Y-104069D01*
X1207608Y-102625D01*
X1208095Y-101903D01*
X1209070Y-101181D01*
X1210044Y-101903D01*
X1210531Y-102625D01*
G01X1193479Y-109843D02*
X1192505Y-109121D01*
X1192017Y-108399D01*
X1191530Y-106956D01*
Y-104069D01*
X1192017Y-102625D01*
X1192505Y-101903D01*
X1193479Y-101181D01*
X1194454Y-101903D01*
X1194941Y-102625D01*
X1195428Y-104069D01*
Y-106956D01*
X1194941Y-108399D01*
X1194454Y-109121D01*
X1193479Y-109843D01*
G01X1183735Y-102625D02*
X1184222Y-101903D01*
X1185196Y-101181D01*
X1186171D01*
X1187145Y-101903D01*
X1187633Y-102625D01*
Y-104069D01*
X1187145Y-104790D01*
X1185196Y-106234D01*
G01D02*
X1184222Y-107678D01*
X1183735Y-109843D01*
X1187633D01*
G01X1210537Y-39469D02*
X1206703D01*
G01X1210341Y-39154D02*
X1206703D01*
G01X1206334Y-38336D02*
X1203063D01*
G01Y-34399D02*
X1206334D01*
G01X1205870Y-34338D02*
X1205804D01*
G01X1214546Y-33775D02*
X1206362D01*
G01X1210537Y-33249D02*
X1206703D01*
G01X1214531Y-33102D02*
X1206362D01*
G01Y-32967D02*
X1214531D01*
G01X1246104Y-32749D02*
X1203797D01*
G01X1202282Y-32023D02*
X1204312D01*
G01X1206362Y-30829D02*
X1214531D01*
G01Y-30744D02*
X1206362D01*
G01X1214531Y-31261D02*
X1206362Y-31255D01*
G01X1246104Y-28812D02*
X1203797D01*
G01Y-32749D02*
X1203802Y-42635D01*
G01X1201232Y-22238D02*
Y-31524D01*
G01X1201282Y-33023D02*
Y-33845D01*
G01X1202797Y-32749D02*
Y-42635D01*
G01Y-28812D02*
Y105958D01*
G01X1203063Y-34399D02*
Y-38336D01*
G01X1203797Y-42635D02*
Y-32749D01*
G01Y-28812D02*
Y105958D01*
G01X1204797Y-38336D02*
Y-34399D01*
G01X1205312Y-33023D02*
Y-33845D01*
G01X1205362Y-22238D02*
Y-31524D01*
G01X1206113Y-38879D02*
Y-33339D01*
G01X1206362Y-33845D02*
Y-17548D01*
G01X1207334Y-35399D02*
Y-37336D01*
G01X1203804Y-14225D02*
X1203797Y-28812D01*
G01X1202282Y-32023D02*
G03X1201282Y-33023I0J-1000D01*
G01X1206334Y-38336D02*
G03X1207334Y-37336I0J1000D01*
G01X1210537Y-39469D02*
G03X1211128Y-38879I1J590D01*
G01X1206113D02*
G03X1206703Y-39469I590J0D01*
G01X1206113Y-38564D02*
G03X1206703Y-39154I590J0D01*
G01X1210341D02*
G03X1210931Y-38564I0J590D01*
G01X1205312Y-33023D02*
G03X1204312Y-32023I-1000J0D01*
G01X1207334Y-35399D02*
G03X1206334Y-34399I-1000J0D01*
G01X1210931Y-33339D02*
G03X1210341Y-32749I-590J0D01*
G01X1206703D02*
G03X1206113Y-33339I0J-590D01*
G01X1206703Y-33249D02*
G03X1206113Y-33839I0J-590D01*
G01X1211128D02*
G03X1210537Y-33249I-590J0D01*
G01X1210931Y-33839D02*
G03X1210341Y-33249I-590J0D01*
G01X1205312Y-33845D02*
G03X1205804Y-34338I492J-1D01*
G01X1205870D02*
G03X1206362Y-33845I0J492D01*
G01X1205862Y-32016D02*
G03X1206362Y-31524I8J492D01*
G01X1205362D02*
G03X1205862Y-32016I492J0D01*
G01X1200232Y-31255D02*
X1192064Y-31261D01*
G01X1218037Y-42635D02*
X1188558D01*
G01X1217436Y-41435D02*
X1189159D01*
G01X1199892Y-39469D02*
X1196057D01*
G01X1177310Y-39467D02*
X1185978D01*
G01X1185644Y-39440D02*
X1177644D01*
G01X1199695Y-39154D02*
X1196057D01*
G01X1200790Y-34338D02*
X1200724D01*
G01X1200232Y-33775D02*
X1192049D01*
G01X1190577D02*
X1182380D01*
G01X1199892Y-33249D02*
X1196057D01*
G01X1200232Y-33102D02*
X1192063D01*
G01X1190563D02*
X1182394D01*
G01Y-32967D02*
X1190563D01*
G01X1192063D02*
X1200232D01*
G01X1190563Y-31261D02*
X1182394D01*
G01Y-30829D02*
X1190563D01*
G01X1192063D02*
X1200232D01*
G01Y-30744D02*
X1192063D01*
G01X1190563D02*
X1182394D01*
G01X1187851Y-42342D02*
X1187437Y-41928D01*
G01X1180908Y-33775D02*
X1180902Y-33744D01*
X1180898Y-33713D01*
X1180895Y-33682D01*
G01X1190577Y-33775D02*
X1190571Y-33744D01*
X1190567Y-33713D01*
X1190564Y-33682D01*
G01X1180895Y-33663D02*
X1180898Y-33701D01*
X1180902Y-33738D01*
X1180908Y-33775D01*
G01X1190564Y-33663D02*
X1190567Y-33701D01*
X1190571Y-33738D01*
X1190577Y-33775D01*
G01X1180895Y-33682D02*
X1180894Y-33647D01*
G01Y-33621D02*
X1180895Y-33663D01*
G01X1190564Y-33682D02*
X1190563Y-33647D01*
G01Y-33621D02*
X1190564Y-33663D01*
G01X1178760Y-34319D02*
Y-32749D01*
G01X1179380D02*
Y-34319D01*
G01X1180895Y-33682D02*
Y-33663D01*
G01X1180894Y-17548D02*
Y-33647D01*
G01X1182394D02*
Y-17548D01*
G01X1182393Y-33663D02*
Y-33682D01*
G01X1183908Y-34319D02*
Y-32749D01*
G01X1184528D02*
Y-34319D01*
G01X1186644Y-41835D02*
Y-40398D01*
G01X1186959Y-32749D02*
Y-34319D01*
G01X1190564Y-33663D02*
Y-33682D01*
G01X1190563Y-17548D02*
Y-33647D01*
G01X1192063D02*
Y-17548D01*
G01X1192062Y-33663D02*
Y-33682D01*
G01X1195467Y-38879D02*
Y-33339D01*
G01X1200232Y-17548D02*
Y-33845D01*
G01X1200285Y-33339D02*
Y-38564D01*
G01X1200482Y-33839D02*
Y-38879D01*
G01X1182393Y-33663D02*
X1182394Y-33621D01*
G01X1192062Y-33663D02*
X1192063Y-33621D01*
G01X1182394Y-33647D02*
X1182393Y-33682D01*
G01X1192063Y-33647D02*
X1192062Y-33682D01*
G01X1182393D02*
X1182390Y-33713D01*
X1182386Y-33744D01*
X1182380Y-33775D01*
G01X1192062Y-33682D02*
X1192059Y-33713D01*
X1192055Y-33744D01*
X1192049Y-33775D01*
G01X1182380D02*
X1182386Y-33738D01*
X1182390Y-33701D01*
X1182393Y-33663D01*
G01X1192049Y-33775D02*
X1192055Y-33738D01*
X1192059Y-33701D01*
X1192062Y-33663D01*
G01X1180908Y-33775D02*
G03X1181644Y-34378I734J145D01*
G01D02*
G03X1182380Y-33775I2J748D01*
G01X1181644Y-32016D02*
G03X1182394Y-31261I2J748D01*
G01X1180894D02*
G03X1181644Y-32016I748J-7D01*
G01X1187851Y-42342D02*
G03X1188558Y-42635I707J707D01*
G01X1187437Y-41928D02*
G03X1186730Y-41635I-707J-707D01*
G01X1186644Y-40440D02*
G03X1185644Y-39440I-1000J0D01*
G01X1188199Y-40670D02*
G03X1189159Y-41435I960J219D01*
G01X1186644Y-40398D02*
G03X1185978Y-39467I-984J0D01*
G01X1188199Y-40670D02*
G03X1186644Y-40845I-768J-175D01*
G01X1199892Y-39469D02*
G03X1200482Y-38879I0J590D01*
G01X1195467D02*
G03X1196057Y-39469I590J0D01*
G01X1195467Y-38564D02*
G03X1196057Y-39154I590J0D01*
G01X1199695D02*
G03X1200285Y-38564I0J590D01*
G01X1190577Y-33775D02*
G03X1191313Y-34378I734J145D01*
G01D02*
G03X1192049Y-33775I2J748D01*
G01X1191313Y-32016D02*
G03X1192063Y-31261I2J748D01*
G01X1190563D02*
G03X1191313Y-32016I748J-7D01*
G01X1196057Y-33249D02*
G03X1195467Y-33839I0J-590D01*
G01X1200285Y-33339D02*
G03X1199695Y-32749I-590J0D01*
G01X1196057D02*
G03X1195467Y-33339I0J-590D01*
G01X1200482Y-33839D02*
G03X1199892Y-33249I-590J0D01*
G01X1200285Y-33839D02*
G03X1199695Y-33249I-590J0D01*
G01X1200232Y-33845D02*
G03X1200724Y-34338I492J-1D01*
G01X1200790D02*
G03X1201282Y-33845I0J492D01*
G01X1200732Y-32016D02*
G03X1201232Y-31524I8J492D01*
G01X1200232D02*
G03X1200732Y-32016I492J0D01*
G01X1207150Y-16798D02*
X1206997Y-16813D01*
X1206850Y-16857D01*
X1206714Y-16929D01*
X1206593Y-17028D01*
X1206495Y-17146D01*
X1206423Y-17281D01*
X1206378Y-17427D01*
X1206362Y-17582D01*
G01X1209457Y-16904D02*
X1209299Y-16918D01*
X1209147Y-16958D01*
X1209008Y-17023D01*
X1208885Y-17112D01*
X1208788Y-17218D01*
X1208717Y-17341D01*
G01X1212735Y-18862D02*
X1208159D01*
G01Y-18845D02*
X1212735D01*
G01X1214531Y-18516D02*
X1206362D01*
G01Y-18481D02*
X1214531D01*
G01Y-18138D02*
X1206362D01*
G01Y-18104D02*
X1214531D01*
G01X1208571Y-17890D02*
X1212323D01*
G01Y-17679D02*
X1208571D01*
G01X1203065Y-17178D02*
X1206925D01*
G01X1209457Y-17116D02*
X1211437D01*
G01Y-16904D02*
X1209457D01*
G01X1207150Y-16798D02*
X1213744D01*
G01Y-16764D02*
X1207150D01*
G01X1203065Y-15934D02*
X1208309D01*
G01X1206925Y-11273D02*
X1203065D01*
G01Y-8060D02*
X1208309D01*
G01X1203797Y-2525D02*
X1202797D01*
G01Y-1874D02*
X1203797D01*
G01X1202797Y-1777D02*
X1203797D01*
G01X1202797Y-1273D02*
X1203797D01*
G01X1202797Y-1244D02*
X1203797D01*
G01Y-832D02*
X1202797D01*
G01Y153D02*
X1203797D01*
G01X1202797Y560D02*
X1203797D01*
G01X1202797Y590D02*
X1203797D01*
G01X1202797Y1097D02*
X1203797D01*
G01Y1190D02*
X1202797D01*
G01X1203797Y1845D02*
X1202797D01*
G01X1203797Y3845D02*
X1202797D01*
G01X1203797Y4436D02*
X1202797D01*
G01X1203065Y-8060D02*
Y-17178D01*
G01X1203802Y31917D02*
X1203804Y-6351D01*
G01X1203815Y-14225D02*
Y-6351D01*
G01X1204797Y-15934D02*
Y-8060D01*
G01X1204801Y-11273D02*
Y-17178D01*
G01X1207150Y-16798D02*
Y-16764D01*
G01X1207925Y-12273D02*
Y-16178D01*
G01X1208159Y-18862D02*
Y-18845D01*
G01X1208238Y-9725D02*
Y-13990D01*
G01X1208571Y-17679D02*
Y-17890D01*
G01X1208717Y-17553D02*
Y-17341D01*
G01X1209309Y-9060D02*
Y-14934D01*
G01X1209457Y-16904D02*
Y-17116D01*
G01X1206362Y-17548D02*
X1206378Y-17396D01*
X1206422Y-17249D01*
X1206494Y-17114D01*
X1206593Y-16994D01*
X1206712Y-16896D01*
X1206847Y-16824D01*
X1206994Y-16779D01*
X1207150Y-16764D01*
G01X1208179Y-14327D02*
X1205422Y-21902D01*
G01X1208571Y-17679D02*
X1208434Y-18044D01*
X1208296Y-18437D01*
X1208159Y-18845D01*
G01Y-18862D02*
X1208296Y-18522D01*
X1208434Y-18195D01*
X1208571Y-17890D01*
G01X1208717Y-17341D02*
X1208571Y-17679D01*
G01Y-17890D02*
X1208717Y-17553D01*
G01D02*
X1208787Y-17432D01*
X1208883Y-17325D01*
X1209003Y-17237D01*
X1209144Y-17170D01*
X1209296Y-17130D01*
X1209457Y-17116D01*
G01X1207925Y-12273D02*
G03X1206925Y-11273I-1000J0D01*
G01Y-17178D02*
G03X1207925Y-16178I0J1000D01*
G01X1208309Y-15934D02*
G03X1209309Y-14934I0J1000D01*
G01Y-9060D02*
G03X1208309Y-8060I-1000J0D01*
G01X1205422Y-21902D02*
G03X1205362Y-22238I924J-338D01*
G01X1208179Y-14327D02*
G03X1208238Y-13990I-925J336D01*
G01Y-9725D02*
G03X1207254Y-8741I-984J0D01*
G01X1201232Y-22238D02*
G03X1201173Y-21902I-984J0D01*
G01X1206362Y-24077D02*
X1214531D01*
G01Y-23942D02*
X1206362D01*
G01X1214504Y-23756D02*
X1206390D01*
G01Y-23671D02*
X1214504D01*
G01X1206524Y-23348D02*
X1214370D01*
G01Y-23331D02*
X1206524D01*
G01X1206362Y-23097D02*
X1214531D01*
G01X1203797Y-23095D02*
X1246104D01*
G01X1214531Y-23063D02*
X1206362D01*
G01X1246104Y-22468D02*
X1203797D01*
G01X1206390Y-23756D02*
Y-23671D01*
G01X1206410Y-23615D02*
Y-23689D01*
G01X1206524Y-23331D02*
Y-23339D01*
G01D02*
Y-23348D01*
G01X1206362Y-23958D02*
X1206363Y-23925D01*
X1206365Y-23891D01*
X1206369Y-23858D01*
X1206374Y-23824D01*
X1206381Y-23790D01*
X1206390Y-23756D01*
G01Y-23671D02*
X1206382Y-23702D01*
X1206375Y-23736D01*
X1206370Y-23768D01*
X1206366Y-23803D01*
X1206363Y-23838D01*
X1206362Y-23872D01*
G01X1206390Y-23756D02*
X1206396Y-23734D01*
X1206403Y-23711D01*
X1206410Y-23689D01*
G01D02*
X1206524Y-23348D01*
G01X1208159Y-18845D02*
X1206524Y-23331D01*
G01Y-23348D02*
X1208159Y-18862D01*
G01X1206410Y-23615D02*
X1206403Y-23633D01*
X1206396Y-23652D01*
X1206390Y-23671D01*
G01X1206524Y-23331D02*
X1206410Y-23615D01*
G01X1192850Y-16798D02*
X1192698Y-16813D01*
X1192550Y-16857D01*
X1192415Y-16929D01*
X1192294Y-17028D01*
X1192196Y-17146D01*
X1192124Y-17281D01*
X1192079Y-17427D01*
X1192063Y-17582D01*
G01X1183181Y-16798D02*
X1183028Y-16813D01*
X1182881Y-16857D01*
X1182746Y-16929D01*
X1182624Y-17028D01*
X1182527Y-17146D01*
X1182454Y-17281D01*
X1182409Y-17427D01*
X1182394Y-17582D01*
G01X1195158Y-16904D02*
X1195000Y-16918D01*
X1194848Y-16958D01*
X1194709Y-17023D01*
X1194586Y-17112D01*
X1194489Y-17218D01*
X1194418Y-17341D01*
G01X1183181Y-16904D02*
X1183028Y-16917D01*
X1182881Y-16954D01*
X1182746Y-17015D01*
X1182624Y-17099D01*
X1182527Y-17199D01*
X1182454Y-17313D01*
X1182409Y-17437D01*
X1182394Y-17568D01*
G01X1198436Y-18862D02*
X1193859D01*
G01X1190563D02*
X1182394D01*
G01Y-18845D02*
X1190563D01*
G01X1193859D02*
X1198436D01*
G01X1200232Y-18516D02*
X1192063D01*
G01X1190563D02*
X1182394D01*
G01Y-18481D02*
X1190563D01*
G01X1192063D02*
X1200232D01*
G01Y-18138D02*
X1192063D01*
G01X1190563D02*
X1182394D01*
G01Y-18104D02*
X1190563D01*
G01X1192063D02*
X1200232D01*
G01X1182394Y-17890D02*
X1190563D01*
G01X1194272D02*
X1198024D01*
G01Y-17679D02*
X1194272D01*
G01X1190563D02*
X1182394D01*
G01X1195115Y-17318D02*
X1190193D01*
G01X1183181Y-17116D02*
X1189776D01*
G01X1195158D02*
X1197138D01*
G01Y-16904D02*
X1195158D01*
G01X1189776D02*
X1183181D01*
G01Y-16798D02*
X1189776D01*
G01X1192850D02*
X1199445D01*
G01Y-16764D02*
X1192850D01*
G01X1189776D02*
X1183181D01*
G01X1195115Y-14786D02*
X1190193D01*
G01Y-14307D02*
X1195115D01*
G01Y-9699D02*
X1190193D01*
G01Y-9220D02*
X1195115D01*
G01X1207254Y-8741D02*
X1199341D01*
G01X1190193Y-6688D02*
X1195115D01*
G01Y-1570D02*
X1190193D01*
G01X1195115Y962D02*
X1190193D01*
G01Y1441D02*
X1195115D01*
G01Y6049D02*
X1190193D01*
G01X1180106Y-17116D02*
X1180259Y-17128D01*
X1180407Y-17166D01*
X1180542Y-17227D01*
X1180663Y-17310D01*
X1180761Y-17410D01*
X1180833Y-17525D01*
X1180878Y-17649D01*
X1180894Y-17780D01*
G01X1189776Y-17116D02*
X1189929Y-17128D01*
X1190076Y-17166D01*
X1190211Y-17227D01*
X1190333Y-17310D01*
X1190430Y-17410D01*
X1190503Y-17525D01*
X1190548Y-17649D01*
X1190563Y-17780D01*
G01X1197138Y-17116D02*
X1197296Y-17129D01*
X1197448Y-17170D01*
X1197587Y-17234D01*
X1197710Y-17323D01*
X1197807Y-17430D01*
X1197878Y-17553D01*
G01X1180106Y-16764D02*
X1180259Y-16779D01*
X1180407Y-16823D01*
X1180542Y-16895D01*
X1180663Y-16994D01*
X1180761Y-17112D01*
X1180833Y-17247D01*
X1180878Y-17393D01*
X1180894Y-17548D01*
G01X1189776Y-16764D02*
X1189929Y-16779D01*
X1190076Y-16823D01*
X1190211Y-16895D01*
X1190333Y-16994D01*
X1190430Y-17112D01*
X1190503Y-17247D01*
X1190548Y-17393D01*
X1190563Y-17548D01*
G01X1199445Y-16764D02*
X1199598Y-16779D01*
X1199745Y-16823D01*
X1199881Y-16895D01*
X1200002Y-16994D01*
X1200099Y-17112D01*
X1200172Y-17247D01*
X1200217Y-17393D01*
X1200232Y-17548D01*
G01X1197878Y-17341D02*
X1197808Y-17220D01*
X1197712Y-17114D01*
X1197592Y-17025D01*
X1197450Y-16959D01*
X1197299Y-16918D01*
X1197138Y-16904D01*
G01X1198024Y-17890D02*
X1198161Y-18195D01*
X1198298Y-18522D01*
X1198436Y-18862D01*
G01X1197878Y-17553D02*
X1198024Y-17890D01*
G01Y-17679D02*
X1197878Y-17341D01*
G01X1198416Y-14327D02*
X1201173Y-21902D01*
G01X1198436Y-18845D02*
X1198298Y-18437D01*
X1198161Y-18044D01*
X1198024Y-17679D01*
G01X1180894Y-17582D02*
X1180879Y-17430D01*
X1180835Y-17284D01*
X1180762Y-17149D01*
X1180663Y-17028D01*
X1180544Y-16931D01*
X1180409Y-16858D01*
X1180262Y-16814D01*
X1180106Y-16798D01*
G01X1190563Y-17582D02*
X1190548Y-17430D01*
X1190504Y-17284D01*
X1190431Y-17149D01*
X1190333Y-17028D01*
X1190214Y-16931D01*
X1190078Y-16858D01*
X1189931Y-16814D01*
X1189776Y-16798D01*
G01X1200232Y-17582D02*
X1200217Y-17430D01*
X1200173Y-17284D01*
X1200101Y-17149D01*
X1200002Y-17028D01*
X1199883Y-16931D01*
X1199748Y-16858D01*
X1199601Y-16814D01*
X1199445Y-16798D01*
G01X1180894Y-17568D02*
X1180879Y-17439D01*
X1180835Y-17315D01*
X1180762Y-17201D01*
X1180663Y-17099D01*
X1180544Y-17016D01*
X1180409Y-16955D01*
X1180262Y-16917D01*
X1180106Y-16904D01*
G01X1190563Y-17568D02*
X1190548Y-17439D01*
X1190504Y-17315D01*
X1190431Y-17201D01*
X1190333Y-17099D01*
X1190214Y-17016D01*
X1190078Y-16955D01*
X1189931Y-16917D01*
X1189776Y-16904D01*
G01X1180106Y-16764D02*
Y-16798D01*
G01Y-17116D02*
Y-16904D01*
G01X1183181D02*
Y-17116D01*
G01Y-16798D02*
Y-16764D01*
G01X1189776D02*
Y-16798D01*
G01Y-17116D02*
Y-16904D01*
G01X1190193Y9060D02*
Y-1570D01*
G01Y-6688D02*
Y-17318D01*
G01X1192850Y-16798D02*
Y-16764D01*
G01X1193859Y-18862D02*
Y-18845D01*
G01X1194272Y-17679D02*
Y-17890D01*
G01X1194418Y-17553D02*
Y-17341D01*
G01X1195115Y-17318D02*
Y-6688D01*
G01Y-1570D02*
Y9060D01*
G01X1195158Y-16904D02*
Y-17116D01*
G01X1197138D02*
Y-16904D01*
G01X1197878Y-17341D02*
Y-17553D01*
G01X1198024Y-17890D02*
Y-17679D01*
G01X1198357Y-9725D02*
Y-13990D01*
G01X1198436Y-18845D02*
Y-18862D01*
G01X1199445Y-16764D02*
Y-16798D01*
G01X1182394Y-17548D02*
X1182409Y-17396D01*
X1182453Y-17249D01*
X1182526Y-17114D01*
X1182624Y-16994D01*
X1182743Y-16896D01*
X1182879Y-16824D01*
X1183026Y-16779D01*
X1183181Y-16764D01*
G01X1182394Y-17780D02*
X1182409Y-17651D01*
X1182453Y-17527D01*
X1182526Y-17412D01*
X1182624Y-17310D01*
X1182743Y-17228D01*
X1182879Y-17167D01*
X1183026Y-17129D01*
X1183181Y-17116D01*
G01X1192063Y-17548D02*
X1192078Y-17396D01*
X1192122Y-17249D01*
X1192195Y-17114D01*
X1192294Y-16994D01*
X1192413Y-16896D01*
X1192548Y-16824D01*
X1192695Y-16779D01*
X1192850Y-16764D01*
G01X1194272Y-17679D02*
X1194135Y-18044D01*
X1193997Y-18437D01*
X1193859Y-18845D01*
G01Y-18862D02*
X1193997Y-18522D01*
X1194135Y-18195D01*
X1194272Y-17890D01*
G01X1194418Y-17341D02*
X1194272Y-17679D01*
G01Y-17890D02*
X1194418Y-17553D01*
G01D02*
X1194487Y-17432D01*
X1194584Y-17325D01*
X1194704Y-17237D01*
X1194845Y-17170D01*
X1194997Y-17130D01*
X1195158Y-17116D01*
G01X1199341Y-8741D02*
G03X1198357Y-9725I0J-984D01*
G01Y-13990D02*
G03X1198416Y-14327I984J-1D01*
G01X1182394Y-24077D02*
X1190563D01*
G01X1192063D02*
X1200232D01*
G01Y-23942D02*
X1192063D01*
G01X1190563D02*
X1182394D01*
G01X1200205Y-23756D02*
X1192091D01*
G01X1190563D02*
X1182394D01*
G01Y-23671D02*
X1190563D01*
G01X1192091D02*
X1200205D01*
G01X1182394Y-23348D02*
X1190563D01*
G01X1192225D02*
X1200070D01*
G01Y-23331D02*
X1192225D01*
G01X1190563D02*
X1182394D01*
G01Y-23097D02*
X1190563D01*
G01X1192063D02*
X1200232D01*
G01Y-23063D02*
X1192063D01*
G01X1190563D02*
X1182394D01*
G01X1200185Y-23615D02*
X1200070Y-23331D01*
G01X1198436Y-18862D02*
X1200070Y-23348D01*
G01Y-23331D02*
X1198436Y-18845D01*
G01X1200070Y-23348D02*
X1200185Y-23689D01*
G01D02*
X1200192Y-23711D01*
X1200199Y-23734D01*
X1200205Y-23756D01*
G01Y-23671D02*
X1200199Y-23652D01*
X1200192Y-23633D01*
X1200185Y-23615D01*
G01X1200205Y-23756D02*
X1200213Y-23787D01*
X1200220Y-23821D01*
X1200225Y-23853D01*
X1200229Y-23888D01*
X1200231Y-23923D01*
X1200232Y-23958D01*
G01Y-23872D02*
Y-23840D01*
X1200230Y-23805D01*
X1200226Y-23773D01*
X1200220Y-23739D01*
X1200213Y-23705D01*
X1200205Y-23671D01*
G01X1192091Y-23756D02*
Y-23671D01*
G01X1192111Y-23615D02*
Y-23689D01*
G01X1192225Y-23331D02*
Y-23339D01*
G01D02*
Y-23348D01*
G01X1200185Y-23689D02*
Y-23615D01*
G01X1200205Y-23671D02*
Y-23756D01*
G01X1200070Y-23348D02*
Y-23331D01*
G01X1192063Y-23958D02*
X1192064Y-23925D01*
X1192066Y-23891D01*
X1192070Y-23858D01*
X1192075Y-23824D01*
X1192082Y-23790D01*
X1192091Y-23756D01*
G01Y-23671D02*
X1192083Y-23702D01*
X1192076Y-23736D01*
X1192070Y-23768D01*
X1192067Y-23803D01*
X1192064Y-23838D01*
X1192063Y-23872D01*
G01X1192091Y-23756D02*
X1192097Y-23734D01*
X1192104Y-23711D01*
X1192111Y-23689D01*
G01D02*
X1192225Y-23348D01*
G01X1193859Y-18845D02*
X1192225Y-23331D01*
G01Y-23348D02*
X1193859Y-18862D01*
G01X1192111Y-23615D02*
X1192104Y-23633D01*
X1192097Y-23652D01*
X1192091Y-23671D01*
G01X1192225Y-23331D02*
X1192111Y-23615D01*
G01X1242545Y12019D02*
X1207309D01*
G01X1240380Y14955D02*
X1209474D01*
G01X1208309Y18242D02*
X1203065D01*
G01Y26116D02*
X1208309D01*
G01X1203990Y31917D02*
X1203797D01*
G01X1209474Y34353D02*
X1240380D01*
G01Y35141D02*
X1209474D01*
G01X1242545Y35267D02*
X1207309D01*
G01X1217761Y36767D02*
X1207309D01*
G01X1203065Y38853D02*
X1206925D01*
G01X1203797Y39791D02*
X1203990D01*
G01X1203065Y26116D02*
Y18242D01*
G01Y38853D02*
Y44759D01*
G01X1203991Y31917D02*
Y39791D01*
G01X1204797Y44759D02*
Y38853D01*
G01Y18242D02*
Y26116D01*
G01X1207925Y43759D02*
Y39853D01*
G01X1209309Y19242D02*
Y25116D01*
G01X1209474Y35141D02*
Y14955D01*
G01X1208309Y18242D02*
G03X1209309Y19242I0J1000D01*
G01Y25116D02*
G03X1208309Y26116I-1000J0D01*
G01X1206925Y38853D02*
G03X1207925Y39853I0J1000D01*
G01X1202797Y6877D02*
X1203797D01*
G01Y7468D02*
X1202797D01*
G01X1207309Y11019D02*
X1242545D01*
G01X1207309Y44408D02*
Y11019D01*
G01X1209474Y14955D02*
X1208293Y11019D01*
G01X1209474Y14955D02*
X1208293Y11019D01*
G01X1183089Y12877D02*
X1185089D01*
G01X1183089Y14058D02*
X1184089D01*
G01X1181270Y18393D02*
X1181970D01*
G01X1178317D02*
X1179017D01*
G01X1184222D02*
X1184922D01*
G01X1187176D02*
X1187876D01*
G01X1190128D02*
X1190828D01*
G01X1193081D02*
X1193781D01*
G01X1184089Y18585D02*
X1183089D01*
G01X1185089Y19766D02*
X1183089D01*
G01X1193781Y21371D02*
X1193081D01*
G01X1190828D02*
X1190128D01*
G01X1187876D02*
X1187176D01*
G01X1184922D02*
X1184222D01*
G01X1181970D02*
X1181270D01*
G01X1179017D02*
X1178317D01*
G01X1193781Y24336D02*
X1193081D01*
G01X1190828D02*
X1190128D01*
G01X1187876D02*
X1187176D01*
G01X1184922D02*
X1184222D01*
G01X1181970D02*
X1181270D01*
G01X1179017D02*
X1178317D01*
G01X1193781Y24561D02*
X1193081D01*
G01X1190828D02*
X1190128D01*
G01X1187876D02*
X1187176D01*
G01X1184922D02*
X1184222D01*
G01X1181970D02*
X1181270D01*
G01X1179017D02*
X1178317D01*
G01X1185299Y27251D02*
X1182346D01*
G01X1181346D02*
X1177989D01*
G01X1185299Y28251D02*
X1182346D01*
G01X1181346D02*
X1177989D01*
G01X1185299Y29251D02*
X1182346D01*
G01X1181346D02*
X1177989D01*
G01X1185299Y29501D02*
X1182346D01*
G01X1181346D02*
X1177989D01*
G01X1184906Y29645D02*
X1178382D01*
G01X1182937Y31367D02*
X1184709D01*
G01X1180756Y32851D02*
X1178579D01*
G01X1199238Y36767D02*
X1188785D01*
G01X1191411Y37588D02*
X1189518D01*
G01X1187077Y38588D02*
X1191545D01*
G01X1187749Y39032D02*
X1187722D01*
G01X1191880Y39392D02*
X1189911D01*
G01X1191545Y38588D02*
X1191678Y38552D01*
X1191797Y38447D01*
X1191880Y38288D01*
X1191911Y38088D01*
G01X1180265Y34686D02*
X1181076Y34298D01*
X1181998Y34147D01*
X1182930Y34252D01*
X1183825Y34621D01*
X1184613Y35238D01*
X1185215Y36057D01*
X1185598Y37073D01*
G01X1189831Y35857D02*
X1187749Y37940D01*
G01X1187722Y39032D02*
X1184770Y41985D01*
G01X1185181Y39341D02*
X1184509Y40116D01*
X1183683Y40669D01*
X1182735Y40987D01*
X1181748Y41034D01*
X1180813Y40811D01*
X1179979Y40337D01*
X1179348Y39675D01*
G01X1188588Y36569D02*
X1189652Y35267D01*
G01X1187722Y38069D02*
X1188785Y36767D01*
G01X1185181Y39341D02*
X1184524Y40265D01*
X1183626Y40969D01*
X1182526Y41398D01*
X1181369Y41489D01*
X1180230Y41238D01*
X1179228Y40682D01*
X1178418Y39846D01*
X1177883Y38822D01*
X1177668Y37666D01*
X1177796Y36502D01*
X1178245Y35448D01*
X1178998Y34547D01*
X1179991Y33899D01*
X1181130Y33574D01*
X1182294Y33592D01*
X1183404Y33950D01*
X1184363Y34614D01*
X1185100Y35547D01*
X1185530Y36666D01*
X1185608Y37866D01*
X1185311Y39065D01*
X1184703Y40063D01*
X1183846Y40833D01*
X1182753Y41340D01*
X1181588Y41497D01*
X1180446Y41313D01*
X1179378Y40790D01*
X1178536Y40005D01*
X1177953Y39005D01*
X1177679Y37852D01*
X1177747Y36714D01*
X1178141Y35630D01*
X1178837Y34697D01*
X1179789Y33999D01*
X1180888Y33612D01*
X1182040Y33560D01*
X1183156Y33837D01*
X1184097Y34385D01*
X1184874Y35195D01*
X1185412Y36241D01*
X1185620Y37379D01*
X1185487Y38551D01*
X1185032Y39606D01*
X1184278Y40501D01*
X1183300Y41136D01*
X1182154Y41464D01*
X1181026Y41451D01*
X1179913Y41101D01*
X1178961Y40458D01*
X1178213Y39533D01*
X1177760Y38387D01*
X1177678Y37197D01*
X1177933Y36081D01*
X1178500Y35079D01*
X1179341Y34274D01*
X1180401Y33738D01*
X1181575Y33540D01*
X1182770Y33702D01*
X1183822Y34188D01*
X1184693Y34961D01*
X1185303Y35956D01*
X1185599Y37089D01*
X1185556Y38249D01*
X1185181Y39341D01*
G01X1187722Y38069D02*
X1188588Y36569D01*
G01X1189652Y35267D02*
X1188785Y36767D01*
G01X1185181Y39341D02*
X1185506Y38627D01*
X1185648Y37855D01*
X1185598Y37073D01*
G01X1185600Y38246D02*
X1185218Y39363D01*
X1184530Y40321D01*
X1183589Y41039D01*
X1182483Y41452D01*
X1181305Y41526D01*
X1180149Y41253D01*
X1179137Y40664D01*
X1178326Y39792D01*
X1177809Y38731D01*
X1177622Y37567D01*
X1177783Y36392D01*
X1178271Y35327D01*
X1179063Y34434D01*
X1180070Y33817D01*
X1181209Y33520D01*
X1182390Y33566D01*
X1183504Y33953D01*
X1184465Y34651D01*
X1185177Y35597D01*
X1185582Y36703D01*
X1185650Y37880D01*
X1185371Y39030D01*
X1184771Y40048D01*
X1183897Y40850D01*
X1182833Y41361D01*
X1181667Y41540D01*
X1180497Y41373D01*
X1179429Y40876D01*
X1178545Y40083D01*
X1177934Y39072D01*
X1177643Y37928D01*
X1177696Y36749D01*
X1178089Y35636D01*
X1178789Y34685D01*
X1179736Y33978D01*
X1180846Y33577D01*
X1182026Y33515D01*
X1183173Y33799D01*
X1184186Y34402D01*
X1184981Y35274D01*
X1185489Y36340D01*
X1185666Y37508D01*
X1185496Y38676D01*
X1184993Y39745D01*
X1184208Y40618D01*
X1183198Y41228D01*
X1182054Y41519D01*
X1180874Y41466D01*
X1179757Y41070D01*
X1178818Y40380D01*
X1178110Y39439D01*
X1177705Y38330D01*
X1177639Y37152D01*
X1177920Y35999D01*
X1178511Y34995D01*
X1179376Y34197D01*
X1180438Y33682D01*
X1181603Y33497D01*
X1182772Y33658D01*
X1183841Y34150D01*
X1184718Y34925D01*
X1185339Y35930D01*
X1185641Y37069D01*
X1185600Y38246D01*
G01X1185506Y38627D02*
X1185648Y37855D01*
X1185598Y37073D01*
G01D02*
X1185556Y38248D01*
X1185162Y39377D01*
X1184479Y40312D01*
X1183543Y41015D01*
X1182404Y41425D01*
X1181203Y41473D01*
X1180024Y41153D01*
X1179062Y40547D01*
X1178317Y39701D01*
X1177828Y38649D01*
X1177666Y37437D01*
X1177881Y36222D01*
X1178400Y35212D01*
X1179205Y34375D01*
X1180203Y33809D01*
X1181317Y33553D01*
X1182536Y33640D01*
X1183643Y34077D01*
X1184527Y34776D01*
X1185184Y35701D01*
X1185557Y36795D01*
X1185600Y37942D01*
X1185296Y39097D01*
X1184695Y40073D01*
X1183822Y40847D01*
X1182804Y41325D01*
X1181659Y41498D01*
X1180443Y41312D01*
X1179417Y40818D01*
X1178575Y40051D01*
X1177964Y39033D01*
X1177683Y37904D01*
X1177740Y36751D01*
X1178145Y35620D01*
X1178841Y34695D01*
X1179739Y34025D01*
X1180828Y33624D01*
X1182036Y33559D01*
X1183167Y33842D01*
X1184143Y34422D01*
X1184942Y35293D01*
X1185433Y36305D01*
X1185623Y37526D01*
X1185433Y38734D01*
X1184944Y39744D01*
X1184176Y40588D01*
X1183202Y41180D01*
X1182071Y41475D01*
X1180866Y41421D01*
X1179760Y41025D01*
X1178862Y40364D01*
X1178160Y39441D01*
X1177764Y38402D01*
X1177675Y37241D01*
X1177954Y36025D01*
X1178539Y35030D01*
X1179394Y34237D01*
X1180464Y33718D01*
X1181614Y33540D01*
X1182765Y33700D01*
X1183833Y34195D01*
X1184683Y34949D01*
X1185306Y35962D01*
X1185598Y37073D01*
G01X1191911Y38088D02*
X1191901Y38173D01*
X1191867Y38258D01*
X1191808Y38341D01*
X1191726Y38418D01*
X1191620Y38484D01*
X1191491Y38538D01*
X1191343Y38574D01*
X1191179Y38588D01*
G01X1176989Y31038D02*
Y26751D01*
G01X1177989Y32261D02*
Y26751D01*
G01X1178317Y24561D02*
Y18393D01*
G01X1179017Y24561D02*
Y18393D01*
G01X1181270Y24561D02*
Y18393D01*
G01X1181346Y32261D02*
Y26751D01*
G01X1181970Y24561D02*
Y18393D01*
G01X1182346Y30777D02*
Y26751D01*
G01X1183089Y12877D02*
Y19766D01*
G01X1184089Y12877D02*
Y19766D01*
G01X1184222Y24561D02*
Y18393D01*
G01X1184922Y24561D02*
Y18393D01*
G01X1185089Y19766D02*
Y12877D01*
G01X1185299Y30777D02*
Y26751D01*
G01X1186299Y31038D02*
Y26751D01*
G01X1186487Y43339D02*
Y39178D01*
G01X1187176Y24561D02*
Y18393D01*
G01X1187722Y44408D02*
Y38069D01*
G01X1187749Y44408D02*
Y37940D01*
G01X1187876Y24561D02*
Y18393D01*
G01X1188447Y44408D02*
Y37242D01*
G01X1188588Y36569D02*
Y44408D01*
G01X1189518Y40780D02*
Y34257D01*
G01X1189661Y43930D02*
Y38588D01*
G01X1189911Y44408D02*
Y36767D01*
G01X1190128Y24561D02*
Y18393D01*
G01X1190828Y24561D02*
Y18393D01*
G01X1190911Y43930D02*
Y38588D01*
G01X1191880Y44408D02*
Y36767D01*
G01X1191911Y43930D02*
Y38088D01*
G01X1193081Y24561D02*
Y18393D01*
G01X1193781Y24561D02*
Y18393D01*
G01X1197073Y35141D02*
Y14955D01*
G01X1185598Y37073D02*
X1185239Y36100D01*
X1184654Y35281D01*
X1183865Y34644D01*
X1182946Y34257D01*
X1181989Y34146D01*
X1181060Y34303D01*
X1180265Y34687D01*
G01X1179349Y39675D02*
X1179969Y40330D01*
X1180789Y40802D01*
X1181716Y41031D01*
X1182698Y40994D01*
X1183653Y40684D01*
X1184493Y40130D01*
X1185182Y39341D01*
G01X1189518Y34257D02*
X1184906Y29645D01*
G01X1176989Y26751D02*
G03X1177989I500J0D01*
G01X1181346D02*
G03X1182346I500J0D01*
G01X1185299Y30777D02*
G03X1184709Y31367I-590J0D01*
G01X1182937D02*
G03X1182346Y30777I0J-591D01*
G01X1185299Y26751D02*
G03X1186299I500J0D01*
G01X1185974Y37519D02*
G03I-4330J0D01*
G01X1184793D02*
G03I-3149J0D01*
G01X1178579Y32851D02*
G03X1177989Y32261I0J-590D01*
G01X1181346D02*
G03X1180756Y32851I-590J0D01*
G01X1186487Y39178D02*
G03X1187077Y38588I590J0D01*
G01X1191411Y37588D02*
G03X1191911Y38088I0J500D01*
G01X1190193Y6528D02*
X1195115D01*
G01X1190193Y9060D02*
X1195115D01*
G01X1197073Y14955D02*
X1198254Y11019D01*
G01X1197073Y14955D02*
X1198254Y11019D01*
G01X1199238D02*
Y44408D01*
G01X1210610Y59749D02*
X1210110Y59623D01*
G01X1210485Y60999D02*
X1209485Y60749D01*
G01X1203797Y45223D02*
X1202797D01*
G01Y46475D02*
X1203797D01*
G01Y47182D02*
X1202797D01*
G01Y50541D02*
X1203797D01*
G01X1202797Y50638D02*
X1203797D01*
G01X1202797Y51142D02*
X1203797D01*
G01X1202797Y51171D02*
X1203797D01*
G01Y51583D02*
X1202797D01*
G01Y52568D02*
X1203797D01*
G01X1202797Y52975D02*
X1203797D01*
G01X1202797Y53005D02*
X1203797D01*
G01X1211485Y53499D02*
X1210485D01*
G01X1205485D02*
X1204110D01*
G01X1202797Y53512D02*
X1203797D01*
G01Y53605D02*
X1202797D01*
G01X1203797Y54260D02*
X1202797D01*
G01X1203797Y54275D02*
X1202797D01*
G01X1211360Y54749D02*
X1210610D01*
G01X1214485Y56999D02*
X1208985D01*
G01X1212985Y57999D02*
X1208985D01*
G01X1211360Y59749D02*
X1210610D01*
G01X1211485Y60999D02*
X1210485D01*
G01X1205485Y63499D02*
X1204110D01*
G01X1207317Y68043D02*
X1202797D01*
G01X1210485Y53499D02*
X1209485Y53749D01*
G01X1210610Y54749D02*
X1210110Y54873D01*
G01D02*
X1209485Y55249D01*
G01Y53749D02*
X1208735Y54249D01*
G01D02*
X1208235Y54749D01*
G01X1201360Y59749D02*
X1201860Y58999D01*
G01X1207735Y55499D02*
X1208235Y54749D01*
G01X1209110Y55873D02*
X1209485Y55249D01*
G01X1201860Y58999D02*
X1202110Y57999D01*
G01X1207485Y56499D02*
X1207735Y55499D01*
G01X1208985Y56373D02*
X1209110Y55873D01*
G01X1201797Y66043D02*
Y56275D01*
G01X1202110Y56499D02*
Y57999D01*
G01X1202593Y56275D02*
Y66043D01*
G01X1204002Y77812D02*
Y68043D01*
G01X1204110Y63499D02*
Y53499D01*
G01X1204797Y68043D02*
Y77812D01*
G01X1205485Y63499D02*
Y53499D01*
G01X1206396Y68043D02*
Y77812D01*
G01X1207485Y57999D02*
Y56499D01*
G01X1208317Y76812D02*
Y69043D01*
G01X1208985Y58123D02*
Y57999D01*
G01Y56999D02*
Y56373D01*
G01X1202110Y56499D02*
X1201860Y55499D01*
G01X1207735Y58999D02*
X1207485Y57999D01*
G01X1209110Y58623D02*
X1208985Y58123D01*
G01X1209485Y60749D02*
X1208735Y60249D01*
G01X1210110Y59623D02*
X1209485Y59249D01*
G01D02*
X1209110Y58623D01*
G01X1201860Y55499D02*
X1201360Y54749D01*
G01X1208235Y59749D02*
X1207735Y58999D01*
G01X1208735Y60249D02*
X1208235Y59749D01*
G01X1207317Y68043D02*
G03X1208317Y69043I0J1000D01*
G01X1205734Y44408D02*
X1244120D01*
G01X1202797Y44516D02*
X1203797D01*
G01X1206925Y44759D02*
X1203065D01*
G01X1205734Y105171D02*
Y44408D01*
G01X1206734D02*
Y68043D01*
G01X1207362Y105171D02*
Y44408D01*
G01X1208776Y105171D02*
Y44408D01*
G01X1207925Y43759D02*
G03X1206925Y44759I-1000J0D01*
G01X1200110Y53749D02*
X1199110Y53499D01*
G01X1199485Y54873D02*
X1198985Y54749D01*
G01X1198235Y59749D02*
X1197735Y59623D01*
G01X1198110Y60999D02*
X1197110Y60749D01*
G01X1190235Y59749D02*
X1189735Y59623D01*
G01X1186110Y59749D02*
X1185610Y59623D01*
G01X1178382Y45393D02*
X1184906D01*
G01X1181270Y48355D02*
X1181970D01*
G01X1190128D02*
X1190828D01*
G01Y48571D02*
X1190128D01*
G01X1181970D02*
X1181270D01*
G01X1190828Y48667D02*
X1190128D01*
G01X1181970D02*
X1181270D01*
G01X1190828Y48729D02*
X1190128D01*
G01X1181970D02*
X1181270D01*
G01X1190828Y48827D02*
X1190128D01*
G01X1181970D02*
X1181270D01*
G01X1190828Y49812D02*
X1190128D01*
G01X1181970D02*
X1181270D01*
G01X1190828Y49910D02*
X1190128D01*
G01X1181970D02*
X1181270D01*
G01X1190828Y49973D02*
X1190128D01*
G01X1181970D02*
X1181270D01*
G01X1190828Y50068D02*
X1190128D01*
G01X1181970D02*
X1181270D01*
G01Y50284D02*
X1181970D01*
G01X1190128D02*
X1190828D01*
G01X1184222Y51111D02*
X1184922D01*
G01X1193081D02*
X1193781D01*
G01Y51327D02*
X1193081D01*
G01X1184922D02*
X1184222D01*
G01X1193781Y51423D02*
X1193081D01*
G01X1184922D02*
X1184222D01*
G01X1193781Y51485D02*
X1193081D01*
G01X1184922D02*
X1184222D01*
G01X1193781Y51583D02*
X1193081D01*
G01X1184922D02*
X1184222D01*
G01X1193781Y52568D02*
X1193081D01*
G01X1184923D02*
X1184223D01*
G01X1193781Y52666D02*
X1193081D01*
G01X1184922D02*
X1184222D01*
G01X1193781Y52729D02*
X1193081D01*
G01X1184922D02*
X1184222D01*
G01X1193781Y52823D02*
X1193081D01*
G01X1184922D02*
X1184222D01*
G01Y53040D02*
X1184922D01*
G01X1193081D02*
X1193781D01*
G01X1193110Y53499D02*
X1191735D01*
G01X1188985D02*
X1187610D01*
G01X1184860D02*
X1183485D01*
G01X1198110D02*
X1199110D01*
G01X1187876Y53867D02*
X1187176D01*
G01X1179017D02*
X1178317D01*
G01Y54083D02*
X1179017D01*
G01X1187176D02*
X1187876D01*
G01X1178317Y54179D02*
X1179017D01*
G01X1187176D02*
X1187876D01*
G01X1178317Y54241D02*
X1179017D01*
G01X1187176D02*
X1187876D01*
G01Y54339D02*
X1187176D01*
G01X1179017D02*
X1178317D01*
G01X1198985Y54749D02*
X1198235D01*
G01X1187876Y55323D02*
X1187176D01*
G01X1179017D02*
X1178317D01*
G01X1187876Y55422D02*
X1187176D01*
G01X1179017D02*
X1178317D01*
G01Y55484D02*
X1179017D01*
G01X1187176D02*
X1187876D01*
G01X1178317Y55579D02*
X1179017D01*
G01X1187176D02*
X1187876D01*
G01Y55796D02*
X1187176D01*
G01X1179017D02*
X1178317D01*
G01X1203797Y56275D02*
X1199278D01*
G01X1198985Y59749D02*
X1198235D01*
G01X1184860Y60873D02*
X1183485D01*
G01X1199110Y60999D02*
X1198110D01*
G01X1190610D02*
X1190110D01*
G01X1186485D02*
X1185985D01*
G01X1181270Y63316D02*
X1181970D01*
G01X1190128D02*
X1190828D01*
G01Y63532D02*
X1190128D01*
G01X1181970D02*
X1181270D01*
G01X1190828Y63627D02*
X1190128D01*
G01X1181970D02*
X1181270D01*
G01X1190828Y63690D02*
X1190128D01*
G01X1181970D02*
X1181270D01*
G01X1190828Y63788D02*
X1190128D01*
G01X1181970D02*
X1181270D01*
G01X1190828Y64772D02*
X1190128D01*
G01X1181970D02*
X1181270D01*
G01X1190828Y64871D02*
X1190128D01*
G01X1181970D02*
X1181270D01*
G01X1190828Y64933D02*
X1190128D01*
G01X1181970D02*
X1181270D01*
G01X1190828Y65028D02*
X1190128D01*
G01X1181970D02*
X1181270D01*
G01Y65245D02*
X1181970D01*
G01X1190128D02*
X1190828D01*
G01X1199278Y66043D02*
X1203797D01*
G01X1184222Y66071D02*
X1184922D01*
G01X1193081D02*
X1193781D01*
G01Y66288D02*
X1193081D01*
G01X1184922D02*
X1184222D01*
G01X1193781Y66383D02*
X1193081D01*
G01X1184922D02*
X1184222D01*
G01X1193781Y66445D02*
X1193081D01*
G01X1184922D02*
X1184222D01*
G01X1193781Y66544D02*
X1193081D01*
G01X1184922D02*
X1184222D01*
G01X1193781Y67528D02*
X1193081D01*
G01X1184923D02*
X1184223D01*
G01X1193781Y67627D02*
X1193081D01*
G01X1184922D02*
X1184222D01*
G01X1193781Y67689D02*
X1193081D01*
G01X1184922D02*
X1184222D01*
G01X1193781Y67784D02*
X1193081D01*
G01X1184922D02*
X1184222D01*
G01Y68001D02*
X1184922D01*
G01X1193081D02*
X1193781D01*
G01X1187876Y68827D02*
X1187176D01*
G01X1179017D02*
X1178317D01*
G01Y69044D02*
X1179017D01*
G01X1187176D02*
X1187876D01*
G01X1178317Y69139D02*
X1179017D01*
G01X1187176D02*
X1187876D01*
G01X1178317Y69201D02*
X1179017D01*
G01X1187176D02*
X1187876D01*
G01Y69300D02*
X1187176D01*
G01X1179017D02*
X1178317D01*
G01X1187876Y70284D02*
X1187176D01*
G01X1179017D02*
X1178317D01*
G01X1187876Y70382D02*
X1187176D01*
G01X1179017D02*
X1178317D01*
G01Y70445D02*
X1179017D01*
G01X1187176D02*
X1187876D01*
G01Y70540D02*
X1187176D01*
G01X1179017D02*
X1178317D01*
G01X1187876Y70756D02*
X1187176D01*
G01X1179017D02*
X1178317D01*
G01X1186735Y59623D02*
X1186110Y59749D01*
G01X1190860Y59623D02*
X1190235Y59749D01*
G01X1198110Y53499D02*
X1197110Y53749D01*
G01X1198235Y54749D02*
X1197735Y54873D01*
G01X1199485Y59623D02*
X1198985Y59749D01*
G01X1200110Y60749D02*
X1199110Y60999D01*
G01X1187360Y60749D02*
X1186485Y60999D01*
G01X1191485Y60749D02*
X1190610Y60999D01*
G01X1197735Y54873D02*
X1197110Y55249D01*
G01X1200110Y59249D02*
X1199485Y59623D01*
G01X1197110Y53749D02*
X1196360Y54249D01*
G01X1188110Y60249D02*
X1187360Y60749D01*
G01X1192235Y60249D02*
X1191485Y60749D01*
G01X1200860Y60249D02*
X1200110Y60749D01*
G01X1187110Y59249D02*
X1186735Y59623D01*
G01X1188610Y59749D02*
X1188110Y60249D01*
G01X1191235Y59249D02*
X1190860Y59623D01*
G01X1196360Y54249D02*
X1195860Y54749D01*
G01X1201360Y59749D02*
X1200860Y60249D01*
G01X1192235D02*
X1192610Y59749D01*
G01X1195360Y55499D02*
X1195860Y54749D01*
G01X1187110Y59249D02*
X1187485Y58623D01*
G01X1191235Y59249D02*
X1191610Y58623D01*
G01X1196735Y55873D02*
X1197110Y55249D01*
G01X1200110Y59249D02*
X1200485Y58623D01*
G01X1192610Y59749D02*
X1192985Y58999D01*
G01X1187485Y58623D02*
X1187610Y58123D01*
G01X1191610Y58623D02*
X1191735Y58123D01*
G01X1195110Y56499D02*
X1195360Y55499D01*
G01X1196610Y56373D02*
X1196735Y55873D01*
G01X1200485Y58623D02*
X1200610Y58123D01*
G01X1192985Y58999D02*
X1193110Y57999D01*
G01X1178317Y53868D02*
Y55794D01*
G01Y68829D02*
Y70755D01*
G01X1179017Y53869D02*
Y55795D01*
G01Y68829D02*
Y70755D01*
G01X1181270Y48356D02*
Y50282D01*
G01Y63317D02*
Y65243D01*
G01X1181970Y48357D02*
Y50283D01*
G01Y63318D02*
Y65243D01*
G01X1183485Y60873D02*
Y53499D01*
G01X1184222Y51112D02*
Y53038D01*
G01Y66073D02*
Y67999D01*
G01X1184860Y58623D02*
Y53499D01*
G01Y60873D02*
Y60249D01*
G01X1184922Y51113D02*
Y53039D01*
G01Y66073D02*
Y67999D01*
G01X1187176Y53868D02*
Y55794D01*
G01Y68829D02*
Y70755D01*
G01X1187610Y58123D02*
Y53499D01*
G01X1187876Y53869D02*
Y55795D01*
G01Y68829D02*
Y70755D01*
G01X1188985Y58623D02*
Y53499D01*
G01X1190128Y48356D02*
Y50282D01*
G01Y63317D02*
Y65243D01*
G01X1190828Y48357D02*
Y50283D01*
G01Y63318D02*
Y65243D01*
G01X1191735Y58123D02*
Y53499D01*
G01X1193081Y51112D02*
Y53038D01*
G01Y66073D02*
Y67999D01*
G01X1193110Y57999D02*
Y53499D01*
G01X1193781Y51113D02*
Y53039D01*
G01Y66073D02*
Y67999D01*
G01X1195110Y57999D02*
Y56499D01*
G01X1196610Y58123D02*
Y56373D01*
G01X1198278Y65043D02*
Y57275D01*
G01X1199813Y66043D02*
Y86182D01*
G01X1200150Y66043D02*
Y56275D01*
G01X1200610Y58123D02*
Y56373D01*
G01X1190110Y60999D02*
X1189485Y60749D01*
G01X1185985Y60999D02*
X1185235Y60749D01*
G01X1195360Y58999D02*
X1195110Y57999D01*
G01X1196735Y58623D02*
X1196610Y58123D01*
G01X1200610Y56373D02*
X1200485Y55873D01*
G01X1185110Y59249D02*
X1184860Y58623D01*
G01X1185610Y59623D02*
X1185110Y59249D01*
G01X1189485Y60749D02*
X1188985Y60373D01*
G01X1189735Y59623D02*
X1189235Y59249D01*
G01X1197110Y60749D02*
X1196360Y60249D01*
G01X1200860Y54249D02*
X1200110Y53749D01*
G01X1197735Y59623D02*
X1197110Y59249D01*
G01X1200110Y55249D02*
X1199485Y54873D01*
G01X1189235Y59249D02*
X1188985Y58623D01*
G01Y60373D02*
X1188610Y59749D01*
G01X1197110Y59249D02*
X1196735Y58623D01*
G01X1200485Y55873D02*
X1200110Y55249D01*
G01X1195860Y59749D02*
X1195360Y58999D01*
G01X1185235Y60749D02*
X1184860Y60249D01*
G01X1196360D02*
X1195860Y59749D01*
G01X1201360Y54749D02*
X1200860Y54249D01*
G01X1198278Y57275D02*
G03X1199278Y56275I1000J0D01*
G01Y66043D02*
G03X1198278Y65043I0J-1000D01*
G01X1191880Y41062D02*
X1189911D01*
G01X1184770Y41985D02*
X1178470D01*
G01X1219518Y43930D02*
X1187077D01*
G01X1189518Y40780D02*
X1184906Y45393D01*
G01X1186541Y46512D02*
Y44408D01*
G01X1197772Y105171D02*
Y44408D01*
G01X1199185Y105171D02*
Y44408D01*
G01X1199813D02*
Y56275D01*
G01X1200813Y44408D02*
Y105171D01*
G01X1187077Y43930D02*
G03X1186487Y43339I1J-591D01*
G01X1202797Y85182D02*
X1203797D01*
G01X1203297Y86182D02*
X1202797D01*
G01X1203065Y91636D02*
X1206925D01*
G01X1207317Y96578D02*
X1202797D01*
G01X1206925Y97542D02*
X1203065D01*
G01X1202797Y103048D02*
X1203797D01*
G01Y103974D02*
X1202797D01*
G01X1203797Y104974D02*
X1202797D01*
G01X1202978Y105169D02*
X1203569D01*
G01X1201797Y94578D02*
Y86182D01*
G01X1202593D02*
Y94578D01*
G01X1203065Y91636D02*
Y97542D01*
G01X1204002Y105171D02*
Y96578D01*
G01X1204797Y91636D02*
Y105171D01*
G01X1206396Y96578D02*
Y105171D01*
G01X1207719Y107942D02*
Y106958D01*
G01X1207925Y92636D02*
Y96542D01*
G01X1208317Y104171D02*
Y97578D01*
G01X1208719Y107942D02*
Y106958D01*
G01X1204797Y107942D02*
G03X1203074Y106958I0J-2000D01*
G01X1207925Y96542D02*
G03X1206925Y97542I-1000J0D01*
G01Y91636D02*
G03X1207925Y92636I0J1000D01*
G01X1207317Y96578D02*
G03X1208317Y97578I0J1000D01*
G01Y104171D02*
G03X1207317Y105171I-1000J0D01*
G01X1202797Y77812D02*
X1207317D01*
G01X1203797Y78812D02*
X1202797D01*
G01X1205734Y75643D02*
X1203797Y77580D01*
G01X1206734Y77812D02*
Y96578D01*
G01X1208317Y76812D02*
G03X1207317Y77812I-1000J0D01*
G01X1190828Y79733D02*
X1190128D01*
G01X1181970D02*
X1181270D01*
G01X1190828Y79831D02*
X1190128D01*
G01X1181970D02*
X1181270D01*
G01X1190828Y79894D02*
X1190128D01*
G01X1181970D02*
X1181270D01*
G01X1190828Y79989D02*
X1190128D01*
G01X1181970D02*
X1181270D01*
G01Y80205D02*
X1181970D01*
G01X1190128D02*
X1190828D01*
G01X1184222Y81032D02*
X1184922D01*
G01X1193081D02*
X1193781D01*
G01Y81249D02*
X1193081D01*
G01X1184922D02*
X1184222D01*
G01X1193781Y81344D02*
X1193081D01*
G01X1184922D02*
X1184222D01*
G01X1193781Y81406D02*
X1193081D01*
G01X1184922D02*
X1184222D01*
G01X1193781Y81505D02*
X1193081D01*
G01X1184922D02*
X1184222D01*
G01X1193781Y82489D02*
X1193081D01*
G01X1184923D02*
X1184223D01*
G01X1193781Y82587D02*
X1193081D01*
G01X1184922D02*
X1184222D01*
G01X1193781Y82650D02*
X1193081D01*
G01X1184922D02*
X1184222D01*
G01X1193781Y82745D02*
X1193081D01*
G01X1184922D02*
X1184222D01*
G01Y82961D02*
X1184922D01*
G01X1193081D02*
X1193781D01*
G01X1187876Y83788D02*
X1187176D01*
G01X1179017D02*
X1178317D01*
G01Y84005D02*
X1179017D01*
G01X1187176D02*
X1187876D01*
G01X1178317Y84100D02*
X1179017D01*
G01X1187176D02*
X1187876D01*
G01X1178317Y84162D02*
X1179017D01*
G01X1187176D02*
X1187876D01*
G01Y84260D02*
X1187176D01*
G01X1179017D02*
X1178317D01*
G01X1187876Y85245D02*
X1187176D01*
G01X1179017D02*
X1178317D01*
G01X1187876Y85343D02*
X1187176D01*
G01X1179017D02*
X1178317D01*
G01Y85406D02*
X1179017D01*
G01X1187176D02*
X1187876D01*
G01Y85501D02*
X1187176D01*
G01X1179017D02*
X1178317D01*
G01X1187876Y85717D02*
X1187176D01*
G01X1179017D02*
X1178317D01*
G01X1203797Y86182D02*
X1199278D01*
G01X1181270Y93237D02*
X1181970D01*
G01X1190128D02*
X1190828D01*
G01Y93453D02*
X1190128D01*
G01X1181970D02*
X1181270D01*
G01X1190828Y93549D02*
X1190128D01*
G01X1181970D02*
X1181270D01*
G01X1190828Y93611D02*
X1190128D01*
G01X1181970D02*
X1181270D01*
G01X1190828Y93709D02*
X1190128D01*
G01X1181970D02*
X1181270D01*
G01X1199278Y94578D02*
X1203797D01*
G01X1190828Y94693D02*
X1190128D01*
G01X1181970D02*
X1181270D01*
G01X1190828Y94792D02*
X1190128D01*
G01X1181970D02*
X1181270D01*
G01X1190828Y94855D02*
X1190128D01*
G01X1181970D02*
X1181270D01*
G01X1190828Y94949D02*
X1190128D01*
G01X1181970D02*
X1181270D01*
G01Y95166D02*
X1181970D01*
G01X1190128D02*
X1190828D01*
G01X1184222Y95993D02*
X1184922D01*
G01X1193081D02*
X1193781D01*
G01Y96209D02*
X1193081D01*
G01X1184922D02*
X1184222D01*
G01X1193781Y96305D02*
X1193081D01*
G01X1184922D02*
X1184222D01*
G01X1193781Y96367D02*
X1193081D01*
G01X1184922D02*
X1184222D01*
G01X1193781Y96465D02*
X1193081D01*
G01X1184922D02*
X1184222D01*
G01X1193781Y97449D02*
X1193081D01*
G01X1184923D02*
X1184223D01*
G01X1193781Y97548D02*
X1193081D01*
G01X1184922D02*
X1184222D01*
G01X1193781Y97610D02*
X1193081D01*
G01X1184922D02*
X1184222D01*
G01X1193781Y97705D02*
X1193081D01*
G01X1184922D02*
X1184222D01*
G01Y97922D02*
X1184922D01*
G01X1193081D02*
X1193781D01*
G01X1187876Y98749D02*
X1187176D01*
G01X1179017D02*
X1178317D01*
G01Y98965D02*
X1179017D01*
G01X1187176D02*
X1187876D01*
G01X1178317Y99060D02*
X1179017D01*
G01X1187176D02*
X1187876D01*
G01X1178317Y99123D02*
X1179017D01*
G01X1187176D02*
X1187876D01*
G01Y99221D02*
X1187176D01*
G01X1179017D02*
X1178317D01*
G01X1187876Y100205D02*
X1187176D01*
G01X1179017D02*
X1178317D01*
G01X1187876Y100304D02*
X1187176D01*
G01X1179017D02*
X1178317D01*
G01Y100366D02*
X1179017D01*
G01X1187176D02*
X1187876D01*
G01Y100461D02*
X1187176D01*
G01X1179017D02*
X1178317D01*
G01X1187876Y100678D02*
X1187176D01*
G01X1179017D02*
X1178317D01*
G01X1177152Y105958D02*
Y106958D01*
G01X1177248Y105958D02*
Y106958D01*
G01X1177900Y105958D02*
Y106958D01*
G01X1178317Y83790D02*
Y85716D01*
G01Y98750D02*
Y100676D01*
G01X1178667Y102336D02*
Y105171D01*
G01Y105958D02*
Y106958D01*
G01X1179017Y83790D02*
Y85716D01*
G01Y98751D02*
Y100677D01*
G01X1179400Y105958D02*
Y106958D01*
G01X1180045Y102336D02*
Y105171D01*
G01X1181270Y93238D02*
Y95164D01*
G01X1181970Y93239D02*
Y95165D01*
G01X1184222Y81034D02*
Y82960D01*
G01Y95994D02*
Y97920D01*
G01X1184573Y105958D02*
Y106958D01*
G01X1184922Y81034D02*
Y82960D01*
G01Y95995D02*
Y97921D01*
G01X1187176Y83790D02*
Y85716D01*
G01Y98750D02*
Y100676D01*
G01X1187876Y83790D02*
Y85716D01*
G01Y98751D02*
Y100677D01*
G01X1189100Y105171D02*
Y102336D01*
G01X1189746Y106958D02*
Y105958D01*
G01X1190128Y93238D02*
Y95164D01*
G01X1190478Y105171D02*
Y102336D01*
G01X1190828Y93239D02*
Y95165D01*
G01X1191246Y105958D02*
Y106958D01*
G01X1191902D02*
Y105958D01*
G01X1191994D02*
Y106958D01*
G01X1192254D02*
Y105958D01*
G01X1192258Y105171D02*
Y106958D01*
G01X1192480Y105958D02*
Y106958D01*
G01X1192531Y105958D02*
Y106958D01*
G01X1192939Y105958D02*
Y106958D01*
G01X1193081Y81034D02*
Y82960D01*
G01Y95994D02*
Y97920D01*
G01X1193781Y81034D02*
Y82960D01*
G01Y95995D02*
Y97921D01*
G01X1193923Y106958D02*
Y105958D01*
G01X1194254Y106958D02*
Y105958D01*
G01X1194335D02*
Y106958D01*
G01X1194386Y105958D02*
Y106958D01*
G01X1194868Y105958D02*
Y106958D01*
G01X1194965Y105958D02*
Y106958D01*
G01X1195006Y105171D02*
Y102336D01*
G01X1195254Y106958D02*
Y105958D01*
G01X1195772Y106958D02*
Y105958D01*
G01X1197116D02*
Y106958D01*
G01X1198278Y93578D02*
Y87182D01*
G01X1199813Y94578D02*
Y105171D01*
G01X1200150Y94578D02*
Y86182D01*
G01X1199278Y94578D02*
G03X1198278Y93578I0J-1000D01*
G01Y87182D02*
G03X1199278Y86182I1000J0D01*
G01X1181270Y78276D02*
X1181970D01*
G01X1190128D02*
X1190828D01*
G01Y78493D02*
X1190128D01*
G01X1181970D02*
X1181270D01*
G01X1190828Y78588D02*
X1190128D01*
G01X1181970D02*
X1181270D01*
G01X1190828Y78650D02*
X1190128D01*
G01X1181970D02*
X1181270D01*
G01X1190828Y78749D02*
X1190128D01*
G01X1181970D02*
X1181270D01*
G01Y78278D02*
Y80204D01*
G01X1181970Y78278D02*
Y80204D01*
G01X1190128Y78278D02*
Y80204D01*
G01X1190828Y78278D02*
Y80204D01*
G01X1202797Y77628D02*
X1200813Y75643D01*
G01X1208719Y107942D02*
X1204797D01*
G01X1177963Y647834D02*
X1177476D01*
Y648555D01*
X1177963Y647834D01*
G01X1185759D02*
X1184784Y648555D01*
X1184297Y649277D01*
X1183810Y650721D01*
Y653608D01*
X1184297Y655051D01*
X1184784Y655773D01*
X1185759Y656495D01*
X1186733Y655773D01*
X1187220Y655051D01*
X1187707Y653608D01*
Y650721D01*
X1187220Y649277D01*
X1186733Y648555D01*
X1185759Y647834D01*
G01X1193554D02*
X1192579Y648555D01*
X1192092Y649277D01*
X1191605Y650721D01*
Y653608D01*
X1192092Y655051D01*
X1192579Y655773D01*
X1193554Y656495D01*
X1194528Y655773D01*
X1195015Y655051D01*
X1195503Y653608D01*
Y650721D01*
X1195015Y649277D01*
X1194528Y648555D01*
X1193554Y647834D01*
G01X1209843Y879920D02*
Y1033312D01*
G01X1208440Y864841D02*
X1207992Y864172D01*
G01X1207785D02*
X1208337Y864981D01*
G01X1209843Y866062D02*
X1211139Y867802D01*
G01X1207992Y864172D02*
X1207785D01*
G01X1209094D02*
X1208888D01*
G01X1208337Y865826D02*
X1208543D01*
G01X1203051Y892519D02*
Y883464D01*
G01X1205512Y892519D02*
Y875983D01*
G01Y892519D02*
Y875983D01*
G01X1208337Y864981D02*
Y865826D01*
G01X1208543D02*
Y864981D01*
G01X1209843Y866062D02*
Y907558D01*
G01Y866062D02*
X1208622Y867802D01*
G01X1208543Y864981D02*
X1209094Y864172D01*
G01X1208888D02*
X1208440Y864841D01*
G01X1205512Y875983D02*
G03X1214173I4330J0D01*
G01X1205512D02*
G03X1214173I4330J0D01*
G01X1177008Y861254D02*
X1177746Y861505D01*
G01X1198150Y882952D02*
X1198054Y882910D01*
G01X1198246Y881695D02*
X1198341Y881737D01*
G01X1198246Y880983D02*
X1198341Y881025D01*
G01X1177500Y860500D02*
X1177008Y860249D01*
G01X1198130Y882742D02*
X1198073Y882700D01*
G01X1198265Y881905D02*
X1198322Y881946D01*
G01Y881234D02*
X1198265Y881193D01*
G01X1198054Y882910D02*
X1197958Y882784D01*
G01X1198341Y881025D02*
X1198437Y881151D01*
G01X1198073Y882700D02*
X1198015Y882617D01*
G01X1198322Y881946D02*
X1198380Y882030D01*
G01X1198341Y881737D02*
X1198456Y881905D01*
G01X1198380Y881318D02*
X1198322Y881234D01*
G01X1199473Y882114D02*
X1199013Y880983D01*
G01X1199339Y882114D02*
X1199013Y881318D01*
G01X1198380Y882030D02*
X1198418Y882114D01*
G01X1198015Y882617D02*
X1197977Y882491D01*
G01X1198418Y881444D02*
X1198380Y881318D01*
G01X1197958Y882784D02*
X1197900Y882617D01*
G01X1198437Y881151D02*
X1198495Y881318D01*
G01X1197900Y882617D02*
X1197862Y882407D01*
G01X1198495Y881318D02*
X1198533Y881528D01*
G01D02*
X1198552Y881821D01*
G01X1198456D02*
X1198437Y881569D01*
G01X1197977Y882491D02*
X1197958Y882365D01*
G01X1198418Y882114D02*
X1198437Y882240D01*
G01Y881569D02*
X1198418Y881444D01*
G01X1200202Y882449D02*
X1200279Y882952D01*
G01X1200183Y882282D02*
X1200010Y881151D01*
G01X1200394Y882952D02*
X1200087Y880983D01*
G01X1178238Y860500D02*
X1177500D01*
G01X1177746Y861505D02*
X1178730D01*
G01X1200087Y880983D02*
X1199933D01*
G01X1199013D02*
X1198898D01*
G01X1198169D02*
X1198246D01*
G01X1198265Y881193D02*
X1198150D01*
G01X1197996Y881444D02*
X1197900D01*
G01X1198150Y881695D02*
X1198246D01*
G01X1198130Y881905D02*
X1198265D01*
G01X1198898Y882114D02*
X1198706D01*
G01X1199013D02*
X1199339D01*
G01X1199837Y882282D02*
X1200183D01*
G01X1199013Y882365D02*
X1199473D01*
G01X1198706D02*
X1198898D01*
G01X1199819Y882449D02*
X1200202D01*
G01X1198265Y882742D02*
X1198130D01*
G01X1198246Y882952D02*
X1198150D01*
G01X1200279D02*
X1200394D01*
G01X1199627D02*
X1199742D01*
G01X1198898D02*
X1199013D01*
G01X1203051Y883464D02*
X1200886D01*
G01X1199902D02*
X1197736D01*
G01X1196752D02*
X1194587D01*
G01X1193602D02*
X1191437D01*
G01X1190453D02*
X1188287D01*
G01X1187303D02*
X1185138D01*
G01X1184154D02*
X1181988D01*
G01X1181004D02*
X1178839D01*
G01X1198552Y882114D02*
X1198533Y882407D01*
G01X1177854Y892519D02*
Y883464D01*
G01X1178839D02*
Y892519D01*
G01X1181004D02*
Y883464D01*
G01X1181988D02*
Y892519D01*
G01X1184154D02*
Y883464D01*
G01X1185138D02*
Y892519D01*
G01X1187303D02*
Y883464D01*
G01X1188287D02*
Y892519D01*
G01X1190453D02*
Y883464D01*
G01X1191437D02*
Y892519D01*
G01X1193602D02*
Y883464D01*
G01X1194587D02*
Y892519D01*
G01X1196752D02*
Y883464D01*
G01X1197736D02*
Y890845D01*
G01X1197862Y882407D02*
Y882198D01*
G01X1197958Y882365D02*
Y882240D01*
G01X1198437D02*
Y882365D01*
G01X1198456Y881905D02*
Y881821D01*
G01X1198552D02*
Y882114D01*
G01X1198706D02*
Y882365D01*
G01X1198898D02*
Y882952D01*
G01Y880983D02*
Y882114D01*
G01X1199013Y882952D02*
Y882365D01*
G01Y881318D02*
Y882114D01*
G01X1199473Y882365D02*
Y882114D01*
G01X1199902Y890845D02*
Y883464D01*
G01X1200886D02*
Y892519D01*
G01X1178730Y861505D02*
X1179469Y861254D01*
G01X1197862Y882198D02*
X1197900Y881988D01*
G01X1198533Y882407D02*
X1198495Y882617D01*
G01X1199933Y880983D02*
X1199627Y882952D01*
G01X1197900Y881444D02*
X1197919Y881318D01*
G01X1197958Y882240D02*
X1197977Y882114D01*
G01X1198437Y882365D02*
X1198418Y882491D01*
G01X1200010Y881151D02*
X1199837Y882282D01*
G01X1199742Y882952D02*
X1199819Y882449D01*
G01X1198073Y881025D02*
X1198169Y880983D01*
G01X1198054Y881737D02*
X1198150Y881695D01*
G01X1198341Y882910D02*
X1198246Y882952D01*
G01X1178730Y860249D02*
X1178238Y860500D01*
G01X1178976Y859997D02*
X1178730Y860249D01*
G01X1179469Y861254D02*
X1179961Y860751D01*
G01X1179222Y859495D02*
X1178976Y859997D01*
G01X1197900Y881988D02*
X1197958Y881863D01*
G01X1197977Y882114D02*
X1198015Y882030D01*
G01X1179961Y860751D02*
X1180453Y859495D01*
G01X1197919Y881318D02*
X1197977Y881151D01*
G01X1198495Y882617D02*
X1198437Y882784D01*
G01X1198035Y881318D02*
X1197996Y881444D01*
G01X1198418Y882491D02*
X1198380Y882617D01*
G01X1198150Y881193D02*
X1198092Y881234D01*
G01X1198073Y881946D02*
X1198130Y881905D01*
G01X1198322Y882700D02*
X1198265Y882742D01*
G01X1197977Y881151D02*
X1198073Y881025D01*
G01X1197958Y881863D02*
X1198054Y881737D01*
G01X1198437Y882784D02*
X1198341Y882910D01*
G01X1198092Y881234D02*
X1198035Y881318D01*
G01X1198015Y882030D02*
X1198073Y881946D01*
G01X1198380Y882617D02*
X1198322Y882700D01*
G01X1180453Y853464D02*
X1179222D01*
G01D02*
Y859495D01*
G01X1180453D02*
Y853464D01*
G01X1205512Y896456D02*
Y943291D01*
G01X1206847Y892519D02*
X1207913Y893267D01*
G01X1207638Y898030D02*
X1206704Y896683D01*
G01X1206539Y896964D02*
X1207308Y898030D01*
G01X1206539Y896459D02*
X1205770Y895393D01*
G01X1205440D02*
X1206374Y896683D01*
G01X1212831Y892519D02*
X1206847D01*
G01X1207638Y895393D02*
X1207308D01*
G01X1205770D02*
X1205440D01*
G01Y898030D02*
X1205770D01*
G01X1207308D02*
X1207638D01*
G01X1206847Y892519D02*
X1207913Y891724D01*
G01X1201575Y897637D02*
X1205512Y892519D01*
G01X1201575Y897637D02*
X1205512Y892519D01*
G01X1206704Y896683D02*
X1207638Y895393D01*
G01X1207308D02*
X1206539Y896459D01*
G01X1205770Y898030D02*
X1206539Y896964D01*
G01X1206374Y896683D02*
X1205440Y898030D01*
G01X1197736Y890845D02*
X1199902D01*
G01X1181988Y892519D02*
X1184154D01*
G01X1178839D02*
X1181004D01*
G01X1185138D02*
X1187303D01*
G01X1191437D02*
X1193602D01*
G01X1188287D02*
X1190453D01*
G01X1194587D02*
X1196752D01*
G01X1200886D02*
X1203051D01*
G01X1233858Y939354D02*
X1209843D01*
G01X1232104Y-692627D02*
X1221100Y-702854D01*
G01X1251474Y-652231D02*
X1243619Y-674145D01*
G01D02*
X1232104Y-692627D01*
G01X1221756Y-572117D02*
X1217425Y-574086D01*
G01X1221441Y-590660D02*
X1217504D01*
G01X1221441Y-586723D02*
X1217504D01*
G01X1211087Y-585424D02*
X1212976D01*
G01Y-583534D02*
X1211087D01*
G01X1221441Y-581960D02*
X1217504D01*
G01X1221441Y-578023D02*
X1217504D01*
G01X1221441Y-570818D02*
X1217504D01*
G01X1212976Y-583534D02*
X1214551Y-581960D01*
G01X1221756Y-591527D02*
X1219079Y-593495D01*
G01X1221756Y-576842D02*
X1217425Y-574873D01*
G01X1212976Y-585424D02*
X1214551Y-586999D01*
G01X1211087Y-585424D02*
Y-583534D01*
G01X1212976Y-585424D02*
Y-583534D01*
G01X1214551Y-541960D02*
Y-586999D01*
G01X1217425Y-574086D02*
Y-574873D01*
G01X1217504Y-566881D02*
Y-570818D01*
G01Y-578023D02*
Y-581960D01*
G01Y-586723D02*
Y-590660D01*
G01X1221441Y-566881D02*
Y-570818D01*
G01Y-578023D02*
Y-581960D01*
G01Y-586723D02*
Y-590660D01*
G01X1221756Y-556842D02*
Y-572117D01*
G01Y-576842D02*
Y-591527D01*
G01X1212988Y-544337D02*
X1212873Y-544375D01*
G01Y-544149D02*
X1212988Y-544111D01*
G01X1212873Y-544149D02*
X1212988Y-544111D01*
G01Y-544337D02*
X1212873Y-544375D01*
G01X1213143Y-544224D02*
X1212988Y-544337D01*
G01X1213143Y-544224D02*
X1212988Y-544337D01*
G01X1217425Y-554086D02*
X1221756Y-552117D01*
G01X1214551Y-541960D02*
X1212976Y-543534D01*
G01X1212988Y-544111D02*
X1213065Y-544035D01*
G01X1212988Y-544111D02*
X1213065Y-544035D01*
G01X1213258Y-544073D02*
X1213143Y-544224D01*
G01X1213258Y-544073D02*
X1213143Y-544224D01*
G01X1221441Y-558338D02*
X1217504D01*
G01X1213065Y-544035D02*
X1213104Y-543922D01*
G01X1213065Y-544035D02*
X1213104Y-543922D01*
G01X1221441Y-550975D02*
X1217504D01*
G01X1221441Y-547038D02*
X1217504D01*
G01X1211087Y-545424D02*
X1212976D01*
G01X1213296Y-545129D02*
X1211485D01*
G01X1213296D02*
X1211485D01*
G01Y-544903D02*
X1212988D01*
G01X1211485D02*
X1212988D01*
G01X1212719Y-544677D02*
X1213027D01*
G01X1212719D02*
X1213027D01*
G01X1212873Y-544375D02*
X1212719D01*
G01X1212873D02*
X1212719D01*
G01X1212757Y-544149D02*
X1212873D01*
G01X1212757D02*
X1212873D01*
G01X1212976Y-543534D02*
X1211087D01*
G01X1212295Y-543205D02*
X1211485D01*
G01X1213104D02*
X1212526D01*
G01X1212295D02*
X1211485D01*
G01X1213104D02*
X1212526D01*
G01X1211485Y-542979D02*
X1213296D01*
G01X1211485D02*
X1213296D01*
G01Y-543884D02*
X1213258Y-544073D01*
G01X1213296Y-543884D02*
X1213258Y-544073D01*
G01X1221441Y-542590D02*
X1217504D01*
G01X1221441Y-538653D02*
X1217504D01*
G01X1211087Y-545424D02*
Y-543534D01*
G01X1211485Y-543205D02*
Y-542979D01*
G01Y-545129D02*
Y-544903D01*
G01Y-543205D02*
Y-542979D01*
G01Y-545129D02*
Y-544903D01*
G01X1212295Y-543884D02*
Y-543205D01*
G01Y-543884D02*
Y-543205D01*
G01X1212526D02*
Y-543922D01*
G01Y-543205D02*
Y-543922D01*
G01X1212976Y-545424D02*
Y-543534D01*
G01X1213104Y-543922D02*
Y-543205D01*
G01Y-543922D02*
Y-543205D01*
G01X1213296Y-542979D02*
Y-543884D01*
G01Y-544903D02*
Y-545129D01*
G01Y-542979D02*
Y-543884D01*
G01Y-544903D02*
Y-545129D01*
G01X1217425Y-554086D02*
Y-554873D01*
G01X1217504Y-538653D02*
Y-542590D01*
G01Y-547038D02*
Y-550975D01*
G01X1212719Y-544375D02*
X1212603Y-544337D01*
G01X1212641Y-544111D02*
X1212757Y-544149D01*
G01X1212641Y-544111D02*
X1212757Y-544149D01*
G01X1212719Y-544375D02*
X1212603Y-544337D01*
G01X1221756Y-556842D02*
X1217425Y-554873D01*
G01X1221441Y-538653D02*
Y-542590D01*
G01Y-547038D02*
Y-550975D01*
G01X1221756Y-537432D02*
Y-552117D01*
G01X1212603Y-544337D02*
X1212449Y-544224D01*
G01X1212603Y-544337D02*
X1212449Y-544224D01*
G01X1212988Y-544903D02*
X1212719Y-544677D01*
G01X1212988Y-544903D02*
X1212719Y-544677D01*
G01X1213027D02*
X1213296Y-544903D01*
G01X1213027Y-544677D02*
X1213296Y-544903D01*
G01X1212565Y-544035D02*
X1212641Y-544111D01*
G01X1212565Y-544035D02*
X1212641Y-544111D01*
G01X1212976Y-545424D02*
X1214551Y-546999D01*
G01X1212449Y-544224D02*
X1212333Y-544073D01*
G01X1212449Y-544224D02*
X1212333Y-544073D01*
G01X1212526Y-543922D02*
X1212565Y-544035D01*
G01X1212526Y-543922D02*
X1212565Y-544035D01*
G01X1212333Y-544073D02*
X1212295Y-543884D01*
G01X1212333Y-544073D02*
X1212295Y-543884D01*
G01X1221756Y-537432D02*
X1219079Y-535464D01*
G01X1221441Y-566881D02*
X1217504D01*
G01X1221441Y-562275D02*
X1217504D01*
G01Y-558338D02*
Y-562275D01*
G01X1221441Y-558338D02*
Y-562275D01*
G01X1237323Y-486550D02*
X1249476Y-506061D01*
G01X1221333Y-471414D02*
X1237323Y-486550D01*
G01X1255959Y-105512D02*
X1244148D01*
G01X1238302Y-102625D02*
X1238789Y-101903D01*
X1239763Y-101181D01*
X1240738D01*
X1241712Y-101903D01*
X1242200Y-102625D01*
Y-104069D01*
X1241712Y-104790D01*
X1239763Y-106234D01*
G01D02*
X1238789Y-107678D01*
X1238302Y-109843D01*
X1242200D01*
G01X1216865D02*
X1215891Y-109121D01*
X1215403Y-108399D01*
X1214916Y-106956D01*
Y-104069D01*
X1215403Y-102625D01*
X1215891Y-101903D01*
X1216865Y-101181D01*
X1217839Y-101903D01*
X1218326Y-102625D01*
X1218814Y-104069D01*
Y-106956D01*
X1218326Y-108399D01*
X1217839Y-109121D01*
X1216865Y-109843D01*
G01X1232456D02*
X1231481Y-109121D01*
X1230994Y-108399D01*
X1230507Y-106956D01*
Y-104069D01*
X1230994Y-102625D01*
X1231481Y-101903D01*
X1232456Y-101181D01*
X1233430Y-101903D01*
X1233917Y-102625D01*
X1234404Y-104069D01*
Y-106956D01*
X1233917Y-108399D01*
X1233430Y-109121D01*
X1232456Y-109843D01*
G01X1222711Y-106956D02*
X1223198Y-105512D01*
X1224660Y-104790D01*
X1226122Y-105512D01*
X1226609Y-106956D01*
X1226122Y-108399D01*
X1225635Y-109121D01*
X1224660Y-109843D01*
X1223686Y-109121D01*
X1223198Y-108399D01*
X1222711Y-106956D01*
Y-104069D01*
X1223198Y-102625D01*
X1223686Y-101903D01*
X1224660Y-101181D01*
X1225635Y-101903D01*
X1226122Y-102625D01*
G01X1243539Y-31255D02*
X1235371Y-31261D01*
G01X1243199Y-39469D02*
X1239561D01*
G01X1243002Y-39154D02*
X1239561D01*
G01X1244097Y-34338D02*
X1244031D01*
G01X1243539Y-33775D02*
X1235356D01*
G01X1243199Y-33249D02*
X1239561D01*
G01X1243539Y-33102D02*
X1235370D01*
G01Y-32967D02*
X1243539D01*
G01X1235370Y-30829D02*
X1243539D01*
G01Y-30744D02*
X1235370D01*
G01Y-33647D02*
Y-17548D01*
G01X1235369Y-33663D02*
Y-33682D01*
G01X1238971Y-38879D02*
Y-33339D01*
G01X1243539Y-17548D02*
Y-33845D01*
G01X1243593Y-33339D02*
Y-38564D01*
G01X1243789Y-33839D02*
Y-38879D01*
G01X1235369Y-33663D02*
X1235370Y-33621D01*
G01Y-33647D02*
X1235369Y-33682D01*
G01D02*
X1235367Y-33713D01*
X1235362Y-33744D01*
X1235356Y-33775D01*
G01D02*
X1235362Y-33738D01*
X1235367Y-33701D01*
X1235369Y-33663D01*
G01X1243002Y-39154D02*
G03X1243593Y-38564I0J591D01*
G01X1243199Y-39469D02*
G03X1243789Y-38879I0J590D01*
G01X1238971D02*
G03X1239561Y-39469I590J0D01*
G01X1238971Y-38564D02*
G03X1239561Y-39154I590J0D01*
G01X1243789Y-33839D02*
G03X1243199Y-33249I-590J0D01*
G01X1239561D02*
G03X1238971Y-33839I0J-590D01*
G01X1243593D02*
G03X1243002Y-33249I-591J-1D01*
G01X1243539Y-33845D02*
G03X1244031Y-34338I492J-1D01*
G01X1244097D02*
G03X1244589Y-33845I0J492D01*
G01X1243593Y-33339D02*
G03X1243002Y-32749I-591J-1D01*
G01X1239561D02*
G03X1238971Y-33339I0J-590D01*
G01X1244039Y-32016D02*
G03X1244539Y-31524I8J492D01*
G01X1243539D02*
G03X1244039Y-32016I492J0D01*
G01X1261344Y-42635D02*
X1231865D01*
G01X1229951Y-41835D02*
X1219951D01*
G01X1230037Y-41635D02*
X1219865D01*
G01X1229951Y-41461D02*
X1219951D01*
G01X1260743Y-41435D02*
X1232466D01*
G01X1219951Y-41403D02*
X1229951D01*
G01X1219951Y-41135D02*
X1229951D01*
G01Y-41107D02*
X1219951D01*
G01X1220617Y-39467D02*
X1229285D01*
G01X1228951Y-39440D02*
X1220951D01*
G01X1219636Y-34319D02*
X1230266D01*
G01X1233884Y-33775D02*
X1225687D01*
G01X1224215D02*
X1216017D01*
G01X1233870Y-33102D02*
X1225701D01*
G01X1224201D02*
X1216031D01*
G01Y-32967D02*
X1224201D01*
G01X1225701D02*
X1233870D01*
G01Y-31261D02*
X1225702D01*
G01X1224200D02*
X1216032D01*
G01X1216031Y-30829D02*
X1224201D01*
G01X1225701D02*
X1233870D01*
G01Y-30744D02*
X1225701D01*
G01X1224201D02*
X1216031D01*
G01X1231158Y-42342D02*
X1230744Y-41928D01*
G01X1214546Y-33775D02*
X1214540Y-33744D01*
X1214535Y-33713D01*
X1214533Y-33682D01*
G01X1224215Y-33775D02*
X1224209Y-33744D01*
X1224205Y-33713D01*
X1224202Y-33682D01*
G01X1233884Y-33775D02*
X1233878Y-33744D01*
X1233874Y-33713D01*
X1233871Y-33682D01*
G01X1214533Y-33663D02*
X1214535Y-33701D01*
X1214540Y-33738D01*
X1214546Y-33775D01*
G01X1224202Y-33663D02*
X1224205Y-33701D01*
X1224209Y-33738D01*
X1224215Y-33775D01*
G01X1233871Y-33663D02*
X1233874Y-33701D01*
X1233878Y-33738D01*
X1233884Y-33775D01*
G01X1214533Y-33682D02*
X1214531Y-33647D01*
G01X1224202Y-33682D02*
X1224201Y-33647D01*
G01X1233871Y-33682D02*
X1233870Y-33647D01*
G01X1214531Y-33621D02*
X1214533Y-33663D01*
G01X1224201Y-33621D02*
X1224202Y-33663D01*
G01X1233870Y-33621D02*
X1233871Y-33663D01*
G01X1210931Y-33339D02*
Y-38564D01*
G01X1211128Y-33839D02*
Y-38879D01*
G01X1214533Y-33682D02*
Y-33663D01*
G01X1214531Y-17548D02*
Y-33647D01*
G01X1216031D02*
Y-17548D01*
G01Y-33663D02*
Y-33682D01*
G01X1219636Y-34319D02*
Y-32749D01*
G01X1219951Y-41832D02*
Y-40398D01*
G01X1222067Y-34319D02*
Y-32749D01*
G01X1222687D02*
Y-34319D01*
G01X1224202Y-33682D02*
Y-33663D01*
G01X1224201Y-17548D02*
Y-33647D01*
G01X1225701D02*
Y-17548D01*
G01X1225700Y-33663D02*
Y-33682D01*
G01X1227215Y-34319D02*
Y-32749D01*
G01X1227835D02*
Y-34319D01*
G01X1229951Y-40398D02*
Y-41832D01*
G01X1230266Y-32749D02*
Y-34319D01*
G01X1216031Y-33663D02*
Y-33621D01*
G01Y-33647D02*
Y-33682D01*
G01X1233871Y-33663D02*
Y-33682D01*
G01X1233870Y-17548D02*
Y-33647D01*
G01X1225700Y-33663D02*
X1225701Y-33621D01*
G01Y-33647D02*
X1225700Y-33682D01*
G01X1216031D02*
X1216028Y-33713D01*
X1216024Y-33744D01*
X1216017Y-33775D01*
G01X1225700Y-33682D02*
X1225697Y-33713D01*
X1225693Y-33744D01*
X1225687Y-33775D01*
G01X1216017D02*
X1216024Y-33738D01*
X1216028Y-33701D01*
X1216031Y-33663D01*
G01X1225687Y-33775D02*
X1225693Y-33738D01*
X1225697Y-33701D01*
X1225700Y-33663D01*
G01X1219158Y-41928D02*
X1218744Y-42342D01*
G01X1218037Y-42635D02*
G03X1218744Y-42342I0J1000D01*
G01X1217436Y-41435D02*
G03X1218394Y-40679I1J984D01*
G01X1219951Y-40845D02*
G03X1218394Y-40679I-787J0D01*
G01X1214546Y-33775D02*
G03X1215281Y-34378I734J145D01*
G01D02*
G03X1216017Y-33775I2J748D01*
G01X1215281Y-32016D02*
G03X1216031Y-31261I2J748D01*
G01X1214532D02*
G03X1215281Y-32016I748J-7D01*
G01X1231158Y-42342D02*
G03X1231865Y-42635I707J707D01*
G01X1230744Y-41928D02*
G03X1230037Y-41635I-707J-707D01*
G01X1219865D02*
G03X1219158Y-41928I0J-1000D01*
G01X1220951Y-39440D02*
G03X1219951Y-40440I0J-1000D01*
G01X1229951D02*
G03X1228951Y-39440I-1000J0D01*
G01X1231506Y-40670D02*
G03X1232466Y-41435I960J219D01*
G01X1229951Y-40398D02*
G03X1229285Y-39467I-984J0D01*
G01X1220617D02*
G03X1219951Y-40398I318J-931D01*
G01X1231506Y-40670D02*
G03X1229951Y-40845I-768J-175D01*
G01X1224215Y-33775D02*
G03X1224951Y-34378I734J145D01*
G01D02*
G03X1225687Y-33775I2J748D01*
G01X1233884D02*
G03X1234620Y-34378I734J145D01*
G01D02*
G03X1235356Y-33775I2J748D01*
G01X1234620Y-32016D02*
G03X1235370Y-31261I2J748D01*
G01X1233870D02*
G03X1234620Y-32016I748J-7D01*
G01X1224951D02*
G03X1225701Y-31261I2J748D01*
G01X1224201D02*
G03X1224951Y-32016I748J-7D01*
G01X1236157Y-16798D02*
X1236005Y-16813D01*
X1235857Y-16857D01*
X1235722Y-16929D01*
X1235601Y-17028D01*
X1235503Y-17146D01*
X1235431Y-17281D01*
X1235386Y-17427D01*
X1235370Y-17582D01*
G01X1238465Y-16904D02*
X1238307Y-16918D01*
X1238155Y-16958D01*
X1238016Y-17023D01*
X1237893Y-17112D01*
X1237796Y-17218D01*
X1237725Y-17341D01*
G01X1241743Y-18862D02*
X1237167D01*
G01Y-18845D02*
X1241743D01*
G01X1243539Y-18516D02*
X1235370D01*
G01Y-18481D02*
X1243539D01*
G01Y-18138D02*
X1235370D01*
G01Y-18104D02*
X1243539D01*
G01X1237579Y-17890D02*
X1241331D01*
G01Y-17679D02*
X1237579D01*
G01X1238465Y-17116D02*
X1240445D01*
G01Y-16904D02*
X1238465D01*
G01X1236157Y-16798D02*
X1242752D01*
G01Y-16764D02*
X1236157D01*
G01X1250561Y-8741D02*
X1242648D01*
G01X1240445Y-17116D02*
X1240603Y-17129D01*
X1240755Y-17170D01*
X1240894Y-17234D01*
X1241017Y-17323D01*
X1241114Y-17430D01*
X1241185Y-17553D01*
G01X1242752Y-16764D02*
X1242905Y-16779D01*
X1243052Y-16823D01*
X1243188Y-16895D01*
X1243309Y-16994D01*
X1243406Y-17112D01*
X1243479Y-17247D01*
X1243524Y-17393D01*
X1243539Y-17548D01*
G01X1241185Y-17341D02*
X1241115Y-17220D01*
X1241019Y-17114D01*
X1240899Y-17025D01*
X1240757Y-16959D01*
X1240606Y-16918D01*
X1240445Y-16904D01*
G01X1241331Y-17890D02*
X1241468Y-18195D01*
X1241606Y-18522D01*
X1241743Y-18862D01*
G01X1241185Y-17553D02*
X1241331Y-17890D01*
G01Y-17679D02*
X1241185Y-17341D01*
G01X1241723Y-14327D02*
X1244480Y-21902D01*
G01X1241743Y-18845D02*
X1241606Y-18437D01*
X1241468Y-18044D01*
X1241331Y-17679D01*
G01X1243539Y-17582D02*
X1243524Y-17430D01*
X1243480Y-17284D01*
X1243408Y-17149D01*
X1243309Y-17028D01*
X1243190Y-16931D01*
X1243055Y-16858D01*
X1242908Y-16814D01*
X1242752Y-16798D01*
G01X1236157D02*
Y-16764D01*
G01X1237167Y-18862D02*
Y-18845D01*
G01X1237579Y-17679D02*
Y-17890D01*
G01X1237725Y-17553D02*
Y-17341D01*
G01X1238422Y-17318D02*
Y-6688D01*
G01Y-1570D02*
Y9060D01*
G01X1238465Y-16904D02*
Y-17116D01*
G01X1240445D02*
Y-16904D01*
G01X1241185Y-17341D02*
Y-17553D01*
G01X1241331Y-17890D02*
Y-17679D01*
G01X1241664Y-9725D02*
Y-13990D01*
G01X1241743Y-18845D02*
Y-18862D01*
G01X1242752Y-16764D02*
Y-16798D01*
G01X1235370Y-17548D02*
X1235385Y-17396D01*
X1235430Y-17249D01*
X1235502Y-17114D01*
X1235601Y-16994D01*
X1235720Y-16896D01*
X1235855Y-16824D01*
X1236002Y-16779D01*
X1236157Y-16764D01*
G01X1237579Y-17679D02*
X1237442Y-18044D01*
X1237304Y-18437D01*
X1237167Y-18845D01*
G01Y-18862D02*
X1237304Y-18522D01*
X1237442Y-18195D01*
X1237579Y-17890D01*
G01X1237725Y-17341D02*
X1237579Y-17679D01*
G01Y-17890D02*
X1237725Y-17553D01*
G01D02*
X1237794Y-17432D01*
X1237891Y-17325D01*
X1238011Y-17237D01*
X1238152Y-17170D01*
X1238304Y-17130D01*
X1238465Y-17116D01*
G01X1242648Y-8741D02*
G03X1241664Y-9725I0J-984D01*
G01Y-13990D02*
G03X1241723Y-14327I984J-1D01*
G01X1235370Y-24077D02*
X1243539D01*
G01Y-23942D02*
X1235370D01*
G01X1243512Y-23756D02*
X1235398D01*
G01Y-23671D02*
X1243512D01*
G01X1235532Y-23348D02*
X1243378D01*
G01Y-23331D02*
X1235532D01*
G01X1235370Y-23097D02*
X1243539D01*
G01Y-23063D02*
X1235370D01*
G01X1243492Y-23615D02*
X1243378Y-23331D01*
G01X1241743Y-18862D02*
X1243378Y-23348D01*
G01Y-23331D02*
X1241743Y-18845D01*
G01X1243378Y-23348D02*
X1243492Y-23689D01*
G01D02*
X1243499Y-23711D01*
X1243506Y-23734D01*
X1243512Y-23756D01*
G01Y-23671D02*
X1243506Y-23652D01*
X1243499Y-23633D01*
X1243492Y-23615D01*
G01X1243512Y-23756D02*
X1243520Y-23787D01*
X1243527Y-23821D01*
X1243532Y-23853D01*
X1243536Y-23888D01*
X1243539Y-23923D01*
Y-23958D01*
G01Y-23872D02*
Y-23840D01*
X1243537Y-23805D01*
X1243533Y-23773D01*
X1243528Y-23739D01*
X1243520Y-23705D01*
X1243512Y-23671D01*
G01X1235398Y-23756D02*
Y-23671D01*
G01X1235418Y-23615D02*
Y-23689D01*
G01X1235532Y-23331D02*
Y-23339D01*
G01D02*
Y-23348D01*
G01X1243492Y-23689D02*
Y-23615D01*
G01X1243512Y-23671D02*
Y-23756D01*
G01X1243378Y-23348D02*
Y-23331D01*
G01X1235370Y-23958D02*
X1235371Y-23925D01*
X1235373Y-23891D01*
X1235377Y-23858D01*
X1235382Y-23824D01*
X1235389Y-23790D01*
X1235398Y-23756D01*
G01Y-23671D02*
X1235390Y-23702D01*
X1235383Y-23736D01*
X1235378Y-23768D01*
X1235374Y-23803D01*
X1235371Y-23838D01*
X1235370Y-23872D01*
G01X1235398Y-23756D02*
X1235404Y-23734D01*
X1235411Y-23711D01*
X1235418Y-23689D01*
G01D02*
X1235532Y-23348D01*
G01X1237167Y-18845D02*
X1235532Y-23331D01*
G01Y-23348D02*
X1237167Y-18862D01*
G01X1235418Y-23615D02*
X1235411Y-23633D01*
X1235404Y-23652D01*
X1235398Y-23671D01*
G01X1235532Y-23331D02*
X1235418Y-23615D01*
G01X1226488Y-16798D02*
X1226335Y-16813D01*
X1226188Y-16857D01*
X1226053Y-16929D01*
X1225931Y-17028D01*
X1225834Y-17146D01*
X1225761Y-17281D01*
X1225717Y-17427D01*
X1225701Y-17582D01*
G01X1216819Y-16798D02*
X1216666Y-16813D01*
X1216519Y-16857D01*
X1216383Y-16929D01*
X1216262Y-17028D01*
X1216165Y-17146D01*
X1216092Y-17281D01*
X1216047Y-17427D01*
X1216031Y-17582D01*
G01X1226488Y-16904D02*
X1226335Y-16917D01*
X1226188Y-16954D01*
X1226053Y-17015D01*
X1225931Y-17099D01*
X1225834Y-17199D01*
X1225761Y-17313D01*
X1225717Y-17437D01*
X1225701Y-17568D01*
G01X1216819Y-16904D02*
X1216666Y-16917D01*
X1216519Y-16954D01*
X1216383Y-17015D01*
X1216262Y-17099D01*
X1216165Y-17199D01*
X1216092Y-17313D01*
X1216047Y-17437D01*
X1216031Y-17568D01*
G01X1233870Y-18862D02*
X1225701D01*
G01X1224201D02*
X1216031D01*
G01Y-18845D02*
X1224201D01*
G01X1225701D02*
X1233870D01*
G01Y-18516D02*
X1225701D01*
G01X1224201D02*
X1216031D01*
G01Y-18481D02*
X1224201D01*
G01X1225701D02*
X1233870D01*
G01Y-18138D02*
X1225701D01*
G01X1224201D02*
X1216031D01*
G01Y-18104D02*
X1224201D01*
G01X1225701D02*
X1233870D01*
G01X1216031Y-17890D02*
X1224201D01*
G01X1225701D02*
X1233870D01*
G01Y-17679D02*
X1225701D01*
G01X1224201D02*
X1216031D01*
G01X1238422Y-17318D02*
X1233500D01*
G01X1216402D02*
X1211480D01*
G01X1216819Y-17116D02*
X1223413D01*
G01X1226488D02*
X1233083D01*
G01Y-16904D02*
X1226488D01*
G01X1223413D02*
X1216819D01*
G01Y-16798D02*
X1223413D01*
G01X1226488D02*
X1233083D01*
G01Y-16764D02*
X1226488D01*
G01X1223413D02*
X1216819D01*
G01X1238422Y-14786D02*
X1233500D01*
G01X1216402D02*
X1211480D01*
G01Y-14307D02*
X1216402D01*
G01X1233500D02*
X1238422D01*
G01Y-9699D02*
X1233500D01*
G01X1216402D02*
X1211480D01*
G01Y-9220D02*
X1216402D01*
G01X1233500D02*
X1238422D01*
G01X1211480Y-6688D02*
X1216402D01*
G01X1233500D02*
X1238422D01*
G01Y-1570D02*
X1233500D01*
G01X1216402D02*
X1211480D01*
G01X1238422Y962D02*
X1233500D01*
G01X1216402D02*
X1211480D01*
G01Y1441D02*
X1216402D01*
G01X1233500D02*
X1238422D01*
G01Y6049D02*
X1233500D01*
G01X1216402D02*
X1211480D01*
G01X1223413Y-17116D02*
X1223567Y-17128D01*
X1223714Y-17166D01*
X1223849Y-17227D01*
X1223970Y-17310D01*
X1224068Y-17410D01*
X1224141Y-17525D01*
X1224185Y-17649D01*
X1224201Y-17780D01*
G01X1233083Y-17116D02*
X1233236Y-17128D01*
X1233383Y-17166D01*
X1233519Y-17227D01*
X1233640Y-17310D01*
X1233737Y-17410D01*
X1233810Y-17525D01*
X1233855Y-17649D01*
X1233870Y-17780D01*
G01X1211437Y-17116D02*
X1211595Y-17129D01*
X1211747Y-17170D01*
X1211886Y-17234D01*
X1212009Y-17323D01*
X1212106Y-17430D01*
X1212177Y-17553D01*
G01X1213744Y-16764D02*
X1213897Y-16779D01*
X1214044Y-16823D01*
X1214180Y-16895D01*
X1214301Y-16994D01*
X1214398Y-17112D01*
X1214471Y-17247D01*
X1214516Y-17393D01*
X1214531Y-17548D01*
G01X1223413Y-16764D02*
X1223567Y-16779D01*
X1223714Y-16823D01*
X1223849Y-16895D01*
X1223970Y-16994D01*
X1224068Y-17112D01*
X1224141Y-17247D01*
X1224185Y-17393D01*
X1224201Y-17548D01*
G01X1233083Y-16764D02*
X1233236Y-16779D01*
X1233383Y-16823D01*
X1233519Y-16895D01*
X1233640Y-16994D01*
X1233737Y-17112D01*
X1233810Y-17247D01*
X1233855Y-17393D01*
X1233870Y-17548D01*
G01X1212177Y-17341D02*
X1212107Y-17220D01*
X1212011Y-17114D01*
X1211891Y-17025D01*
X1211750Y-16959D01*
X1211598Y-16918D01*
X1211437Y-16904D01*
G01X1212323Y-17890D02*
X1212460Y-18195D01*
X1212598Y-18522D01*
X1212735Y-18862D01*
G01X1212177Y-17553D02*
X1212323Y-17890D01*
G01Y-17679D02*
X1212177Y-17341D01*
G01X1212735Y-18845D02*
X1212598Y-18437D01*
X1212460Y-18044D01*
X1212323Y-17679D01*
G01X1214531Y-17582D02*
X1214517Y-17430D01*
X1214472Y-17284D01*
X1214400Y-17149D01*
X1214301Y-17028D01*
X1214182Y-16931D01*
X1214047Y-16858D01*
X1213900Y-16814D01*
X1213744Y-16798D01*
G01X1224201Y-17568D02*
X1224186Y-17439D01*
X1224142Y-17315D01*
X1224069Y-17201D01*
X1223970Y-17099D01*
X1223852Y-17016D01*
X1223716Y-16955D01*
X1223569Y-16917D01*
X1223413Y-16904D01*
G01X1224201Y-17582D02*
X1224186Y-17430D01*
X1224142Y-17284D01*
X1224069Y-17149D01*
X1223970Y-17028D01*
X1223852Y-16931D01*
X1223716Y-16858D01*
X1223569Y-16814D01*
X1223413Y-16798D01*
G01X1233870Y-17582D02*
X1233855Y-17430D01*
X1233811Y-17284D01*
X1233739Y-17149D01*
X1233640Y-17028D01*
X1233521Y-16931D01*
X1233385Y-16858D01*
X1233239Y-16814D01*
X1233083Y-16798D01*
G01X1211437Y-17116D02*
Y-16904D01*
G01X1211480Y9060D02*
Y-1570D01*
G01Y-6688D02*
Y-17318D01*
G01X1212177Y-17341D02*
Y-17553D01*
G01X1212323Y-17890D02*
Y-17679D01*
G01X1212735Y-18845D02*
Y-18862D01*
G01X1213744Y-16764D02*
Y-16798D01*
G01X1216402Y-17318D02*
Y-6688D01*
G01Y-1570D02*
Y9060D01*
G01X1216819Y-16904D02*
Y-17116D01*
G01Y-16798D02*
Y-16764D01*
G01X1223413D02*
Y-16798D01*
G01Y-17116D02*
Y-16904D01*
G01X1226488D02*
Y-17116D01*
G01Y-16798D02*
Y-16764D01*
G01X1233870Y-17568D02*
X1233855Y-17439D01*
X1233811Y-17315D01*
X1233739Y-17201D01*
X1233640Y-17099D01*
X1233521Y-17016D01*
X1233385Y-16955D01*
X1233239Y-16917D01*
X1233083Y-16904D01*
G01Y-16764D02*
Y-16798D01*
G01Y-17116D02*
Y-16904D01*
G01X1233500Y9060D02*
Y-1570D01*
G01Y-6688D02*
Y-17318D01*
G01X1216031Y-17548D02*
X1216047Y-17396D01*
X1216091Y-17249D01*
X1216163Y-17114D01*
X1216262Y-16994D01*
X1216381Y-16896D01*
X1216517Y-16824D01*
X1216663Y-16779D01*
X1216819Y-16764D01*
G01X1225701Y-17548D02*
X1225716Y-17396D01*
X1225760Y-17249D01*
X1225833Y-17114D01*
X1225931Y-16994D01*
X1226050Y-16896D01*
X1226186Y-16824D01*
X1226333Y-16779D01*
X1226488Y-16764D01*
G01X1216031Y-17780D02*
X1216047Y-17651D01*
X1216091Y-17527D01*
X1216163Y-17412D01*
X1216262Y-17310D01*
X1216381Y-17228D01*
X1216517Y-17167D01*
X1216663Y-17129D01*
X1216819Y-17116D01*
G01X1225701Y-17780D02*
X1225716Y-17651D01*
X1225760Y-17527D01*
X1225833Y-17412D01*
X1225931Y-17310D01*
X1226050Y-17228D01*
X1226186Y-17167D01*
X1226333Y-17129D01*
X1226488Y-17116D01*
G01X1216031Y-24077D02*
X1224201D01*
G01X1225701D02*
X1233870D01*
G01Y-23942D02*
X1225701D01*
G01X1224201D02*
X1216031D01*
G01X1233870Y-23756D02*
X1225701D01*
G01X1224201D02*
X1216031D01*
G01Y-23671D02*
X1224201D01*
G01X1225701D02*
X1233870D01*
G01X1216031Y-23348D02*
X1224201D01*
G01X1225701D02*
X1233870D01*
G01Y-23331D02*
X1225701D01*
G01X1224201D02*
X1216031D01*
G01Y-23097D02*
X1224201D01*
G01X1225701D02*
X1233870D01*
G01Y-23063D02*
X1225701D01*
G01X1224201D02*
X1216031D01*
G01X1214484Y-23615D02*
X1214370Y-23331D01*
G01X1212735Y-18862D02*
X1214370Y-23348D01*
G01Y-23331D02*
X1212735Y-18845D01*
G01X1214370Y-23348D02*
X1214484Y-23689D01*
G01D02*
X1214491Y-23711D01*
X1214498Y-23734D01*
X1214504Y-23756D01*
G01Y-23671D02*
X1214498Y-23652D01*
X1214491Y-23633D01*
X1214484Y-23615D01*
G01X1214504Y-23756D02*
X1214512Y-23787D01*
X1214519Y-23821D01*
X1214524Y-23853D01*
X1214528Y-23888D01*
X1214531Y-23923D01*
Y-23958D01*
G01Y-23872D02*
Y-23840D01*
X1214529Y-23805D01*
X1214525Y-23773D01*
X1214520Y-23739D01*
X1214513Y-23705D01*
X1214504Y-23671D01*
G01X1214484Y-23689D02*
Y-23615D01*
G01X1214504Y-23671D02*
Y-23756D01*
G01X1214370Y-23348D02*
Y-23331D01*
G01X1236388Y18393D02*
X1237088D01*
G01Y21371D02*
X1236388D01*
G01X1237088Y24336D02*
X1236388D01*
G01X1237088Y24561D02*
X1236388D01*
G01X1234852Y38588D02*
X1234985Y38552D01*
X1235104Y38447D01*
X1235187Y38288D01*
X1235219Y38088D01*
G01X1235187Y44408D02*
Y36767D01*
G01X1235219Y43930D02*
Y38088D01*
G01X1236388Y24561D02*
Y18393D01*
G01X1237088Y24561D02*
Y18393D01*
G01X1240380Y35141D02*
Y14955D01*
G01D02*
X1241561Y11019D01*
G01X1240380Y14955D02*
X1241561Y11019D01*
G01X1242545D02*
Y44408D01*
G01X1215416Y38588D02*
X1215135Y38547D01*
X1214902Y38441D01*
X1214741Y38279D01*
X1214683Y38088D01*
G01X1226396Y12877D02*
X1228396D01*
G01X1226396Y14058D02*
X1227396D01*
G01X1212766Y18393D02*
X1213466D01*
G01X1215719D02*
X1216419D01*
G01X1218671D02*
X1219371D01*
G01X1224577D02*
X1225277D01*
G01X1221624D02*
X1222324D01*
G01X1227530D02*
X1228230D01*
G01X1233435D02*
X1234135D01*
G01X1230483D02*
X1231183D01*
G01X1227396Y18585D02*
X1226396D01*
G01X1228396Y19766D02*
X1226396D01*
G01X1234135Y21371D02*
X1233435D01*
G01X1231183D02*
X1230483D01*
G01X1228230D02*
X1227530D01*
G01X1225277D02*
X1224577D01*
G01X1222324D02*
X1221624D01*
G01X1216419D02*
X1215719D01*
G01X1219371D02*
X1218671D01*
G01X1213466D02*
X1212766D01*
G01X1234135Y24336D02*
X1233435D01*
G01X1231183D02*
X1230483D01*
G01X1228230D02*
X1227530D01*
G01X1225277D02*
X1224577D01*
G01X1222324D02*
X1221624D01*
G01X1216419D02*
X1215719D01*
G01X1219371D02*
X1218671D01*
G01X1213466D02*
X1212766D01*
G01X1234135Y24561D02*
X1233435D01*
G01X1231183D02*
X1230483D01*
G01X1228230D02*
X1227530D01*
G01X1225277D02*
X1224577D01*
G01X1222324D02*
X1221624D01*
G01X1219371D02*
X1218671D01*
G01X1216419D02*
X1215719D01*
G01X1213466D02*
X1212766D01*
G01X1228606Y27251D02*
X1225654D01*
G01X1224654D02*
X1221296D01*
G01X1228606Y28251D02*
X1225654D01*
G01X1224654D02*
X1221296D01*
G01X1228606Y29251D02*
X1225654D01*
G01X1224654D02*
X1221296D01*
G01X1228606Y29501D02*
X1225654D01*
G01X1224654D02*
X1221296D01*
G01X1228213Y29645D02*
X1221689D01*
G01X1226244Y31367D02*
X1228016D01*
G01X1224063Y32851D02*
X1221886D01*
G01X1233139Y35857D02*
X1216715D01*
G01X1242545Y36767D02*
X1232093D01*
G01X1234719Y37588D02*
X1232825D01*
G01X1217077D02*
X1215183D01*
G01X1215050Y38588D02*
X1219518D01*
G01X1230384D02*
X1234852D01*
G01X1231056Y39032D02*
X1231030D01*
G01X1218825D02*
X1218798D01*
G01X1235187Y39392D02*
X1233219D01*
G01X1216683D02*
X1214715D01*
G01X1223572Y34687D02*
X1224402Y34292D01*
X1225334Y34145D01*
X1226264Y34260D01*
X1227150Y34632D01*
X1227929Y35247D01*
X1228526Y36062D01*
X1228906Y37073D01*
G01X1223572Y34686D02*
X1224383Y34298D01*
X1225306Y34147D01*
X1226237Y34252D01*
X1227132Y34621D01*
X1227920Y35238D01*
X1228522Y36057D01*
X1228905Y37073D01*
G01X1221689Y29645D02*
X1217077Y34257D01*
G01X1233139Y35857D02*
X1231056Y37940D01*
G01X1231030Y39032D02*
X1228077Y41985D01*
G01X1228489Y39341D02*
X1227816Y40116D01*
X1226990Y40669D01*
X1226043Y40987D01*
X1225055Y41034D01*
X1224120Y40811D01*
X1223286Y40337D01*
X1222656Y39675D01*
G01X1231895Y36569D02*
X1232959Y35267D01*
G01X1231030Y38069D02*
X1232093Y36767D01*
G01X1228489Y39341D02*
X1227831Y40265D01*
X1226933Y40969D01*
X1225833Y41398D01*
X1224676Y41489D01*
X1223537Y41238D01*
X1222535Y40682D01*
X1221725Y39846D01*
X1221191Y38822D01*
X1220975Y37666D01*
X1221104Y36502D01*
X1221552Y35448D01*
X1222306Y34547D01*
X1223298Y33899D01*
X1224437Y33574D01*
X1225601Y33592D01*
X1226711Y33950D01*
X1227670Y34614D01*
X1228407Y35547D01*
X1228837Y36666D01*
X1228915Y37866D01*
X1228618Y39065D01*
X1228010Y40063D01*
X1227153Y40833D01*
X1226060Y41340D01*
X1224895Y41497D01*
X1223753Y41313D01*
X1222685Y40790D01*
X1221843Y40005D01*
X1221260Y39005D01*
X1220986Y37852D01*
X1221054Y36714D01*
X1221448Y35630D01*
X1222144Y34697D01*
X1223096Y33999D01*
X1224195Y33612D01*
X1225347Y33560D01*
X1226463Y33837D01*
X1227404Y34385D01*
X1228181Y35195D01*
X1228719Y36241D01*
X1228928Y37379D01*
X1228794Y38551D01*
X1228339Y39606D01*
X1227585Y40501D01*
X1226607Y41136D01*
X1225461Y41464D01*
X1224333Y41451D01*
X1223220Y41101D01*
X1222268Y40458D01*
X1221520Y39533D01*
X1221067Y38387D01*
X1220985Y37197D01*
X1221240Y36081D01*
X1221807Y35079D01*
X1222648Y34274D01*
X1223708Y33738D01*
X1224882Y33540D01*
X1226077Y33702D01*
X1227129Y34188D01*
X1228000Y34961D01*
X1228610Y35956D01*
X1228906Y37089D01*
X1228863Y38249D01*
X1228489Y39341D01*
G01X1231030Y38069D02*
X1231895Y36569D01*
G01X1232959Y35267D02*
X1232093Y36767D01*
G01X1228907Y38246D02*
X1228525Y39363D01*
X1227837Y40321D01*
X1226896Y41039D01*
X1225791Y41452D01*
X1224612Y41526D01*
X1223456Y41253D01*
X1222444Y40664D01*
X1221633Y39792D01*
X1221116Y38731D01*
X1220929Y37567D01*
X1221090Y36392D01*
X1221578Y35327D01*
X1222370Y34434D01*
X1223377Y33817D01*
X1224516Y33520D01*
X1225697Y33566D01*
X1226811Y33953D01*
X1227772Y34651D01*
X1228484Y35597D01*
X1228889Y36703D01*
X1228957Y37880D01*
X1228678Y39030D01*
X1228078Y40048D01*
X1227204Y40850D01*
X1226141Y41361D01*
X1224974Y41540D01*
X1223804Y41373D01*
X1222736Y40876D01*
X1221852Y40083D01*
X1221241Y39072D01*
X1220950Y37928D01*
X1221003Y36749D01*
X1221396Y35636D01*
X1222096Y34685D01*
X1223043Y33978D01*
X1224154Y33577D01*
X1225333Y33515D01*
X1226480Y33799D01*
X1227493Y34402D01*
X1228289Y35274D01*
X1228796Y36340D01*
X1228973Y37508D01*
X1228803Y38676D01*
X1228300Y39745D01*
X1227515Y40618D01*
X1226506Y41228D01*
X1225361Y41519D01*
X1224181Y41466D01*
X1223064Y41070D01*
X1222125Y40380D01*
X1221417Y39439D01*
X1221012Y38330D01*
X1220946Y37152D01*
X1221227Y35999D01*
X1221819Y34995D01*
X1222683Y34197D01*
X1223745Y33682D01*
X1224910Y33497D01*
X1226080Y33658D01*
X1227148Y34150D01*
X1228025Y34925D01*
X1228646Y35930D01*
X1228948Y37069D01*
X1228907Y38246D01*
G01X1228955Y37855D02*
X1228813Y38627D01*
X1228489Y39341D01*
G01X1228905Y37073D02*
X1228863Y38248D01*
X1228469Y39377D01*
X1227786Y40312D01*
X1226850Y41015D01*
X1225711Y41425D01*
X1224510Y41473D01*
X1223331Y41153D01*
X1222369Y40547D01*
X1221624Y39701D01*
X1221135Y38649D01*
X1220973Y37437D01*
X1221189Y36222D01*
X1221707Y35212D01*
X1222512Y34375D01*
X1223510Y33809D01*
X1224624Y33553D01*
X1225843Y33640D01*
X1226950Y34077D01*
X1227834Y34776D01*
X1228491Y35701D01*
X1228864Y36795D01*
X1228907Y37942D01*
X1228604Y39097D01*
X1228002Y40073D01*
X1227130Y40847D01*
X1226111Y41325D01*
X1224966Y41498D01*
X1223750Y41312D01*
X1222724Y40818D01*
X1221882Y40051D01*
X1221271Y39033D01*
X1220990Y37904D01*
X1221047Y36751D01*
X1221452Y35620D01*
X1222148Y34695D01*
X1223046Y34025D01*
X1224135Y33624D01*
X1225343Y33559D01*
X1226474Y33842D01*
X1227450Y34422D01*
X1228249Y35293D01*
X1228741Y36305D01*
X1228930Y37526D01*
X1228740Y38734D01*
X1228251Y39744D01*
X1227483Y40588D01*
X1226509Y41180D01*
X1225378Y41475D01*
X1224173Y41421D01*
X1223067Y41025D01*
X1222169Y40364D01*
X1221467Y39441D01*
X1221071Y38402D01*
X1220982Y37241D01*
X1221261Y36025D01*
X1221846Y35030D01*
X1222701Y34237D01*
X1223771Y33718D01*
X1224921Y33540D01*
X1226072Y33700D01*
X1227140Y34195D01*
X1227990Y34949D01*
X1228613Y35962D01*
X1228906Y37073D01*
G01X1212766Y24561D02*
Y18393D01*
G01X1213466Y24561D02*
Y18393D01*
G01X1214683Y43930D02*
Y38088D01*
G01X1214715Y44408D02*
Y36767D01*
G01X1215683Y43930D02*
Y38588D01*
G01X1215719Y24561D02*
Y18393D01*
G01X1216419Y24561D02*
Y18393D01*
G01X1216683Y44408D02*
Y36767D01*
G01X1216933Y43930D02*
Y38588D01*
G01X1217077Y34257D02*
Y40780D01*
G01X1217959Y44408D02*
Y36569D01*
G01X1218100Y44408D02*
Y37242D01*
G01X1218671Y24561D02*
Y18393D01*
G01X1218798Y37940D02*
Y44408D01*
G01X1218825Y38069D02*
Y44408D01*
G01X1219371Y24561D02*
Y18393D01*
G01X1220108Y43339D02*
Y39178D01*
G01X1220296Y31038D02*
Y26751D01*
G01X1221296Y32261D02*
Y26751D01*
G01X1221624Y24561D02*
Y18393D01*
G01X1222324Y24561D02*
Y18393D01*
G01X1224577Y24561D02*
Y18393D01*
G01X1224654Y32261D02*
Y26751D01*
G01X1225277Y24561D02*
Y18393D01*
G01X1225654Y30777D02*
Y26751D01*
G01X1226396Y12877D02*
Y19766D01*
G01X1227396Y12877D02*
Y19766D01*
G01X1227530Y24561D02*
Y18393D01*
G01X1228230Y24561D02*
Y18393D01*
G01X1228396Y19766D02*
Y12877D01*
G01X1228606Y30777D02*
Y26751D01*
G01X1229606Y31038D02*
Y26751D01*
G01X1229794Y43339D02*
Y39178D01*
G01X1230483Y24561D02*
Y18393D01*
G01X1235219Y38088D02*
X1235208Y38173D01*
X1235174Y38258D01*
X1235115Y38341D01*
X1235033Y38418D01*
X1234927Y38484D01*
X1234798Y38538D01*
X1234650Y38574D01*
X1234486Y38588D01*
G01X1231030Y44408D02*
Y38069D01*
G01X1231056Y44408D02*
Y37940D01*
G01X1231183Y24561D02*
Y18393D01*
G01X1231754Y44408D02*
Y37242D01*
G01X1231895Y36569D02*
Y44408D01*
G01X1232825Y40780D02*
Y34257D01*
G01X1232969Y43930D02*
Y38588D01*
G01X1233219Y44408D02*
Y36767D01*
G01X1233435Y24561D02*
Y18393D01*
G01X1234135Y24561D02*
Y18393D01*
G01X1234219Y43930D02*
Y38588D01*
G01X1228906Y37073D02*
X1228955Y37855D01*
X1228813Y38627D01*
G01X1214683Y38088D02*
X1214715Y38288D01*
X1214798Y38447D01*
X1214917Y38552D01*
X1215050Y38588D01*
G01X1217761Y36767D02*
X1216895Y35267D01*
G01X1217959Y36569D02*
X1218825Y38069D01*
G01X1222656Y39675D02*
X1223276Y40330D01*
X1224096Y40802D01*
X1225023Y41031D01*
X1226005Y40994D01*
X1226960Y40684D01*
X1227800Y40130D01*
X1228489Y39341D01*
G01X1221778Y41985D02*
X1218825Y39032D01*
G01X1218798Y37940D02*
X1216715Y35857D01*
G01X1217761Y36767D02*
X1218825Y38069D01*
G01X1216895Y35267D02*
X1217959Y36569D01*
G01X1232825Y34257D02*
X1228213Y29645D01*
G01X1228606Y30777D02*
G03X1228016Y31367I-590J0D01*
G01X1226244D02*
G03X1225654Y30777I0J-590D01*
G01X1228606Y26751D02*
G03X1229606I500J0D01*
G01X1220296D02*
G03X1221296I500J0D01*
G01X1224654D02*
G03X1225654I500J0D01*
G01X1214683Y38088D02*
G03X1215183Y37588I500J0D01*
G01X1229281Y37519D02*
G03I-4330J0D01*
G01X1228100D02*
G03I-3149J0D01*
G01X1221886Y32851D02*
G03X1221296Y32261I0J-590D01*
G01X1224654D02*
G03X1224063Y32851I-591J-1D01*
G01X1229794Y39178D02*
G03X1230384Y38588I590J0D01*
G01X1219518D02*
G03X1220108Y39178I0J590D01*
G01X1234719Y37588D02*
G03X1235219Y38088I0J500D01*
G01X1211480Y6528D02*
X1216402D01*
G01X1233500D02*
X1238422D01*
G01X1211480Y9060D02*
X1216402D01*
G01X1233500D02*
X1238422D01*
G01X1236388Y51111D02*
X1237088D01*
G01Y51327D02*
X1236388D01*
G01X1237088Y51423D02*
X1236388D01*
G01X1237088Y51485D02*
X1236388D01*
G01X1237088Y51583D02*
X1236388D01*
G01X1237088Y52568D02*
X1236388D01*
G01X1237088Y52666D02*
X1236388D01*
G01X1237088Y52729D02*
X1236388D01*
G01X1237088Y52823D02*
X1236388D01*
G01Y53040D02*
X1237088D01*
G01X1247104Y56275D02*
X1242585D01*
G01Y66043D02*
X1247104D01*
G01X1236388Y66071D02*
X1237088D01*
G01Y66288D02*
X1236388D01*
G01X1237088Y66383D02*
X1236388D01*
G01X1237088Y66445D02*
X1236388D01*
G01X1237088Y66544D02*
X1236388D01*
G01X1237088Y67528D02*
X1236388D01*
G01X1237088Y67627D02*
X1236388D01*
G01X1237088Y67689D02*
X1236388D01*
G01X1237088Y67784D02*
X1236388D01*
G01Y68001D02*
X1237088D01*
G01X1236388Y51112D02*
Y53038D01*
G01Y66073D02*
Y67999D01*
G01X1237088Y51113D02*
Y53039D01*
G01Y66073D02*
Y67999D01*
G01X1241585Y65043D02*
Y57275D01*
G01X1243120Y66043D02*
Y86182D01*
G01X1243457Y66043D02*
Y56275D01*
G01X1241585Y57275D02*
G03X1242585Y56275I1000J0D01*
G01Y66043D02*
G03X1241585Y65043I0J-1000D01*
G01X1241079Y105171D02*
Y44408D01*
G01X1242492Y105171D02*
Y44408D01*
G01X1243120D02*
Y56275D01*
G01X1244120Y44408D02*
Y105171D01*
G01X1213206Y54558D02*
X1213258Y54572D01*
G01X1213088Y55028D02*
X1213035Y55014D01*
G01X1212485Y53749D02*
X1211485Y53499D01*
G01X1211860Y54873D02*
X1211360Y54749D01*
G01X1213271Y54492D02*
X1213206Y54478D01*
G01X1213022Y55095D02*
X1213088Y55108D01*
G01X1221689Y45393D02*
X1228213D01*
G01X1229848Y45528D02*
X1220006D01*
G01X1229848Y46512D02*
X1220006D01*
G01X1215719Y48355D02*
X1216419D01*
G01X1224577D02*
X1225277D01*
G01X1233435D02*
X1234135D01*
G01Y48571D02*
X1233435D01*
G01X1225277D02*
X1224577D01*
G01X1216419D02*
X1215719D01*
G01X1234135Y48667D02*
X1233435D01*
G01X1225277D02*
X1224577D01*
G01X1216419D02*
X1215719D01*
G01X1234135Y48729D02*
X1233435D01*
G01X1225277D02*
X1224577D01*
G01X1216419D02*
X1215719D01*
G01X1234135Y48827D02*
X1233435D01*
G01X1225277D02*
X1224577D01*
G01X1216419D02*
X1215719D01*
G01X1234135Y49812D02*
X1233435D01*
G01X1225277D02*
X1224577D01*
G01X1216419D02*
X1215719D01*
G01X1234135Y49910D02*
X1233435D01*
G01X1225277D02*
X1224577D01*
G01X1216419D02*
X1215719D01*
G01X1234135Y49973D02*
X1233435D01*
G01X1225277D02*
X1224577D01*
G01X1216419D02*
X1215719D01*
G01X1234135Y50068D02*
X1233435D01*
G01X1225277D02*
X1224577D01*
G01X1216419D02*
X1215719D01*
G01Y50284D02*
X1216419D01*
G01X1224577D02*
X1225277D01*
G01X1233435D02*
X1234135D01*
G01X1218671Y51111D02*
X1219371D01*
G01X1227530D02*
X1228230D01*
G01Y51327D02*
X1227530D01*
G01X1219371D02*
X1218671D01*
G01X1228230Y51423D02*
X1227530D01*
G01X1219371D02*
X1218671D01*
G01X1228230Y51485D02*
X1227530D01*
G01X1219371D02*
X1218671D01*
G01X1228230Y51583D02*
X1227530D01*
G01X1219371D02*
X1218671D01*
G01X1228230Y52568D02*
X1227530D01*
G01X1219371D02*
X1218671D01*
G01X1228230Y52666D02*
X1227530D01*
G01X1219371D02*
X1218671D01*
G01X1228230Y52729D02*
X1227530D01*
G01X1219371D02*
X1218671D01*
G01X1228230Y52823D02*
X1227530D01*
G01X1219371D02*
X1218671D01*
G01Y53040D02*
X1219371D01*
G01X1227530D02*
X1228230D01*
G01X1216485Y53499D02*
X1218110D01*
G01X1221860D02*
X1223485D01*
G01X1231183Y53867D02*
X1230483D01*
G01X1222324D02*
X1221624D01*
G01X1213466D02*
X1212766D01*
G01Y54083D02*
X1213466D01*
G01X1221624D02*
X1222324D01*
G01X1230483D02*
X1231183D01*
G01X1212766Y54179D02*
X1213466D01*
G01X1221624D02*
X1222324D01*
G01X1230483D02*
X1231183D01*
G01X1212766Y54241D02*
X1213466D01*
G01X1221624D02*
X1222324D01*
G01X1230483D02*
X1231183D01*
G01Y54339D02*
X1230483D01*
G01X1222324D02*
X1221624D01*
G01X1213466D02*
X1212766D01*
G01X1213206Y54478D02*
X1213088D01*
G01X1213573D02*
X1213494D01*
G01X1214019D02*
X1213941D01*
G01X1214282D02*
X1214203D01*
G01X1213088Y54558D02*
X1213206D01*
G01X1213888Y54639D02*
X1213626D01*
G01X1213311D02*
X1213389D01*
G01X1213875Y54693D02*
X1213639D01*
G01X1213389Y54947D02*
X1213311D01*
G01X1213206Y55028D02*
X1213088D01*
G01Y55108D02*
X1213206D01*
G01X1213704D02*
X1213809D01*
G01X1214203D02*
X1214282D01*
G01X1231183Y55323D02*
X1230483D01*
G01X1222324D02*
X1221624D01*
G01X1213466D02*
X1212766D01*
G01X1231183Y55422D02*
X1230483D01*
G01X1222324D02*
X1221624D01*
G01X1213466D02*
X1212766D01*
G01Y55484D02*
X1213466D01*
G01X1221624D02*
X1222324D01*
G01X1230483D02*
X1231183D01*
G01X1212766Y55579D02*
X1213466D01*
G01X1221624D02*
X1222324D01*
G01X1230483D02*
X1231183D01*
G01Y55796D02*
X1230483D01*
G01X1222324D02*
X1221624D01*
G01X1213466D02*
X1212766D01*
G01X1214360Y55999D02*
X1212985D01*
G01X1223110Y60999D02*
X1221485D01*
G01X1218485D02*
X1216860D01*
G01X1215719Y63316D02*
X1216419D01*
G01X1224577D02*
X1225277D01*
G01X1233435D02*
X1234135D01*
G01Y63532D02*
X1233435D01*
G01X1225277D02*
X1224577D01*
G01X1216419D02*
X1215719D01*
G01X1234135Y63627D02*
X1233435D01*
G01X1225277D02*
X1224577D01*
G01X1216419D02*
X1215719D01*
G01X1234135Y63690D02*
X1233435D01*
G01X1225277D02*
X1224577D01*
G01X1216419D02*
X1215719D01*
G01X1234135Y63788D02*
X1233435D01*
G01X1225277D02*
X1224577D01*
G01X1216419D02*
X1215719D01*
G01X1234135Y64772D02*
X1233435D01*
G01X1225277D02*
X1224577D01*
G01X1216419D02*
X1215719D01*
G01X1234135Y64871D02*
X1233435D01*
G01X1225277D02*
X1224577D01*
G01X1216419D02*
X1215719D01*
G01X1234135Y64933D02*
X1233435D01*
G01X1225277D02*
X1224577D01*
G01X1216419D02*
X1215719D01*
G01X1234135Y65028D02*
X1233435D01*
G01X1225277D02*
X1224577D01*
G01X1216419D02*
X1215719D01*
G01Y65245D02*
X1216419D01*
G01X1224577D02*
X1225277D01*
G01X1233435D02*
X1234135D01*
G01X1218671Y66071D02*
X1219371D01*
G01X1227530D02*
X1228230D01*
G01Y66288D02*
X1227530D01*
G01X1219371D02*
X1218671D01*
G01X1228230Y66383D02*
X1227530D01*
G01X1219371D02*
X1218671D01*
G01X1228230Y66445D02*
X1227530D01*
G01X1219371D02*
X1218671D01*
G01X1228230Y66544D02*
X1227530D01*
G01X1219371D02*
X1218671D01*
G01X1228230Y67528D02*
X1227530D01*
G01X1219371D02*
X1218671D01*
G01X1228230Y67627D02*
X1227530D01*
G01X1219371D02*
X1218671D01*
G01X1228230Y67689D02*
X1227530D01*
G01X1219371D02*
X1218671D01*
G01X1228230Y67784D02*
X1227530D01*
G01X1219371D02*
X1218671D01*
G01Y68001D02*
X1219371D01*
G01X1227530D02*
X1228230D01*
G01X1231183Y68827D02*
X1230483D01*
G01X1222324D02*
X1221624D01*
G01X1213466D02*
X1212766D01*
G01Y69044D02*
X1213466D01*
G01X1221624D02*
X1222324D01*
G01X1230483D02*
X1231183D01*
G01X1212766Y69139D02*
X1213466D01*
G01X1221624D02*
X1222324D01*
G01X1230483D02*
X1231183D01*
G01X1212766Y69201D02*
X1213466D01*
G01X1221624D02*
X1222324D01*
G01X1230483D02*
X1231183D01*
G01Y69300D02*
X1230483D01*
G01X1222324D02*
X1221624D01*
G01X1213466D02*
X1212766D01*
G01X1231183Y70284D02*
X1230483D01*
G01X1222324D02*
X1221624D01*
G01X1213466D02*
X1212766D01*
G01X1231183Y70382D02*
X1230483D01*
G01X1222324D02*
X1221624D01*
G01X1213466D02*
X1212766D01*
G01Y70445D02*
X1213466D01*
G01X1221624D02*
X1222324D01*
G01X1230483D02*
X1231183D01*
G01Y70540D02*
X1230483D01*
G01X1222324D02*
X1221624D01*
G01X1213466D02*
X1212766D01*
G01X1231183Y70756D02*
X1230483D01*
G01X1222324D02*
X1221624D01*
G01X1213466D02*
X1212766D01*
G01X1213088Y54478D02*
X1213022Y54492D01*
G01X1213206Y55108D02*
X1213271Y55095D01*
G01X1211860Y59623D02*
X1211360Y59749D01*
G01X1212485Y60749D02*
X1211485Y60999D01*
G01X1213035Y54572D02*
X1213088Y54558D01*
G01X1213258Y55014D02*
X1213206Y55028D01*
G01X1213022Y54492D02*
X1212970Y54518D01*
G01X1213271Y55095D02*
X1213324Y55068D01*
G01X1212485Y59249D02*
X1211860Y59623D01*
G01X1213235Y60249D02*
X1212485Y60749D01*
G01X1212996Y54599D02*
X1213035Y54572D01*
G01X1213298Y54988D02*
X1213258Y55014D01*
G01X1213735Y59749D02*
X1213235Y60249D01*
G01X1212970Y54518D02*
X1212917Y54572D01*
G01X1213324Y55068D02*
X1213376Y55014D01*
G01X1219985Y56249D02*
X1221860Y53499D01*
G01X1213735Y59749D02*
X1214235Y58999D01*
G01X1218485Y60999D02*
X1219985Y58749D01*
G01X1220860Y57499D02*
X1223485Y53499D01*
G01X1212970Y54639D02*
X1212996Y54599D01*
G01X1216860Y60999D02*
X1219110Y57499D01*
G01X1212485Y59249D02*
X1212860Y58623D01*
G01X1212917Y54572D02*
X1212891Y54626D01*
G01X1213809Y55108D02*
X1214019Y54478D01*
G01X1213311Y54947D02*
X1213298Y54988D01*
G01X1213941Y54478D02*
X1213888Y54639D01*
G01X1213757Y55055D02*
X1213875Y54693D01*
G01X1214235Y58999D02*
X1214485Y57999D01*
G01X1212956Y54693D02*
X1212970Y54639D01*
G01X1212860Y58623D02*
X1212985Y57999D01*
G01X1212891Y54626D02*
X1212878Y54693D01*
G01X1213376Y55014D02*
X1213389Y54947D01*
G01X1212766Y53868D02*
Y55794D01*
G01Y68829D02*
Y70755D01*
G01X1212878Y54693D02*
Y54893D01*
G01X1212956D02*
Y54693D01*
G01X1213466Y53869D02*
Y55795D01*
G01Y68829D02*
Y70755D01*
G01X1214124Y54907D02*
Y55014D01*
G01X1214203Y54478D02*
Y55001D01*
G01X1214282Y55108D02*
Y54478D01*
G01X1214485Y57999D02*
Y56999D01*
G01X1215719Y48356D02*
Y50282D01*
G01Y63317D02*
Y65243D01*
G01X1216419Y48357D02*
Y50283D01*
G01Y63318D02*
Y65243D01*
G01X1218671Y51112D02*
Y53038D01*
G01Y66073D02*
Y67999D01*
G01X1219371Y51113D02*
Y53039D01*
G01Y66073D02*
Y67999D01*
G01X1221624Y53868D02*
Y55794D01*
G01Y68829D02*
Y70755D01*
G01X1222324Y53869D02*
Y55795D01*
G01Y68829D02*
Y70755D01*
G01X1224577Y48356D02*
Y50282D01*
G01Y63317D02*
Y65243D01*
G01X1225277Y48357D02*
Y50283D01*
G01Y63318D02*
Y65243D01*
G01X1227530Y51112D02*
Y53038D01*
G01Y66073D02*
Y67999D01*
G01X1228230Y51113D02*
Y53039D01*
G01Y66073D02*
Y67999D01*
G01X1230483Y53868D02*
Y55794D01*
G01Y68829D02*
Y70755D01*
G01X1231183Y53869D02*
Y55795D01*
G01Y68829D02*
Y70755D01*
G01X1233435Y48356D02*
Y50282D01*
G01Y63317D02*
Y65243D01*
G01X1234135Y48357D02*
Y50283D01*
G01Y63318D02*
Y65243D01*
G01X1212878Y54893D02*
X1212891Y54961D01*
G01X1213389Y54639D02*
X1213376Y54572D01*
G01X1212970Y54947D02*
X1212956Y54893D01*
G01X1212485Y55249D02*
X1211860Y54873D01*
G01X1212970Y55068D02*
X1213022Y55095D01*
G01X1213324Y54518D02*
X1213271Y54492D01*
G01X1214360Y55999D02*
X1214235Y55499D01*
G01X1213298Y54599D02*
X1213311Y54639D01*
G01X1213639Y54693D02*
X1213757Y55055D01*
G01X1213626Y54639D02*
X1213573Y54478D01*
G01X1213494D02*
X1213704Y55108D01*
G01X1212891Y54961D02*
X1212917Y55014D01*
G01X1223110Y60999D02*
X1220860Y57499D01*
G01X1212996Y54988D02*
X1212970Y54947D01*
G01X1219110Y57499D02*
X1216485Y53499D01*
G01X1212985Y55999D02*
X1212485Y55249D01*
G01X1214235Y55499D02*
X1213735Y54749D01*
G01X1221485Y60999D02*
X1219985Y58749D01*
G01Y56249D02*
X1218110Y53499D01*
G01X1214124Y55014D02*
X1214203Y55108D01*
G01Y55001D02*
X1214124Y54907D01*
G01X1212917Y55014D02*
X1212970Y55068D01*
G01X1213376Y54572D02*
X1213324Y54518D01*
G01X1213735Y54749D02*
X1213235Y54249D01*
G01X1213035Y55014D02*
X1212996Y54988D01*
G01X1213258Y54572D02*
X1213298Y54599D01*
G01X1213235Y54249D02*
X1212485Y53749D01*
G01X1235187Y41062D02*
X1233219D01*
G01X1216683D02*
X1214715D01*
G01X1228077Y41985D02*
X1221778D01*
G01X1262825Y43930D02*
X1230384D01*
G01X1232825Y40780D02*
X1228213Y45393D01*
G01X1220006Y46512D02*
Y44408D01*
G01X1229848Y46512D02*
Y44408D01*
G01X1221689Y45393D02*
X1217077Y40780D01*
G01X1230384Y43930D02*
G03X1229794Y43339I1J-591D01*
G01X1220108D02*
G03X1219518Y43930I-591J0D01*
G01X1236388Y81032D02*
X1237088D01*
G01Y81249D02*
X1236388D01*
G01X1237088Y81344D02*
X1236388D01*
G01X1237088Y81406D02*
X1236388D01*
G01X1237088Y81505D02*
X1236388D01*
G01X1237088Y82489D02*
X1236388D01*
G01X1237088Y82587D02*
X1236388D01*
G01X1237088Y82650D02*
X1236388D01*
G01X1237088Y82745D02*
X1236388D01*
G01Y82961D02*
X1237088D01*
G01X1247104Y86182D02*
X1242585D01*
G01Y94578D02*
X1247104D01*
G01X1236388Y95993D02*
X1237088D01*
G01Y96209D02*
X1236388D01*
G01X1237088Y96305D02*
X1236388D01*
G01X1237088Y96367D02*
X1236388D01*
G01X1237088Y96465D02*
X1236388D01*
G01X1237088Y97449D02*
X1236388D01*
G01X1237088Y97548D02*
X1236388D01*
G01X1237088Y97610D02*
X1236388D01*
G01X1237088Y97705D02*
X1236388D01*
G01Y97922D02*
X1237088D01*
G01X1235209Y106958D02*
Y105958D01*
G01X1235301D02*
Y106958D01*
G01X1235561D02*
Y105958D01*
G01X1235565Y105171D02*
Y106958D01*
G01X1235787Y105958D02*
Y106958D01*
G01X1235839Y105958D02*
Y106958D01*
G01X1236246Y105958D02*
Y106958D01*
G01X1236388Y81034D02*
Y82960D01*
G01Y95994D02*
Y97920D01*
G01X1237088Y81034D02*
Y82960D01*
G01Y95995D02*
Y97921D01*
G01X1237230Y106958D02*
Y105958D01*
G01X1237561Y106958D02*
Y105958D01*
G01X1237642D02*
Y106958D01*
G01X1237693Y105958D02*
Y106958D01*
G01X1238175Y105958D02*
Y106958D01*
G01X1238272Y105958D02*
Y106958D01*
G01X1238313Y105171D02*
Y102336D01*
G01X1238561Y106958D02*
Y105958D01*
G01X1239080Y106958D02*
Y105958D01*
G01X1240423D02*
Y106958D01*
G01X1241585Y93578D02*
Y87182D01*
G01X1243120Y94578D02*
Y105171D01*
G01X1243457Y94578D02*
Y86182D01*
G01X1241585Y87182D02*
G03X1242585Y86182I1000J0D01*
G01Y94578D02*
G03X1241585Y93578I0J-1000D01*
G01X1246104Y77628D02*
X1244120Y75643D01*
G01X1234135Y79733D02*
X1233435D01*
G01X1225277D02*
X1224577D01*
G01X1216419D02*
X1215719D01*
G01X1234135Y79831D02*
X1233435D01*
G01X1225277D02*
X1224577D01*
G01X1216419D02*
X1215719D01*
G01X1234135Y79894D02*
X1233435D01*
G01X1225277D02*
X1224577D01*
G01X1216419D02*
X1215719D01*
G01X1234135Y79989D02*
X1233435D01*
G01X1225277D02*
X1224577D01*
G01X1216419D02*
X1215719D01*
G01Y80205D02*
X1216419D01*
G01X1224577D02*
X1225277D01*
G01X1233435D02*
X1234135D01*
G01X1218671Y81032D02*
X1219371D01*
G01X1227530D02*
X1228230D01*
G01Y81249D02*
X1227530D01*
G01X1219371D02*
X1218671D01*
G01X1228230Y81344D02*
X1227530D01*
G01X1219371D02*
X1218671D01*
G01X1228230Y81406D02*
X1227530D01*
G01X1219371D02*
X1218671D01*
G01X1228230Y81505D02*
X1227530D01*
G01X1219371D02*
X1218671D01*
G01X1228230Y82489D02*
X1227530D01*
G01X1219371D02*
X1218671D01*
G01X1228230Y82587D02*
X1227530D01*
G01X1219371D02*
X1218671D01*
G01X1228230Y82650D02*
X1227530D01*
G01X1219371D02*
X1218671D01*
G01X1228230Y82745D02*
X1227530D01*
G01X1219371D02*
X1218671D01*
G01Y82961D02*
X1219371D01*
G01X1227530D02*
X1228230D01*
G01X1231183Y83788D02*
X1230483D01*
G01X1222324D02*
X1221624D01*
G01X1213466D02*
X1212766D01*
G01Y84005D02*
X1213466D01*
G01X1221624D02*
X1222324D01*
G01X1230483D02*
X1231183D01*
G01X1212766Y84100D02*
X1213466D01*
G01X1221624D02*
X1222324D01*
G01X1230483D02*
X1231183D01*
G01X1212766Y84162D02*
X1213466D01*
G01X1221624D02*
X1222324D01*
G01X1230483D02*
X1231183D01*
G01Y84260D02*
X1230483D01*
G01X1222324D02*
X1221624D01*
G01X1213466D02*
X1212766D01*
G01X1231183Y85245D02*
X1230483D01*
G01X1222324D02*
X1221624D01*
G01X1213466D02*
X1212766D01*
G01X1231183Y85343D02*
X1230483D01*
G01X1222324D02*
X1221624D01*
G01X1213466D02*
X1212766D01*
G01Y85406D02*
X1213466D01*
G01X1221624D02*
X1222324D01*
G01X1230483D02*
X1231183D01*
G01Y85501D02*
X1230483D01*
G01X1222324D02*
X1221624D01*
G01X1213466D02*
X1212766D01*
G01X1231183Y85717D02*
X1230483D01*
G01X1222324D02*
X1221624D01*
G01X1213466D02*
X1212766D01*
G01X1215719Y93237D02*
X1216419D01*
G01X1224577D02*
X1225277D01*
G01X1233435D02*
X1234135D01*
G01Y93453D02*
X1233435D01*
G01X1225277D02*
X1224577D01*
G01X1216419D02*
X1215719D01*
G01X1234135Y93549D02*
X1233435D01*
G01X1225277D02*
X1224577D01*
G01X1216419D02*
X1215719D01*
G01X1234135Y93611D02*
X1233435D01*
G01X1225277D02*
X1224577D01*
G01X1216419D02*
X1215719D01*
G01X1234135Y93709D02*
X1233435D01*
G01X1225277D02*
X1224577D01*
G01X1216419D02*
X1215719D01*
G01X1234135Y94693D02*
X1233435D01*
G01X1225277D02*
X1224577D01*
G01X1216419D02*
X1215719D01*
G01X1234135Y94792D02*
X1233435D01*
G01X1225277D02*
X1224577D01*
G01X1216419D02*
X1215719D01*
G01X1234135Y94855D02*
X1233435D01*
G01X1225277D02*
X1224577D01*
G01X1216419D02*
X1215719D01*
G01X1234135Y94949D02*
X1233435D01*
G01X1225277D02*
X1224577D01*
G01X1216419D02*
X1215719D01*
G01Y95166D02*
X1216419D01*
G01X1224577D02*
X1225277D01*
G01X1233435D02*
X1234135D01*
G01X1218671Y95993D02*
X1219371D01*
G01X1227530D02*
X1228230D01*
G01Y96209D02*
X1227530D01*
G01X1219371D02*
X1218671D01*
G01X1228230Y96305D02*
X1227530D01*
G01X1219371D02*
X1218671D01*
G01X1228230Y96367D02*
X1227530D01*
G01X1219371D02*
X1218671D01*
G01X1228230Y96465D02*
X1227530D01*
G01X1219371D02*
X1218671D01*
G01X1228230Y97449D02*
X1227530D01*
G01X1219371D02*
X1218671D01*
G01X1228230Y97548D02*
X1227530D01*
G01X1219371D02*
X1218671D01*
G01X1228230Y97610D02*
X1227530D01*
G01X1219371D02*
X1218671D01*
G01X1228230Y97705D02*
X1227530D01*
G01X1219371D02*
X1218671D01*
G01Y97922D02*
X1219371D01*
G01X1227530D02*
X1228230D01*
G01X1231183Y98749D02*
X1230483D01*
G01X1222324D02*
X1221624D01*
G01X1213466D02*
X1212766D01*
G01Y98965D02*
X1213466D01*
G01X1221624D02*
X1222324D01*
G01X1230483D02*
X1231183D01*
G01X1212766Y99060D02*
X1213466D01*
G01X1221624D02*
X1222324D01*
G01X1230483D02*
X1231183D01*
G01X1212766Y99123D02*
X1213466D01*
G01X1221624D02*
X1222324D01*
G01X1230483D02*
X1231183D01*
G01Y99221D02*
X1230483D01*
G01X1222324D02*
X1221624D01*
G01X1213466D02*
X1212766D01*
G01X1231183Y100205D02*
X1230483D01*
G01X1222324D02*
X1221624D01*
G01X1213466D02*
X1212766D01*
G01X1231183Y100304D02*
X1230483D01*
G01X1222324D02*
X1221624D01*
G01X1213466D02*
X1212766D01*
G01Y100366D02*
X1213466D01*
G01X1221624D02*
X1222324D01*
G01X1230483D02*
X1231183D01*
G01Y100461D02*
X1230483D01*
G01X1222324D02*
X1221624D01*
G01X1213466D02*
X1212766D01*
G01X1231183Y100678D02*
X1230483D01*
G01X1222324D02*
X1221624D01*
G01X1213466D02*
X1212766D01*
G01X1211541Y102336D02*
X1238313D01*
G01X1211321Y105958D02*
Y106958D01*
G01X1211541Y105171D02*
Y102336D01*
G01X1212321Y106958D02*
Y105958D01*
G01X1212766Y83790D02*
Y85716D01*
G01Y98750D02*
Y100676D01*
G01X1213466Y83790D02*
Y85716D01*
G01Y98751D02*
Y100677D01*
G01X1214317Y106958D02*
Y105958D01*
G01X1214321Y105171D02*
Y106958D01*
G01X1215337D02*
Y105958D01*
G01X1215719Y93238D02*
Y95164D01*
G01X1216419Y93239D02*
Y95165D01*
G01X1216680Y105958D02*
Y106958D01*
G01X1217492D02*
Y105958D01*
G01X1217585D02*
Y106958D01*
G01X1218070Y105958D02*
Y106958D01*
G01X1218122Y105958D02*
Y106958D01*
G01X1218530Y105958D02*
Y106958D01*
G01X1218671Y81034D02*
Y82960D01*
G01Y95994D02*
Y97920D01*
G01X1219371Y81034D02*
Y82960D01*
G01Y95995D02*
Y97921D01*
G01X1219514Y106958D02*
Y105958D01*
G01X1219926D02*
Y106958D01*
G01X1219977Y105958D02*
Y106958D01*
G01X1220459Y105958D02*
Y106958D01*
G01X1220556Y105958D02*
Y106958D01*
G01X1221207Y105958D02*
Y106958D01*
G01X1221624Y83790D02*
Y85716D01*
G01Y98750D02*
Y100676D01*
G01X1221974Y102336D02*
Y105171D01*
G01Y105958D02*
Y106958D01*
G01X1222324Y83790D02*
Y85716D01*
G01Y98751D02*
Y100677D01*
G01X1222707Y105958D02*
Y106958D01*
G01X1223352Y102336D02*
Y105171D01*
G01X1224577Y93238D02*
Y95164D01*
G01X1225277Y93239D02*
Y95165D01*
G01X1227530Y81034D02*
Y82960D01*
G01Y95994D02*
Y97920D01*
G01X1227880Y105958D02*
Y106958D01*
G01X1228230Y81034D02*
Y82960D01*
G01Y95995D02*
Y97921D01*
G01X1230483Y83790D02*
Y85716D01*
G01Y98750D02*
Y100676D01*
G01X1231183Y83790D02*
Y85716D01*
G01Y98751D02*
Y100677D01*
G01X1232407Y105171D02*
Y102336D01*
G01X1233053Y106958D02*
Y105958D01*
G01X1233435Y93238D02*
Y95164D01*
G01X1233785Y105171D02*
Y102336D01*
G01X1234135Y93239D02*
Y95165D01*
G01X1234553Y105958D02*
Y106958D01*
G01X1215719Y78276D02*
X1216419D01*
G01X1224577D02*
X1225277D01*
G01X1233435D02*
X1234135D01*
G01Y78493D02*
X1233435D01*
G01X1225277D02*
X1224577D01*
G01X1216419D02*
X1215719D01*
G01X1234135Y78588D02*
X1233435D01*
G01X1225277D02*
X1224577D01*
G01X1216419D02*
X1215719D01*
G01X1234135Y78650D02*
X1233435D01*
G01X1225277D02*
X1224577D01*
G01X1216419D02*
X1215719D01*
G01X1234135Y78749D02*
X1233435D01*
G01X1225277D02*
X1224577D01*
G01X1216419D02*
X1215719D01*
G01Y78278D02*
Y80204D01*
G01X1216419Y78278D02*
Y80204D01*
G01X1224577Y78278D02*
Y80204D01*
G01X1225277Y78278D02*
Y80204D01*
G01X1233435Y78278D02*
Y80204D01*
G01X1234135Y78278D02*
Y80204D01*
G01X1243996Y883464D02*
X1241831D01*
G01X1237697D02*
X1235531D01*
G01X1240846D02*
X1238681D01*
G01X1235531D02*
Y892519D01*
G01X1237697D02*
Y883464D01*
G01X1238681D02*
Y892519D01*
G01X1240846D02*
Y883464D01*
G01X1241831D02*
Y892519D01*
G01X1243996D02*
Y883464D01*
G01X1217081Y882075D02*
X1216651Y881279D01*
G01X1217257Y882075D02*
X1216651Y880944D01*
G01X1218471Y882075D02*
X1217865Y880944D01*
G01X1218294Y882075D02*
X1217865Y881279D01*
G01X1219432Y882410D02*
X1219533Y882912D01*
G01X1219407Y882242D02*
X1219180Y881111D01*
G01X1219685Y882912D02*
X1219281Y880944D01*
G01D02*
X1219078D01*
G01X1217865D02*
X1217713D01*
G01X1216651D02*
X1216499D01*
G01X1217713Y882075D02*
X1217460D01*
G01X1216499D02*
X1216246D01*
G01X1217865D02*
X1218294D01*
G01X1216651D02*
X1217081D01*
G01X1218952Y882242D02*
X1219407D01*
G01X1217865Y882326D02*
X1218471D01*
G01X1217460D02*
X1217713D01*
G01X1216651D02*
X1217257D01*
G01X1216246D02*
X1216499D01*
G01X1218927Y882410D02*
X1219432D01*
G01X1219533Y882912D02*
X1219685D01*
G01X1218674D02*
X1218826D01*
G01X1217713D02*
X1217865D01*
G01X1216499D02*
X1216651D01*
G01X1234547Y883464D02*
X1232382D01*
G01X1228248D02*
X1226083D01*
G01X1231398D02*
X1229232D01*
G01X1225098D02*
X1222933D01*
G01X1218799D02*
X1216634D01*
G01X1221949D02*
X1219783D01*
G01X1214173Y892519D02*
Y875983D01*
G01Y892519D02*
Y875983D01*
G01X1216246Y882075D02*
Y882326D01*
G01X1216499D02*
Y882912D01*
G01Y880944D02*
Y882075D01*
G01X1216634Y883464D02*
Y892519D01*
G01X1216651Y882912D02*
Y882326D01*
G01Y881279D02*
Y882075D01*
G01X1217257Y882326D02*
Y882075D01*
G01X1217460D02*
Y882326D01*
G01X1217713D02*
Y882912D01*
G01Y880944D02*
Y882075D01*
G01X1217865Y882912D02*
Y882326D01*
G01Y881279D02*
Y882075D01*
G01X1218471Y882326D02*
Y882075D01*
G01X1218799Y892519D02*
Y883464D01*
G01X1219783D02*
Y892519D01*
G01X1221949D02*
Y883464D01*
G01X1222933D02*
Y892519D01*
G01X1225098D02*
Y883464D01*
G01X1226083D02*
Y892519D01*
G01X1228248D02*
Y883464D01*
G01X1229232D02*
Y892519D01*
G01X1231398D02*
Y883464D01*
G01X1232382D02*
Y892519D01*
G01X1234547D02*
Y883464D01*
G01X1219078Y880944D02*
X1218674Y882912D01*
G01X1219180Y881111D02*
X1218952Y882242D01*
G01X1218826Y882912D02*
X1218927Y882410D01*
G01X1235531Y892519D02*
X1237697D01*
G01X1238681D02*
X1240846D01*
G01X1241831D02*
X1243996D01*
G01X1214173Y896456D02*
Y943291D01*
G01X1218110Y897637D02*
X1214173Y892519D01*
G01D02*
X1218110Y897637D01*
G01X1214173Y892519D02*
X1356299D01*
G01X1216634D02*
X1218799D01*
G01X1219783D02*
X1221949D01*
G01X1222933D02*
X1225098D01*
G01X1226083D02*
X1228248D01*
G01X1229232D02*
X1231398D01*
G01X1232382D02*
X1234547D01*
G01X1218110Y897637D02*
X1352362D01*
G01X1218110D02*
X1352362D01*
G01X1214173Y939354D02*
X1233858D01*
G01X1256959Y-628831D02*
X1251474Y-652231D01*
G01X1283038Y-606762D02*
X1282316Y-607736D01*
X1281594Y-608224D01*
X1280151Y-608711D01*
X1277264D01*
X1275820Y-608224D01*
X1275098Y-607736D01*
X1274377Y-606762D01*
X1275098Y-605788D01*
X1275820Y-605301D01*
X1277264Y-604814D01*
X1280151D01*
X1281594Y-605301D01*
X1282316Y-605788D01*
X1283038Y-606762D01*
G01Y-614557D02*
X1282316Y-615532D01*
X1281594Y-616019D01*
X1280151Y-616507D01*
X1277264D01*
X1275820Y-616019D01*
X1275098Y-615532D01*
X1274377Y-614557D01*
X1275098Y-613583D01*
X1275820Y-613096D01*
X1277264Y-612609D01*
X1280151D01*
X1281594Y-613096D01*
X1282316Y-613583D01*
X1283038Y-614557D01*
G01X1274377Y-628199D02*
Y-631123D01*
X1277985Y-631610D01*
X1277264Y-630635D01*
Y-629661D01*
X1277985Y-628686D01*
X1278707Y-628199D01*
X1280151Y-627712D01*
X1281594Y-628199D01*
X1282316Y-628686D01*
X1283038Y-629661D01*
Y-630635D01*
X1282316Y-631610D01*
X1281594Y-632097D01*
G01X1262418Y-594592D02*
X1256959Y-628831D01*
G01X1263403Y-561014D02*
X1262418Y-594592D01*
G01X1257788Y-527753D02*
X1263403Y-561014D01*
G01X1249476Y-506061D02*
X1257788Y-527753D01*
G01X1276172Y-442223D02*
X1276660Y-438614D01*
X1277147Y-436449D01*
X1277634Y-435005D01*
X1278121Y-433562D01*
X1274224D01*
G01X1258633Y-435005D02*
X1259120Y-434284D01*
X1260095Y-433562D01*
X1261069D01*
X1262044Y-434284D01*
X1262531Y-435005D01*
Y-436449D01*
X1262044Y-437171D01*
X1261069Y-437892D01*
X1260095Y-438614D01*
X1259120Y-440058D01*
X1258633Y-442223D01*
X1262531D01*
G01X1266916D02*
X1269839Y-436449D01*
G01X1266916D02*
X1269839Y-442223D01*
G01X1313504Y-25653D02*
X1255959Y-105512D01*
G01X1290411Y-42635D02*
X1275172D01*
G01X1290805Y-41435D02*
X1275773D01*
G01X1277191Y-33775D02*
X1268994D01*
G01X1277177Y-33102D02*
X1269008D01*
G01Y-32967D02*
X1277177D01*
G01Y-31261D02*
X1269009D01*
G01X1269008Y-30829D02*
X1277177D01*
G01Y-30744D02*
X1269008D01*
G01X1274465Y-42342D02*
X1274051Y-41928D01*
G01X1277191Y-33775D02*
X1277185Y-33744D01*
X1277181Y-33713D01*
X1277178Y-33682D01*
G01Y-33663D02*
X1277181Y-33701D01*
X1277185Y-33738D01*
X1277191Y-33775D01*
G01X1277178Y-33682D02*
X1277177Y-33647D01*
G01Y-33621D02*
X1277178Y-33663D01*
G01X1269008Y-33647D02*
Y-17548D01*
G01X1269007Y-33663D02*
Y-33682D01*
G01X1270522Y-34319D02*
Y-32749D01*
G01X1271142D02*
Y-34319D01*
G01X1273258Y-41835D02*
Y-40398D01*
G01X1273573Y-32749D02*
Y-34319D01*
G01X1277178Y-33663D02*
Y-33682D01*
G01X1277177Y-17548D02*
Y-33647D01*
G01X1269007Y-33663D02*
X1269008Y-33621D01*
G01Y-33647D02*
X1269007Y-33682D01*
G01D02*
X1269004Y-33713D01*
X1269000Y-33744D01*
X1268994Y-33775D01*
G01D02*
X1269000Y-33738D01*
X1269004Y-33701D01*
X1269007Y-33663D01*
G01X1274051Y-41928D02*
G03X1273344Y-41635I-707J-707D01*
G01X1274465Y-42342D02*
G03X1275172Y-42635I707J707D01*
G01X1273258Y-40440D02*
G03X1272258Y-39440I-1000J0D01*
G01X1274813Y-40670D02*
G03X1275773Y-41435I960J219D01*
G01X1273258Y-40398D02*
G03X1272592Y-39467I-984J0D01*
G01X1274813Y-40670D02*
G03X1273258Y-40845I-768J-175D01*
G01X1277191Y-33775D02*
G03X1277927Y-34378I734J145D01*
G01D02*
G03X1278663Y-33775I2J748D01*
G01X1277927Y-32016D02*
G03X1278677Y-31261I2J748D01*
G01X1277178D02*
G03X1277927Y-32016I748J-7D01*
G01X1273258Y-41835D02*
X1263258D01*
G01X1273344Y-41635D02*
X1263172D01*
G01X1273258Y-41461D02*
X1263258D01*
G01Y-41403D02*
X1273258D01*
G01X1263258Y-41135D02*
X1273258D01*
G01Y-41107D02*
X1263258D01*
G01X1253844Y-39469D02*
X1250010D01*
G01X1272592Y-39467D02*
X1263924D01*
G01X1272258Y-39440D02*
X1264258D01*
G01X1253648Y-39154D02*
X1250010D01*
G01X1249641Y-38336D02*
X1246370D01*
G01Y-34399D02*
X1249641D01*
G01X1249177Y-34338D02*
X1249111D01*
G01X1262943Y-34319D02*
X1273573D01*
G01X1267522Y-33775D02*
X1259324D01*
G01X1257853D02*
X1249669D01*
G01X1253844Y-33249D02*
X1250010D01*
G01X1267508Y-33102D02*
X1259339D01*
G01X1257839D02*
X1249669D01*
G01Y-32967D02*
X1257839D01*
G01X1259339D02*
X1267508D01*
G01X1289411Y-32749D02*
X1247104D01*
G01X1245589Y-32023D02*
X1247619D01*
G01X1267507Y-31261D02*
X1259339D01*
G01X1249669Y-30829D02*
X1257839D01*
G01X1259339D02*
X1267508D01*
G01Y-30744D02*
X1259339D01*
G01X1257839D02*
X1249669D01*
G01X1257838Y-31261D02*
X1249669Y-31255D01*
G01X1247104Y-28812D02*
X1289411D01*
G01X1257853Y-33775D02*
X1257847Y-33744D01*
X1257843Y-33713D01*
X1257840Y-33682D01*
G01X1267522Y-33775D02*
X1267516Y-33744D01*
X1267512Y-33713D01*
X1267509Y-33682D01*
G01X1257840Y-33663D02*
X1257843Y-33701D01*
X1257847Y-33738D01*
X1257853Y-33775D01*
G01X1267509Y-33663D02*
X1267512Y-33701D01*
X1267516Y-33738D01*
X1267522Y-33775D01*
G01X1257840Y-33682D02*
X1257839Y-33647D01*
G01X1267509Y-33682D02*
X1267508Y-33647D01*
G01X1257839Y-33621D02*
X1257840Y-33663D01*
G01X1267508Y-33621D02*
X1267509Y-33663D01*
G01X1247104Y-32749D02*
X1247109Y-42635D01*
G01X1244539Y-22238D02*
Y-31524D01*
G01X1244589Y-33023D02*
Y-33845D01*
G01X1246104Y-32749D02*
Y-42635D01*
G01Y-28812D02*
Y105958D01*
G01X1246370Y-34399D02*
Y-38336D01*
G01X1247104Y-42635D02*
Y-32749D01*
G01Y-28812D02*
Y105958D01*
G01X1248104Y-38336D02*
Y-34399D01*
G01X1248619Y-33023D02*
Y-33845D01*
G01X1248669Y-22238D02*
Y-31524D01*
G01X1249420Y-38879D02*
Y-33339D01*
G01X1249669Y-17548D02*
Y-33845D01*
G01X1250641Y-35399D02*
Y-37336D01*
G01X1254238Y-33339D02*
Y-38564D01*
G01X1254435Y-33839D02*
Y-38879D01*
G01X1257840Y-33682D02*
Y-33663D01*
G01X1257839Y-17548D02*
Y-33647D01*
G01X1259339D02*
Y-17548D01*
G01X1259338Y-33663D02*
Y-33682D01*
G01X1262943Y-34319D02*
Y-32749D01*
G01X1263258Y-41835D02*
Y-40398D01*
G01X1265374Y-34319D02*
Y-32749D01*
G01X1265994D02*
Y-34319D01*
G01X1267509Y-33682D02*
Y-33663D01*
G01X1267508Y-17548D02*
Y-33647D01*
G01X1247111Y-14225D02*
X1247104Y-28812D01*
G01X1259338Y-33663D02*
X1259339Y-33621D01*
G01Y-33647D02*
X1259338Y-33682D01*
G01D02*
X1259335Y-33713D01*
X1259331Y-33744D01*
X1259324Y-33775D01*
G01D02*
X1259331Y-33738D01*
X1259335Y-33701D01*
X1259338Y-33663D01*
G01X1262465Y-41928D02*
X1262051Y-42342D01*
G01X1249641Y-38336D02*
G03X1250641Y-37336I0J1000D01*
G01X1253648Y-39154D02*
G03X1254238Y-38564I0J590D01*
G01X1253844Y-39469D02*
G03X1254435Y-38879I1J590D01*
G01X1249420D02*
G03X1250010Y-39469I590J0D01*
G01X1249420Y-38564D02*
G03X1250010Y-39154I590J0D01*
G01X1245589Y-32023D02*
G03X1244589Y-33023I0J-1000D01*
G01X1250641Y-35399D02*
G03X1249641Y-34399I-1000J0D01*
G01X1250010Y-33249D02*
G03X1249420Y-33839I0J-590D01*
G01X1254238D02*
G03X1253648Y-33249I-590J0D01*
G01X1254435Y-33839D02*
G03X1253844Y-33249I-590J0D01*
G01X1248619Y-33845D02*
G03X1249111Y-34338I492J-1D01*
G01X1249177D02*
G03X1249669Y-33845I0J492D01*
G01X1248619Y-33023D02*
G03X1247619Y-32023I-1000J0D01*
G01X1254238Y-33339D02*
G03X1253648Y-32749I-590J0D01*
G01X1250010D02*
G03X1249420Y-33339I0J-590D01*
G01X1249169Y-32016D02*
G03X1249669Y-31524I8J492D01*
G01X1248669D02*
G03X1249169Y-32016I492J0D01*
G01X1263172Y-41635D02*
G03X1262465Y-41928I0J-1000D01*
G01X1261344Y-42635D02*
G03X1262051Y-42342I0J1000D01*
G01X1264258Y-39440D02*
G03X1263258Y-40440I0J-1000D01*
G01X1260743Y-41435D02*
G03X1261701Y-40679I1J984D01*
G01X1263924Y-39467D02*
G03X1263258Y-40398I318J-931D01*
G01Y-40845D02*
G03X1261701Y-40679I-787J0D01*
G01X1257853Y-33775D02*
G03X1258589Y-34378I734J145D01*
G01D02*
G03X1259324Y-33775I1J748D01*
G01X1267522D02*
G03X1268258Y-34378I734J145D01*
G01X1267508Y-31261D02*
G03X1268258Y-32016I748J-7D01*
G01X1258589D02*
G03X1259339Y-31261I2J748D01*
G01X1257839D02*
G03X1258589Y-32016I748J-7D01*
G01X1268258Y-34378D02*
G03X1268994Y-33775I2J748D01*
G01X1268258Y-32016D02*
G03X1269008Y-31261I2J748D01*
G01X1269795Y-16798D02*
X1269643Y-16813D01*
X1269495Y-16857D01*
X1269360Y-16929D01*
X1269239Y-17028D01*
X1269141Y-17146D01*
X1269069Y-17281D01*
X1269024Y-17427D01*
X1269008Y-17582D01*
G01X1269795Y-16904D02*
X1269643Y-16917D01*
X1269495Y-16954D01*
X1269360Y-17015D01*
X1269239Y-17099D01*
X1269141Y-17199D01*
X1269069Y-17313D01*
X1269024Y-17437D01*
X1269008Y-17568D01*
G01X1277177Y-18862D02*
X1269008D01*
G01Y-18845D02*
X1277177D01*
G01Y-18516D02*
X1269008D01*
G01Y-18481D02*
X1277177D01*
G01Y-18138D02*
X1269008D01*
G01Y-18104D02*
X1277177D01*
G01X1269008Y-17890D02*
X1277177D01*
G01Y-17679D02*
X1269008D01*
G01X1281729Y-17318D02*
X1276807D01*
G01X1269795Y-17116D02*
X1276390D01*
G01Y-16904D02*
X1269795D01*
G01Y-16798D02*
X1276390D01*
G01Y-16764D02*
X1269795D01*
G01X1281729Y-14786D02*
X1276807D01*
G01Y-14307D02*
X1281729D01*
G01Y-9699D02*
X1276807D01*
G01Y-9220D02*
X1281729D01*
G01X1276807Y-6688D02*
X1281729D01*
G01Y-1570D02*
X1276807D01*
G01X1281729Y962D02*
X1276807D01*
G01Y1441D02*
X1281729D01*
G01Y6049D02*
X1276807D01*
G01X1276390Y-17116D02*
X1276543Y-17128D01*
X1276690Y-17166D01*
X1276826Y-17227D01*
X1276947Y-17310D01*
X1277044Y-17410D01*
X1277117Y-17525D01*
X1277162Y-17649D01*
X1277177Y-17780D01*
G01X1276390Y-16764D02*
X1276543Y-16779D01*
X1276690Y-16823D01*
X1276826Y-16895D01*
X1276947Y-16994D01*
X1277044Y-17112D01*
X1277117Y-17247D01*
X1277162Y-17393D01*
X1277177Y-17548D01*
G01Y-17582D02*
X1277162Y-17430D01*
X1277118Y-17284D01*
X1277046Y-17149D01*
X1276947Y-17028D01*
X1276828Y-16931D01*
X1276693Y-16858D01*
X1276546Y-16814D01*
X1276390Y-16798D01*
G01X1277177Y-17568D02*
X1277162Y-17439D01*
X1277118Y-17315D01*
X1277046Y-17201D01*
X1276947Y-17099D01*
X1276828Y-17016D01*
X1276693Y-16955D01*
X1276546Y-16917D01*
X1276390Y-16904D01*
G01X1269795D02*
Y-17116D01*
G01Y-16798D02*
Y-16764D01*
G01X1276390D02*
Y-16798D01*
G01Y-17116D02*
Y-16904D01*
G01X1276807Y9060D02*
Y-1570D01*
G01Y-6688D02*
Y-17318D01*
G01X1269008Y-17548D02*
X1269023Y-17396D01*
X1269067Y-17249D01*
X1269140Y-17114D01*
X1269239Y-16994D01*
X1269357Y-16896D01*
X1269493Y-16824D01*
X1269640Y-16779D01*
X1269795Y-16764D01*
G01X1269008Y-17780D02*
X1269023Y-17651D01*
X1269067Y-17527D01*
X1269140Y-17412D01*
X1269239Y-17310D01*
X1269357Y-17228D01*
X1269493Y-17167D01*
X1269640Y-17129D01*
X1269795Y-17116D01*
G01X1269008Y-24077D02*
X1277177D01*
G01Y-23942D02*
X1269008D01*
G01X1277177Y-23756D02*
X1269008D01*
G01Y-23671D02*
X1277177D01*
G01X1269008Y-23348D02*
X1277177D01*
G01Y-23331D02*
X1269008D01*
G01Y-23097D02*
X1277177D01*
G01Y-23063D02*
X1269008D01*
G01X1260126Y-16798D02*
X1259973Y-16813D01*
X1259826Y-16857D01*
X1259691Y-16929D01*
X1259569Y-17028D01*
X1259472Y-17146D01*
X1259399Y-17281D01*
X1259354Y-17427D01*
X1259339Y-17582D01*
G01X1250457Y-16798D02*
X1250304Y-16813D01*
X1250157Y-16857D01*
X1250021Y-16929D01*
X1249900Y-17028D01*
X1249802Y-17146D01*
X1249730Y-17281D01*
X1249685Y-17427D01*
X1249669Y-17582D01*
G01X1252764Y-16904D02*
X1252606Y-16918D01*
X1252454Y-16958D01*
X1252315Y-17023D01*
X1252192Y-17112D01*
X1252095Y-17218D01*
X1252024Y-17341D01*
G01X1260126Y-16904D02*
X1259973Y-16917D01*
X1259826Y-16954D01*
X1259691Y-17015D01*
X1259569Y-17099D01*
X1259472Y-17199D01*
X1259399Y-17313D01*
X1259354Y-17437D01*
X1259339Y-17568D01*
G01X1267508Y-18862D02*
X1259339D01*
G01X1256043D02*
X1251466D01*
G01Y-18845D02*
X1256043D01*
G01X1259339D02*
X1267508D01*
G01X1257839Y-18516D02*
X1249669D01*
G01X1267508D02*
X1259339D01*
G01X1249669Y-18481D02*
X1257839D01*
G01X1259339D02*
X1267508D01*
G01Y-18138D02*
X1259339D01*
G01X1257839D02*
X1249669D01*
G01Y-18104D02*
X1257839D01*
G01X1259339D02*
X1267508D01*
G01X1251878Y-17890D02*
X1255630D01*
G01X1259339D02*
X1267508D01*
G01Y-17679D02*
X1259339D01*
G01X1255630D02*
X1251878D01*
G01X1259709Y-17318D02*
X1254787D01*
G01X1246372Y-17178D02*
X1250232D01*
G01X1252764Y-17116D02*
X1254744D01*
G01X1260126D02*
X1266720D01*
G01Y-16904D02*
X1260126D01*
G01X1254744D02*
X1252764D01*
G01X1250457Y-16798D02*
X1257051D01*
G01X1260126D02*
X1266720D01*
G01Y-16764D02*
X1260126D01*
G01X1257051D02*
X1250457D01*
G01X1246372Y-15934D02*
X1251616D01*
G01X1259709Y-14786D02*
X1254787D01*
G01Y-14307D02*
X1259709D01*
G01X1250232Y-11273D02*
X1246372D01*
G01X1259709Y-9699D02*
X1254787D01*
G01Y-9220D02*
X1259709D01*
G01X1251616Y-8060D02*
X1246372D01*
G01X1254787Y-6688D02*
X1259709D01*
G01X1247104Y-2525D02*
X1246104D01*
G01Y-1874D02*
X1247104D01*
G01X1246104Y-1777D02*
X1247104D01*
G01X1259709Y-1570D02*
X1254787D01*
G01X1246104Y-1273D02*
X1247104D01*
G01X1246104Y-1244D02*
X1247104D01*
G01Y-832D02*
X1246104D01*
G01Y153D02*
X1247104D01*
G01X1246104Y560D02*
X1247104D01*
G01X1246104Y590D02*
X1247104D01*
G01X1259709Y962D02*
X1254787D01*
G01X1246104Y1097D02*
X1247104D01*
G01Y1190D02*
X1246104D01*
G01X1254787Y1441D02*
X1259709D01*
G01X1247104Y1845D02*
X1246104D01*
G01X1247104Y3845D02*
X1246104D01*
G01X1247104Y4436D02*
X1246104D01*
G01X1259709Y6049D02*
X1254787D01*
G01X1266720Y-17116D02*
X1266874Y-17128D01*
X1267021Y-17166D01*
X1267156Y-17227D01*
X1267278Y-17310D01*
X1267375Y-17410D01*
X1267448Y-17525D01*
X1267493Y-17649D01*
X1267508Y-17780D01*
G01X1254744Y-17116D02*
X1254902Y-17129D01*
X1255054Y-17170D01*
X1255193Y-17234D01*
X1255316Y-17323D01*
X1255413Y-17430D01*
X1255484Y-17553D01*
G01X1257051Y-16764D02*
X1257204Y-16779D01*
X1257352Y-16823D01*
X1257487Y-16895D01*
X1257608Y-16994D01*
X1257706Y-17112D01*
X1257778Y-17247D01*
X1257823Y-17393D01*
X1257839Y-17548D01*
G01X1266720Y-16764D02*
X1266874Y-16779D01*
X1267021Y-16823D01*
X1267156Y-16895D01*
X1267278Y-16994D01*
X1267375Y-17112D01*
X1267448Y-17247D01*
X1267493Y-17393D01*
X1267508Y-17548D01*
G01X1255484Y-17341D02*
X1255415Y-17220D01*
X1255318Y-17114D01*
X1255198Y-17025D01*
X1255057Y-16959D01*
X1254905Y-16918D01*
X1254744Y-16904D01*
G01X1255630Y-17890D02*
X1255767Y-18195D01*
X1255905Y-18522D01*
X1256043Y-18862D01*
G01X1255484Y-17553D02*
X1255630Y-17890D01*
G01Y-17679D02*
X1255484Y-17341D01*
G01X1256043Y-18845D02*
X1255905Y-18437D01*
X1255767Y-18044D01*
X1255630Y-17679D01*
G01X1257839Y-17582D02*
X1257824Y-17430D01*
X1257780Y-17284D01*
X1257707Y-17149D01*
X1257608Y-17028D01*
X1257489Y-16931D01*
X1257354Y-16858D01*
X1257207Y-16814D01*
X1257051Y-16798D01*
G01X1267508Y-17582D02*
X1267493Y-17430D01*
X1267449Y-17284D01*
X1267376Y-17149D01*
X1267278Y-17028D01*
X1267159Y-16931D01*
X1267023Y-16858D01*
X1266876Y-16814D01*
X1266720Y-16798D01*
G01X1267508Y-17568D02*
X1267493Y-17439D01*
X1267449Y-17315D01*
X1267376Y-17201D01*
X1267278Y-17099D01*
X1267159Y-17016D01*
X1267023Y-16955D01*
X1266876Y-16917D01*
X1266720Y-16904D01*
G01X1246372Y-8060D02*
Y-17178D01*
G01X1247109Y31917D02*
X1247111Y-6351D01*
G01X1247122Y-14225D02*
Y-6351D01*
G01X1248104Y-15934D02*
Y-8060D01*
G01X1248108Y-11273D02*
Y-17178D01*
G01X1250457Y-16798D02*
Y-16764D01*
G01X1251232Y-12273D02*
Y-16178D01*
G01X1251466Y-18862D02*
Y-18845D01*
G01X1251545Y-9725D02*
Y-13990D01*
G01X1251878Y-17679D02*
Y-17890D01*
G01X1252024Y-17553D02*
Y-17341D01*
G01X1252616Y-9060D02*
Y-14934D01*
G01X1252764Y-16904D02*
Y-17116D01*
G01X1254744D02*
Y-16904D01*
G01X1254787Y9060D02*
Y-1570D01*
G01Y-6688D02*
Y-17318D01*
G01X1255484Y-17341D02*
Y-17553D01*
G01X1255630Y-17890D02*
Y-17679D01*
G01X1256043Y-18845D02*
Y-18862D01*
G01X1257051Y-16764D02*
Y-16798D01*
G01X1259709Y-17318D02*
Y-6688D01*
G01Y-1570D02*
Y9060D01*
G01X1260126Y-16904D02*
Y-17116D01*
G01Y-16798D02*
Y-16764D01*
G01X1266720D02*
Y-16798D01*
G01Y-17116D02*
Y-16904D01*
G01X1249669Y-17548D02*
X1249685Y-17396D01*
X1249729Y-17249D01*
X1249801Y-17114D01*
X1249900Y-16994D01*
X1250019Y-16896D01*
X1250154Y-16824D01*
X1250301Y-16779D01*
X1250457Y-16764D01*
G01X1259339Y-17548D02*
X1259354Y-17396D01*
X1259398Y-17249D01*
X1259470Y-17114D01*
X1259569Y-16994D01*
X1259688Y-16896D01*
X1259824Y-16824D01*
X1259970Y-16779D01*
X1260126Y-16764D01*
G01X1259339Y-17780D02*
X1259354Y-17651D01*
X1259398Y-17527D01*
X1259470Y-17412D01*
X1259569Y-17310D01*
X1259688Y-17228D01*
X1259824Y-17167D01*
X1259970Y-17129D01*
X1260126Y-17116D01*
G01X1251486Y-14327D02*
X1248729Y-21902D01*
G01X1251878Y-17679D02*
X1251741Y-18044D01*
X1251603Y-18437D01*
X1251466Y-18845D01*
G01Y-18862D02*
X1251603Y-18522D01*
X1251741Y-18195D01*
X1251878Y-17890D01*
G01X1252024Y-17341D02*
X1251878Y-17679D01*
G01Y-17890D02*
X1252024Y-17553D01*
G01D02*
X1252094Y-17432D01*
X1252190Y-17325D01*
X1252310Y-17237D01*
X1252452Y-17170D01*
X1252603Y-17130D01*
X1252764Y-17116D01*
G01X1251232Y-12273D02*
G03X1250232Y-11273I-1000J0D01*
G01Y-17178D02*
G03X1251232Y-16178I0J1000D01*
G01X1251616Y-15934D02*
G03X1252616Y-14934I0J1000D01*
G01Y-9060D02*
G03X1251616Y-8060I-1000J0D01*
G01X1248729Y-21902D02*
G03X1248669Y-22238I924J-338D01*
G01X1251486Y-14327D02*
G03X1251545Y-13990I-925J336D01*
G01Y-9725D02*
G03X1250561Y-8741I-984J0D01*
G01X1244539Y-22238D02*
G03X1244480Y-21902I-984J0D01*
G01X1249669Y-24077D02*
X1257839D01*
G01X1259339D02*
X1267508D01*
G01Y-23942D02*
X1259339D01*
G01X1257839D02*
X1249669D01*
G01X1267508Y-23756D02*
X1259339D01*
G01X1257811D02*
X1249697D01*
G01Y-23671D02*
X1257811D01*
G01X1259339D02*
X1267508D01*
G01X1249831Y-23348D02*
X1257677D01*
G01X1259339D02*
X1267508D01*
G01Y-23331D02*
X1259339D01*
G01X1257677D02*
X1249831D01*
G01X1249669Y-23097D02*
X1257839D01*
G01X1259339D02*
X1267508D01*
G01X1247104Y-23095D02*
X1289411D01*
G01X1267508Y-23063D02*
X1259339D01*
G01X1257839D02*
X1249669D01*
G01X1289411Y-22468D02*
X1247104D01*
G01X1257791Y-23615D02*
X1257677Y-23331D01*
G01X1256043Y-18862D02*
X1257677Y-23348D01*
G01Y-23331D02*
X1256043Y-18845D01*
G01X1257677Y-23348D02*
X1257791Y-23689D01*
G01D02*
X1257798Y-23711D01*
X1257805Y-23734D01*
X1257811Y-23756D01*
G01Y-23671D02*
X1257805Y-23652D01*
X1257798Y-23633D01*
X1257791Y-23615D01*
G01X1257811Y-23756D02*
X1257819Y-23787D01*
X1257826Y-23821D01*
X1257831Y-23853D01*
X1257835Y-23888D01*
X1257838Y-23923D01*
X1257839Y-23958D01*
G01Y-23872D02*
X1257838Y-23840D01*
X1257836Y-23805D01*
X1257832Y-23773D01*
X1257827Y-23739D01*
X1257820Y-23705D01*
X1257811Y-23671D01*
G01X1249697Y-23756D02*
Y-23671D01*
G01X1249717Y-23615D02*
Y-23689D01*
G01X1249831Y-23331D02*
Y-23339D01*
G01D02*
Y-23348D01*
G01X1257791Y-23689D02*
Y-23615D01*
G01X1257811Y-23671D02*
Y-23756D01*
G01X1257677Y-23348D02*
Y-23331D01*
G01X1249669Y-23958D02*
X1249670Y-23925D01*
X1249672Y-23891D01*
X1249676Y-23858D01*
X1249681Y-23824D01*
X1249689Y-23790D01*
X1249697Y-23756D01*
G01Y-23671D02*
X1249689Y-23702D01*
X1249682Y-23736D01*
X1249677Y-23768D01*
X1249673Y-23803D01*
X1249670Y-23838D01*
X1249669Y-23872D01*
G01X1249697Y-23756D02*
X1249703Y-23734D01*
X1249710Y-23711D01*
X1249717Y-23689D01*
G01D02*
X1249831Y-23348D01*
G01X1251466Y-18845D02*
X1249831Y-23331D01*
G01Y-23348D02*
X1251466Y-18862D01*
G01X1249717Y-23615D02*
X1249710Y-23633D01*
X1249703Y-23652D01*
X1249697Y-23671D01*
G01X1249831Y-23331D02*
X1249717Y-23615D01*
G01X1271703Y12877D02*
X1269703D01*
G01Y14058D02*
X1270703D01*
G01X1270837Y18393D02*
X1271537D01*
G01X1273790D02*
X1274490D01*
G01X1276743D02*
X1277443D01*
G01X1270703Y18585D02*
X1269703D01*
G01X1271703Y19766D02*
X1269703D01*
G01X1277443Y21371D02*
X1276743D01*
G01X1274490D02*
X1273790D01*
G01X1271537D02*
X1270837D01*
G01X1277443Y24336D02*
X1276743D01*
G01X1274490D02*
X1273790D01*
G01X1271537D02*
X1270837D01*
G01X1277443Y24561D02*
X1276743D01*
G01X1274490D02*
X1273790D01*
G01X1271537D02*
X1270837D01*
G01X1271913Y27251D02*
X1268961D01*
G01X1271913Y28251D02*
X1268961D01*
G01X1271913Y29251D02*
X1268961D01*
G01X1271913Y29501D02*
X1268961D01*
G01X1269551Y31367D02*
X1271323D01*
G01X1285852Y36767D02*
X1275400D01*
G01X1278026Y37588D02*
X1276132D01*
G01X1273691Y38588D02*
X1278159D01*
G01X1274363Y39032D02*
X1274337D01*
G01X1278494Y39392D02*
X1276526D01*
G01X1276446Y35857D02*
X1274363Y37940D01*
G01X1274337Y39032D02*
X1271384Y41985D01*
G01X1275202Y36569D02*
X1276266Y35267D01*
G01X1274337Y38069D02*
X1275400Y36767D01*
G01X1274337Y38069D02*
X1275202Y36569D01*
G01X1276266Y35267D02*
X1275400Y36767D01*
G01X1271796Y39341D02*
X1272120Y38627D01*
X1272262Y37855D01*
G01X1278526Y38088D02*
X1278515Y38173D01*
X1278481Y38258D01*
X1278422Y38341D01*
X1278340Y38418D01*
X1278234Y38484D01*
X1278105Y38538D01*
X1277957Y38574D01*
X1277793Y38588D01*
G01X1268584Y24561D02*
Y18393D01*
G01X1268961Y30777D02*
Y26751D01*
G01X1269703Y19766D02*
Y12877D01*
G01X1270703Y19766D02*
Y12877D01*
G01X1270837Y24561D02*
Y18393D01*
G01X1271537Y24561D02*
Y18393D01*
G01X1271703Y19766D02*
Y12877D01*
G01X1271913Y30777D02*
Y26751D01*
G01X1272913Y31038D02*
Y26751D01*
G01X1273101Y43339D02*
Y39178D01*
G01X1273790Y24561D02*
Y18393D01*
G01X1274337Y44408D02*
Y38069D01*
G01X1274363Y44408D02*
Y37940D01*
G01X1274490Y24561D02*
Y18393D01*
G01X1275061Y44408D02*
Y37242D01*
G01X1275202Y36569D02*
Y44408D01*
G01X1276132Y40780D02*
Y34257D01*
G01X1276276Y43930D02*
Y38588D01*
G01X1276526Y44408D02*
Y36767D01*
G01X1276743Y24561D02*
Y18393D01*
G01X1277443Y24561D02*
Y18393D01*
G01X1277526Y43930D02*
Y38588D01*
G01X1272213Y37073D02*
X1272262Y37855D01*
X1272120Y38627D01*
G01X1276132Y34257D02*
X1271520Y29645D01*
G01X1271913Y30777D02*
G03X1271323Y31367I-590J0D01*
G01X1269551D02*
G03X1268961Y30777I0J-590D01*
G01X1271913Y26751D02*
G03X1272913I500J0D01*
G01X1273101Y39178D02*
G03X1273691Y38588I590J0D01*
G01X1278026Y37588D02*
G03X1278526Y38088I0J500D01*
G01X1276807Y6528D02*
X1281729D01*
G01X1276807Y9060D02*
X1281729D01*
G01X1258723Y38588D02*
X1258443Y38547D01*
X1258209Y38441D01*
X1258048Y38279D01*
X1257990Y38088D01*
G01X1285852Y12019D02*
X1250616D01*
G01X1283687Y14955D02*
X1252781D01*
G01X1251616Y18242D02*
X1246372D01*
G01X1256073Y18393D02*
X1256773D01*
G01X1259026D02*
X1259726D01*
G01X1261978D02*
X1262678D01*
G01X1264931D02*
X1265631D01*
G01X1267884D02*
X1268584D01*
G01Y21371D02*
X1267884D01*
G01X1265631D02*
X1264931D01*
G01X1259726D02*
X1259026D01*
G01X1262678D02*
X1261978D01*
G01X1256773D02*
X1256073D01*
G01X1268584Y24336D02*
X1267884D01*
G01X1265631D02*
X1264931D01*
G01X1259726D02*
X1259026D01*
G01X1262678D02*
X1261978D01*
G01X1256773D02*
X1256073D01*
G01X1268584Y24561D02*
X1267884D01*
G01X1265631D02*
X1264931D01*
G01X1262678D02*
X1261978D01*
G01X1259726D02*
X1259026D01*
G01X1256773D02*
X1256073D01*
G01X1246372Y26116D02*
X1251616D01*
G01X1267961Y27251D02*
X1264603D01*
G01X1267961Y28251D02*
X1264603D01*
G01X1267961Y29251D02*
X1264603D01*
G01X1267961Y29501D02*
X1264603D01*
G01X1271520Y29645D02*
X1264996D01*
G01X1247297Y31917D02*
X1247104D01*
G01X1267370Y32851D02*
X1265193D01*
G01X1252781Y34353D02*
X1283687D01*
G01Y35141D02*
X1252781D01*
G01X1285852Y35267D02*
X1250616D01*
G01X1276446Y35857D02*
X1260022D01*
G01X1261069Y36767D02*
X1250616D01*
G01X1260384Y37588D02*
X1258490D01*
G01X1258357Y38588D02*
X1262825D01*
G01X1246372Y38853D02*
X1250232D01*
G01X1262132Y39032D02*
X1262105D01*
G01X1259990Y39392D02*
X1258022D01*
G01X1247104Y39791D02*
X1247297D01*
G01X1266880Y34687D02*
X1267709Y34292D01*
X1268641Y34145D01*
X1269571Y34260D01*
X1270457Y34632D01*
X1271236Y35247D01*
X1271833Y36062D01*
X1272213Y37073D01*
G01X1266880Y34686D02*
X1267690Y34298D01*
X1268613Y34147D01*
X1269544Y34252D01*
X1270439Y34621D01*
X1271228Y35238D01*
X1271830Y36057D01*
X1272212Y37073D01*
G01X1264996Y29645D02*
X1260384Y34257D01*
G01X1271796Y39341D02*
X1271103Y40133D01*
X1270264Y40686D01*
X1269313Y40994D01*
X1268335Y41031D01*
X1267411Y40806D01*
X1266590Y40333D01*
X1265962Y39674D01*
G01X1271796Y39341D02*
X1271139Y40265D01*
X1270240Y40969D01*
X1269141Y41398D01*
X1267983Y41489D01*
X1266844Y41238D01*
X1265842Y40682D01*
X1265032Y39846D01*
X1264498Y38822D01*
X1264282Y37666D01*
X1264411Y36502D01*
X1264859Y35448D01*
X1265613Y34547D01*
X1266605Y33899D01*
X1267744Y33574D01*
X1268908Y33592D01*
X1270019Y33950D01*
X1270978Y34614D01*
X1271714Y35547D01*
X1272144Y36666D01*
X1272222Y37866D01*
X1271925Y39065D01*
X1271317Y40063D01*
X1270460Y40833D01*
X1269367Y41340D01*
X1268202Y41497D01*
X1267060Y41313D01*
X1265992Y40790D01*
X1265150Y40005D01*
X1264567Y39005D01*
X1264293Y37852D01*
X1264361Y36714D01*
X1264755Y35630D01*
X1265452Y34697D01*
X1266403Y33999D01*
X1267502Y33612D01*
X1268654Y33560D01*
X1269770Y33837D01*
X1270711Y34385D01*
X1271488Y35195D01*
X1272026Y36241D01*
X1272235Y37379D01*
X1272102Y38551D01*
X1271646Y39606D01*
X1270892Y40501D01*
X1269914Y41136D01*
X1268769Y41464D01*
X1267641Y41451D01*
X1266528Y41101D01*
X1265575Y40458D01*
X1264828Y39533D01*
X1264374Y38387D01*
X1264292Y37197D01*
X1264547Y36081D01*
X1265114Y35079D01*
X1265955Y34274D01*
X1267015Y33738D01*
X1268189Y33540D01*
X1269384Y33702D01*
X1270436Y34188D01*
X1271307Y34961D01*
X1271917Y35956D01*
X1272213Y37089D01*
X1272170Y38249D01*
X1271796Y39341D01*
G01X1272214Y38246D02*
X1271832Y39363D01*
X1271144Y40321D01*
X1270204Y41039D01*
X1269098Y41452D01*
X1267919Y41526D01*
X1266763Y41253D01*
X1265751Y40664D01*
X1264940Y39792D01*
X1264423Y38731D01*
X1264236Y37567D01*
X1264397Y36392D01*
X1264885Y35327D01*
X1265677Y34434D01*
X1266684Y33817D01*
X1267823Y33520D01*
X1269004Y33566D01*
X1270118Y33953D01*
X1271079Y34651D01*
X1271791Y35597D01*
X1272196Y36703D01*
X1272264Y37880D01*
X1271985Y39030D01*
X1271385Y40048D01*
X1270511Y40850D01*
X1269448Y41361D01*
X1268281Y41540D01*
X1267111Y41373D01*
X1266043Y40876D01*
X1265159Y40083D01*
X1264548Y39072D01*
X1264257Y37928D01*
X1264310Y36749D01*
X1264704Y35636D01*
X1265404Y34685D01*
X1266350Y33978D01*
X1267461Y33577D01*
X1268641Y33515D01*
X1269787Y33799D01*
X1270800Y34402D01*
X1271596Y35274D01*
X1272104Y36340D01*
X1272280Y37508D01*
X1272110Y38676D01*
X1271607Y39745D01*
X1270822Y40618D01*
X1269813Y41228D01*
X1268668Y41519D01*
X1267489Y41466D01*
X1266371Y41070D01*
X1265432Y40380D01*
X1264724Y39439D01*
X1264319Y38330D01*
X1264253Y37152D01*
X1264534Y35999D01*
X1265126Y34995D01*
X1265990Y34197D01*
X1267052Y33682D01*
X1268217Y33497D01*
X1269387Y33658D01*
X1270455Y34150D01*
X1271332Y34925D01*
X1271953Y35930D01*
X1272255Y37069D01*
X1272214Y38246D01*
G01X1272212Y37073D02*
X1272170Y38248D01*
X1271776Y39377D01*
X1271093Y40312D01*
X1270157Y41015D01*
X1269019Y41425D01*
X1267817Y41473D01*
X1266638Y41153D01*
X1265676Y40547D01*
X1264931Y39701D01*
X1264443Y38649D01*
X1264280Y37437D01*
X1264496Y36222D01*
X1265015Y35212D01*
X1265819Y34375D01*
X1266817Y33809D01*
X1267931Y33553D01*
X1269150Y33640D01*
X1270257Y34077D01*
X1271141Y34776D01*
X1271798Y35701D01*
X1272171Y36795D01*
X1272215Y37942D01*
X1271911Y39097D01*
X1271309Y40073D01*
X1270437Y40847D01*
X1269419Y41325D01*
X1268273Y41498D01*
X1267057Y41312D01*
X1266031Y40818D01*
X1265189Y40051D01*
X1264578Y39033D01*
X1264297Y37904D01*
X1264354Y36751D01*
X1264759Y35620D01*
X1265455Y34695D01*
X1266353Y34025D01*
X1267442Y33624D01*
X1268650Y33559D01*
X1269781Y33842D01*
X1270757Y34422D01*
X1271556Y35293D01*
X1272048Y36305D01*
X1272237Y37526D01*
X1272047Y38734D01*
X1271558Y39744D01*
X1270790Y40588D01*
X1269816Y41180D01*
X1268685Y41475D01*
X1267480Y41421D01*
X1266374Y41025D01*
X1265476Y40364D01*
X1264774Y39441D01*
X1264378Y38402D01*
X1264289Y37241D01*
X1264569Y36025D01*
X1265153Y35030D01*
X1266008Y34237D01*
X1267078Y33718D01*
X1268228Y33540D01*
X1269379Y33700D01*
X1270447Y34195D01*
X1271297Y34949D01*
X1271920Y35962D01*
X1272213Y37073D01*
G01X1246372Y26116D02*
Y18242D01*
G01Y38853D02*
Y44759D01*
G01X1247298Y31917D02*
Y39791D01*
G01X1248104Y44759D02*
Y38853D01*
G01Y18242D02*
Y26116D01*
G01X1251232Y43759D02*
Y39853D01*
G01X1252616Y19242D02*
Y25116D01*
G01X1252781Y35141D02*
Y14955D01*
G01X1256073Y24561D02*
Y18393D01*
G01X1256773Y24561D02*
Y18393D01*
G01X1257990Y43930D02*
Y38088D01*
G01X1258022Y44408D02*
Y36767D01*
G01X1258990Y43930D02*
Y38588D01*
G01X1259026Y24561D02*
Y18393D01*
G01X1259726Y24561D02*
Y18393D01*
G01X1259990Y44408D02*
Y36767D01*
G01X1260240Y43930D02*
Y38588D01*
G01X1260384Y34257D02*
Y40780D01*
G01X1261266Y44408D02*
Y36569D01*
G01X1261407Y44408D02*
Y37242D01*
G01X1261978Y24561D02*
Y18393D01*
G01X1262105Y37940D02*
Y44408D01*
G01X1262132Y38069D02*
Y44408D01*
G01X1262678Y24561D02*
Y18393D01*
G01X1263415Y43339D02*
Y39178D01*
G01X1263603Y31038D02*
Y26751D01*
G01X1264603Y32261D02*
Y26751D01*
G01X1264931Y24561D02*
Y18393D01*
G01X1265631Y24561D02*
Y18393D01*
G01X1267884Y24561D02*
Y18393D01*
G01X1267961Y32261D02*
Y26751D01*
G01X1257990Y38088D02*
X1258022Y38288D01*
X1258105Y38447D01*
X1258224Y38552D01*
X1258357Y38588D01*
G01X1266589Y40332D02*
X1267402Y40802D01*
X1268312Y41029D01*
X1269275Y41001D01*
X1270228Y40703D01*
X1271081Y40152D01*
X1271796Y39341D01*
G01X1261069Y36767D02*
X1260202Y35267D01*
G01X1261266Y36569D02*
X1262132Y38069D01*
G01X1261069Y36767D02*
X1262132Y38069D01*
G01X1260202Y35267D02*
X1261266Y36569D01*
G01X1265085Y41985D02*
X1262132Y39032D01*
G01X1262105Y37940D02*
X1260022Y35857D01*
G01X1251616Y18242D02*
G03X1252616Y19242I0J1000D01*
G01Y25116D02*
G03X1251616Y26116I-1000J0D01*
G01X1250232Y38853D02*
G03X1251232Y39853I0J1000D01*
G01X1263603Y26751D02*
G03X1264603I500J0D01*
G01X1267961D02*
G03X1268961I500J0D01*
G01X1272589Y37519D02*
G03I-4331J0D01*
G01X1271407D02*
G03I-3149J0D01*
G01X1265193Y32851D02*
G03X1264603Y32261I0J-590D01*
G01X1267961D02*
G03X1267370Y32851I-591J-1D01*
G01X1262825Y38588D02*
G03X1263415Y39178I0J590D01*
G01X1257990Y38088D02*
G03X1258490Y37588I500J0D01*
G01X1254787Y6528D02*
X1259709D01*
G01X1246104Y6877D02*
X1247104D01*
G01Y7468D02*
X1246104D01*
G01X1254787Y9060D02*
X1259709D01*
G01X1250616Y11019D02*
X1285852D01*
G01X1250616Y44408D02*
Y11019D01*
G01X1252781Y14955D02*
X1251600Y11019D01*
G01X1252781Y14955D02*
X1251600Y11019D01*
G01X1276743Y48355D02*
X1277443D01*
G01Y48571D02*
X1276743D01*
G01X1277443Y48667D02*
X1276743D01*
G01X1277443Y48729D02*
X1276743D01*
G01X1277443Y48827D02*
X1276743D01*
G01X1277443Y49812D02*
X1276743D01*
G01X1277443Y49910D02*
X1276743D01*
G01X1277443Y49973D02*
X1276743D01*
G01X1277443Y50068D02*
X1276743D01*
G01Y50284D02*
X1277443D01*
G01X1270837Y51111D02*
X1271537D01*
G01Y51327D02*
X1270837D01*
G01X1271537Y51423D02*
X1270837D01*
G01X1271537Y51485D02*
X1270837D01*
G01X1271537Y51583D02*
X1270837D01*
G01X1271537Y52568D02*
X1270837D01*
G01X1271537Y52666D02*
X1270837D01*
G01X1271537Y52729D02*
X1270837D01*
G01X1271537Y52823D02*
X1270837D01*
G01Y53040D02*
X1271537D01*
G01X1274490Y53867D02*
X1273790D01*
G01Y54083D02*
X1274490D01*
G01X1273790Y54179D02*
X1274490D01*
G01X1273790Y54241D02*
X1274490D01*
G01Y54339D02*
X1273790D01*
G01X1274490Y55323D02*
X1273790D01*
G01X1274490Y55422D02*
X1273790D01*
G01Y55484D02*
X1274490D01*
G01X1273790Y55579D02*
X1274490D01*
G01Y55796D02*
X1273790D01*
G01X1276743Y63316D02*
X1277443D01*
G01Y63532D02*
X1276743D01*
G01X1277443Y63627D02*
X1276743D01*
G01X1277443Y63690D02*
X1276743D01*
G01X1277443Y63788D02*
X1276743D01*
G01X1277443Y64772D02*
X1276743D01*
G01X1277443Y64871D02*
X1276743D01*
G01X1277443Y64933D02*
X1276743D01*
G01X1277443Y65028D02*
X1276743D01*
G01Y65245D02*
X1277443D01*
G01X1270837Y66071D02*
X1271537D01*
G01Y66288D02*
X1270837D01*
G01X1271537Y66383D02*
X1270837D01*
G01X1271537Y66445D02*
X1270837D01*
G01X1271537Y66544D02*
X1270837D01*
G01X1271537Y67528D02*
X1270837D01*
G01X1271537Y67627D02*
X1270837D01*
G01X1271537Y67689D02*
X1270837D01*
G01X1271537Y67784D02*
X1270837D01*
G01Y68001D02*
X1271537D01*
G01X1274490Y68827D02*
X1273790D01*
G01Y69044D02*
X1274490D01*
G01X1273790Y69139D02*
X1274490D01*
G01X1273790Y69201D02*
X1274490D01*
G01Y69300D02*
X1273790D01*
G01X1274490Y70284D02*
X1273790D01*
G01X1274490Y70382D02*
X1273790D01*
G01Y70445D02*
X1274490D01*
G01Y70540D02*
X1273790D01*
G01X1274490Y70756D02*
X1273790D01*
G01X1268584Y48357D02*
Y50283D01*
G01Y63318D02*
Y65243D01*
G01X1270837Y51112D02*
Y53038D01*
G01Y66073D02*
Y67999D01*
G01X1271537Y51113D02*
Y53039D01*
G01Y66073D02*
Y67999D01*
G01X1273790Y53868D02*
Y55794D01*
G01Y68829D02*
Y70755D01*
G01X1274490Y53869D02*
Y55795D01*
G01Y68829D02*
Y70755D01*
G01X1276743Y48356D02*
Y50282D01*
G01Y63317D02*
Y65243D01*
G01X1277443Y48357D02*
Y50283D01*
G01Y63318D02*
Y65243D01*
G01X1278494Y41062D02*
X1276526D01*
G01X1289411Y43930D02*
X1273691D01*
G01X1276132Y40780D02*
X1271520Y45393D01*
G01X1273156Y46512D02*
Y44408D01*
G01X1273691Y43930D02*
G03X1273101Y43339I1J-591D01*
G01X1256587Y54572D02*
X1256535Y54558D01*
G01X1256600Y54492D02*
X1256535Y54478D01*
G01X1247104Y45223D02*
X1246104D01*
G01X1264996Y45393D02*
X1271520D01*
G01X1273156Y45528D02*
X1263313D01*
G01X1246104Y46475D02*
X1247104D01*
G01X1273156Y46512D02*
X1263313D01*
G01X1247104Y47182D02*
X1246104D01*
G01X1259026Y48355D02*
X1259726D01*
G01X1267884D02*
X1268584D01*
G01Y48571D02*
X1267884D01*
G01X1259726D02*
X1259026D01*
G01X1268584Y48667D02*
X1267884D01*
G01X1259726D02*
X1259026D01*
G01X1268584Y48729D02*
X1267884D01*
G01X1259726D02*
X1259026D01*
G01X1268584Y48827D02*
X1267884D01*
G01X1259726D02*
X1259026D01*
G01X1268584Y49812D02*
X1267884D01*
G01X1259726D02*
X1259026D01*
G01X1268584Y49910D02*
X1267884D01*
G01X1259726D02*
X1259026D01*
G01X1268584Y49973D02*
X1267884D01*
G01X1259726D02*
X1259026D01*
G01X1268584Y50068D02*
X1267884D01*
G01X1259726D02*
X1259026D01*
G01Y50284D02*
X1259726D01*
G01X1267884D02*
X1268584D01*
G01X1246104Y50541D02*
X1247104D01*
G01X1246104Y50638D02*
X1247104D01*
G01X1261978Y51111D02*
X1262678D01*
G01X1246104Y51142D02*
X1247104D01*
G01X1246104Y51171D02*
X1247104D01*
G01X1262678Y51327D02*
X1261978D01*
G01X1262678Y51423D02*
X1261978D01*
G01X1262678Y51485D02*
X1261978D01*
G01X1262678Y51583D02*
X1261978D01*
G01X1247104D02*
X1246104D01*
G01X1262678Y52568D02*
X1261978D01*
G01X1246104D02*
X1247104D01*
G01X1262678Y52666D02*
X1261978D01*
G01X1262678Y52729D02*
X1261978D01*
G01X1262678Y52823D02*
X1261978D01*
G01X1246104Y52975D02*
X1247104D01*
G01X1246104Y53005D02*
X1247104D01*
G01X1261978Y53040D02*
X1262678D01*
G01X1246104Y53512D02*
X1247104D01*
G01Y53605D02*
X1246104D01*
G01X1265631Y53867D02*
X1264931D01*
G01X1256773D02*
X1256073D01*
G01Y54083D02*
X1256773D01*
G01X1264931D02*
X1265631D01*
G01X1256073Y54179D02*
X1256773D01*
G01X1264931D02*
X1265631D01*
G01X1256073Y54241D02*
X1256773D01*
G01X1264931D02*
X1265631D01*
G01X1247104Y54260D02*
X1246104D01*
G01X1247104Y54275D02*
X1246104D01*
G01X1265631Y54339D02*
X1264931D01*
G01X1256773D02*
X1256073D01*
G01X1256535Y54478D02*
X1256220D01*
G01X1256928D02*
X1256850D01*
G01X1257374D02*
X1257296D01*
G01X1257637D02*
X1257558D01*
G01X1256535Y54558D02*
X1256298D01*
G01X1257243Y54639D02*
X1256981D01*
G01X1257230Y54693D02*
X1256994D01*
G01X1256298Y55028D02*
X1256535D01*
G01X1256220Y55108D02*
X1256535D01*
G01X1257059D02*
X1257165D01*
G01X1257558D02*
X1257637D01*
G01X1265631Y55323D02*
X1264931D01*
G01X1256773D02*
X1256073D01*
G01X1265631Y55422D02*
X1264931D01*
G01X1256773D02*
X1256073D01*
G01Y55484D02*
X1256773D01*
G01X1264931D02*
X1265631D01*
G01X1256073Y55579D02*
X1256773D01*
G01X1264931D02*
X1265631D01*
G01Y55796D02*
X1264931D01*
G01X1256773D02*
X1256073D01*
G01X1259026Y63316D02*
X1259726D01*
G01X1267884D02*
X1268584D01*
G01Y63532D02*
X1267884D01*
G01X1259726D02*
X1259026D01*
G01X1268584Y63627D02*
X1267884D01*
G01X1259726D02*
X1259026D01*
G01X1268584Y63690D02*
X1267884D01*
G01X1259726D02*
X1259026D01*
G01X1268584Y63788D02*
X1267884D01*
G01X1259726D02*
X1259026D01*
G01X1268584Y64772D02*
X1267884D01*
G01X1259726D02*
X1259026D01*
G01X1268584Y64871D02*
X1267884D01*
G01X1259726D02*
X1259026D01*
G01X1268584Y64933D02*
X1267884D01*
G01X1259726D02*
X1259026D01*
G01X1268584Y65028D02*
X1267884D01*
G01X1259726D02*
X1259026D01*
G01Y65245D02*
X1259726D01*
G01X1267884D02*
X1268584D01*
G01X1261978Y66071D02*
X1262678D01*
G01Y66288D02*
X1261978D01*
G01X1262678Y66383D02*
X1261978D01*
G01X1262678Y66445D02*
X1261978D01*
G01X1262678Y66544D02*
X1261978D01*
G01X1262678Y67528D02*
X1261978D01*
G01X1262678Y67627D02*
X1261978D01*
G01X1262678Y67689D02*
X1261978D01*
G01X1262678Y67784D02*
X1261978D01*
G01Y68001D02*
X1262678D01*
G01X1250624Y68043D02*
X1246104D01*
G01X1265631Y68827D02*
X1264931D01*
G01X1256773D02*
X1256073D01*
G01Y69044D02*
X1256773D01*
G01X1264931D02*
X1265631D01*
G01X1256073Y69139D02*
X1256773D01*
G01X1264931D02*
X1265631D01*
G01X1256073Y69201D02*
X1256773D01*
G01X1264931D02*
X1265631D01*
G01Y69300D02*
X1264931D01*
G01X1256773D02*
X1256073D01*
G01X1265631Y70284D02*
X1264931D01*
G01X1256773D02*
X1256073D01*
G01X1265631Y70382D02*
X1264931D01*
G01X1256773D02*
X1256073D01*
G01Y70445D02*
X1256773D01*
G01X1264931D02*
X1265631D01*
G01Y70540D02*
X1264931D01*
G01X1256773D02*
X1256073D01*
G01X1265631Y70756D02*
X1264931D01*
G01X1256773D02*
X1256073D01*
G01X1256535Y55108D02*
X1256600Y55095D01*
G01X1256535Y55028D02*
X1256587Y55014D01*
G01X1256600Y55095D02*
X1256653Y55068D01*
G01X1256587Y55014D02*
X1256626Y54988D01*
G01X1256653Y55068D02*
X1256705Y55014D01*
G01X1256626Y54988D02*
X1256653Y54947D01*
G01X1256705Y55014D02*
X1256731Y54961D01*
G01X1257165Y55108D02*
X1257374Y54478D01*
G01X1257296D02*
X1257243Y54639D01*
G01X1257112Y55055D02*
X1257230Y54693D01*
G01X1256653Y54947D02*
X1256666Y54893D01*
G01X1256731Y54961D02*
X1256744Y54893D01*
G01X1245104Y66043D02*
Y56275D01*
G01X1245900D02*
Y66043D01*
G01X1247309Y77812D02*
Y68043D01*
G01X1248104D02*
Y77812D01*
G01X1249704Y68043D02*
Y77812D01*
G01X1251624Y76812D02*
Y69043D01*
G01X1256073Y53868D02*
Y55794D01*
G01Y68829D02*
Y70755D01*
G01X1256220Y54478D02*
Y55108D01*
G01X1256298Y54558D02*
Y55028D01*
G01X1256666Y54893D02*
Y54693D01*
G01X1256744Y54893D02*
Y54693D01*
G01X1256773Y53869D02*
Y55795D01*
G01Y68829D02*
Y70755D01*
G01X1257480Y54907D02*
Y55014D01*
G01X1257558Y54478D02*
Y55001D01*
G01X1257637Y55108D02*
Y54478D01*
G01X1259026Y48356D02*
Y50282D01*
G01Y63317D02*
Y65243D01*
G01X1259726Y48357D02*
Y50283D01*
G01Y63318D02*
Y65243D01*
G01X1261978Y51112D02*
Y53038D01*
G01Y66073D02*
Y67999D01*
G01X1262678Y51113D02*
Y53039D01*
G01Y66073D02*
Y67999D01*
G01X1264931Y53868D02*
Y55794D01*
G01Y68829D02*
Y70755D01*
G01X1265631Y53869D02*
Y55795D01*
G01Y68829D02*
Y70755D01*
G01X1267884Y48356D02*
Y50282D01*
G01Y63317D02*
Y65243D01*
G01X1256653Y54518D02*
X1256600Y54492D01*
G01X1256744Y54693D02*
X1256731Y54626D01*
G01X1256666Y54693D02*
X1256653Y54639D01*
G01X1256994Y54693D02*
X1257112Y55055D01*
G01X1256981Y54639D02*
X1256928Y54478D01*
G01X1256850D02*
X1257059Y55108D01*
G01X1256626Y54599D02*
X1256587Y54572D01*
G01X1256731Y54626D02*
X1256705Y54572D01*
G01X1256653Y54639D02*
X1256626Y54599D01*
G01X1257480Y55014D02*
X1257558Y55108D01*
G01Y55001D02*
X1257480Y54907D01*
G01X1256705Y54572D02*
X1256653Y54518D01*
G01X1250624Y68043D02*
G03X1251624Y69043I0J1000D01*
G01X1259990Y41062D02*
X1258022D01*
G01X1271384Y41985D02*
X1265085D01*
G01X1249041Y44408D02*
X1287427D01*
G01X1246104Y44516D02*
X1247104D01*
G01X1250232Y44759D02*
X1246372D01*
G01X1249041Y105171D02*
Y44408D01*
G01X1250041D02*
Y68043D01*
G01X1250669Y105171D02*
Y44408D01*
G01X1252083Y105171D02*
Y44408D01*
G01X1263313Y46512D02*
Y44408D01*
G01X1264996Y45393D02*
X1260384Y40780D01*
G01X1251232Y43759D02*
G03X1250232Y44759I-1000J0D01*
G01X1263415Y43339D02*
G03X1262825Y43930I-591J0D01*
G01X1277443Y79733D02*
X1276743D01*
G01X1277443Y79831D02*
X1276743D01*
G01X1277443Y79894D02*
X1276743D01*
G01X1277443Y79989D02*
X1276743D01*
G01Y80205D02*
X1277443D01*
G01X1270837Y81032D02*
X1271537D01*
G01Y81249D02*
X1270837D01*
G01X1271537Y81344D02*
X1270837D01*
G01X1271537Y81406D02*
X1270837D01*
G01X1271537Y81505D02*
X1270837D01*
G01X1271537Y82489D02*
X1270837D01*
G01X1271537Y82587D02*
X1270837D01*
G01X1271537Y82650D02*
X1270837D01*
G01X1271537Y82745D02*
X1270837D01*
G01Y82961D02*
X1271537D01*
G01X1274490Y83788D02*
X1273790D01*
G01Y84005D02*
X1274490D01*
G01X1273790Y84100D02*
X1274490D01*
G01X1273790Y84162D02*
X1274490D01*
G01Y84260D02*
X1273790D01*
G01X1274490Y85245D02*
X1273790D01*
G01X1274490Y85343D02*
X1273790D01*
G01Y85406D02*
X1274490D01*
G01Y85501D02*
X1273790D01*
G01X1274490Y85717D02*
X1273790D01*
G01X1276743Y93237D02*
X1277443D01*
G01Y93453D02*
X1276743D01*
G01X1277443Y93549D02*
X1276743D01*
G01X1277443Y93611D02*
X1276743D01*
G01X1277443Y93709D02*
X1276743D01*
G01X1277443Y94693D02*
X1276743D01*
G01X1277443Y94792D02*
X1276743D01*
G01X1277443Y94855D02*
X1276743D01*
G01X1277443Y94949D02*
X1276743D01*
G01Y95166D02*
X1277443D01*
G01X1270837Y95993D02*
X1271537D01*
G01Y96209D02*
X1270837D01*
G01X1271537Y96305D02*
X1270837D01*
G01X1271537Y96367D02*
X1270837D01*
G01X1271537Y96465D02*
X1270837D01*
G01X1271537Y97449D02*
X1270837D01*
G01X1271537Y97548D02*
X1270837D01*
G01X1271537Y97610D02*
X1270837D01*
G01X1271537Y97705D02*
X1270837D01*
G01Y97922D02*
X1271537D01*
G01X1274490Y98749D02*
X1273790D01*
G01Y98965D02*
X1274490D01*
G01X1273790Y99060D02*
X1274490D01*
G01X1273790Y99123D02*
X1274490D01*
G01Y99221D02*
X1273790D01*
G01X1274490Y100205D02*
X1273790D01*
G01X1274490Y100304D02*
X1273790D01*
G01Y100366D02*
X1274490D01*
G01Y100461D02*
X1273790D01*
G01X1274490Y100678D02*
X1273790D01*
G01X1268584Y93239D02*
Y95165D01*
G01X1270837Y81034D02*
Y82960D01*
G01Y95994D02*
Y97920D01*
G01X1271187Y105958D02*
Y106958D01*
G01X1271537Y81034D02*
Y82960D01*
G01Y95995D02*
Y97921D01*
G01X1273790Y83790D02*
Y85716D01*
G01Y98750D02*
Y100676D01*
G01X1274490Y83790D02*
Y85716D01*
G01Y98751D02*
Y100677D01*
G01X1275715Y105171D02*
Y102336D01*
G01X1276360Y106958D02*
Y105958D01*
G01X1276743Y93238D02*
Y95164D01*
G01X1277093Y105171D02*
Y102336D01*
G01X1277443Y93239D02*
Y95165D01*
G01X1277860Y105958D02*
Y106958D01*
G01X1276743Y78276D02*
X1277443D01*
G01Y78493D02*
X1276743D01*
G01X1277443Y78588D02*
X1276743D01*
G01X1277443Y78650D02*
X1276743D01*
G01X1277443Y78749D02*
X1276743D01*
G01X1268584Y78278D02*
Y80204D01*
G01X1276743Y78278D02*
Y80204D01*
G01X1277443Y78278D02*
Y80204D01*
G01X1268584Y79733D02*
X1267884D01*
G01X1259726D02*
X1259026D01*
G01X1268584Y79831D02*
X1267884D01*
G01X1259726D02*
X1259026D01*
G01X1268584Y79894D02*
X1267884D01*
G01X1259726D02*
X1259026D01*
G01X1268584Y79989D02*
X1267884D01*
G01X1259726D02*
X1259026D01*
G01Y80205D02*
X1259726D01*
G01X1267884D02*
X1268584D01*
G01X1261978Y81032D02*
X1262678D01*
G01Y81249D02*
X1261978D01*
G01X1262678Y81344D02*
X1261978D01*
G01X1262678Y81406D02*
X1261978D01*
G01X1262678Y81505D02*
X1261978D01*
G01X1262678Y82489D02*
X1261978D01*
G01X1262678Y82587D02*
X1261978D01*
G01X1262678Y82650D02*
X1261978D01*
G01X1262678Y82745D02*
X1261978D01*
G01Y82961D02*
X1262678D01*
G01X1265631Y83788D02*
X1264931D01*
G01X1256773D02*
X1256073D01*
G01Y84005D02*
X1256773D01*
G01X1264931D02*
X1265631D01*
G01X1256073Y84100D02*
X1256773D01*
G01X1264931D02*
X1265631D01*
G01X1256073Y84162D02*
X1256773D01*
G01X1264931D02*
X1265631D01*
G01Y84260D02*
X1264931D01*
G01X1256773D02*
X1256073D01*
G01X1246104Y85182D02*
X1247104D01*
G01X1265631Y85245D02*
X1264931D01*
G01X1256773D02*
X1256073D01*
G01X1265631Y85343D02*
X1264931D01*
G01X1256773D02*
X1256073D01*
G01Y85406D02*
X1256773D01*
G01X1264931D02*
X1265631D01*
G01Y85501D02*
X1264931D01*
G01X1256773D02*
X1256073D01*
G01X1265631Y85717D02*
X1264931D01*
G01X1256773D02*
X1256073D01*
G01X1246372Y91636D02*
X1250232D01*
G01X1259026Y93237D02*
X1259726D01*
G01X1267884D02*
X1268584D01*
G01Y93453D02*
X1267884D01*
G01X1259726D02*
X1259026D01*
G01X1268584Y93549D02*
X1267884D01*
G01X1259726D02*
X1259026D01*
G01X1268584Y93611D02*
X1267884D01*
G01X1259726D02*
X1259026D01*
G01X1268584Y93709D02*
X1267884D01*
G01X1259726D02*
X1259026D01*
G01X1268584Y94693D02*
X1267884D01*
G01X1259726D02*
X1259026D01*
G01X1268584Y94792D02*
X1267884D01*
G01X1259726D02*
X1259026D01*
G01X1268584Y94855D02*
X1267884D01*
G01X1259726D02*
X1259026D01*
G01X1268584Y94949D02*
X1267884D01*
G01X1259726D02*
X1259026D01*
G01Y95166D02*
X1259726D01*
G01X1267884D02*
X1268584D01*
G01X1261978Y95993D02*
X1262678D01*
G01Y96209D02*
X1261978D01*
G01X1262678Y96305D02*
X1261978D01*
G01X1262678Y96367D02*
X1261978D01*
G01X1262678Y96465D02*
X1261978D01*
G01X1250624Y96578D02*
X1246104D01*
G01X1262678Y97449D02*
X1261978D01*
G01X1250232Y97542D02*
X1246372D01*
G01X1262678Y97548D02*
X1261978D01*
G01X1262678Y97610D02*
X1261978D01*
G01X1262678Y97705D02*
X1261978D01*
G01Y97922D02*
X1262678D01*
G01X1265631Y98749D02*
X1264931D01*
G01X1256773D02*
X1256073D01*
G01Y98965D02*
X1256773D01*
G01X1264931D02*
X1265631D01*
G01X1256073Y99060D02*
X1256773D01*
G01X1264931D02*
X1265631D01*
G01X1256073Y99123D02*
X1256773D01*
G01X1264931D02*
X1265631D01*
G01Y99221D02*
X1264931D01*
G01X1256773D02*
X1256073D01*
G01X1265631Y100205D02*
X1264931D01*
G01X1256773D02*
X1256073D01*
G01X1265631Y100304D02*
X1264931D01*
G01X1256773D02*
X1256073D01*
G01Y100366D02*
X1256773D01*
G01X1264931D02*
X1265631D01*
G01Y100461D02*
X1264931D01*
G01X1256773D02*
X1256073D01*
G01X1265631Y100678D02*
X1264931D01*
G01X1256773D02*
X1256073D01*
G01X1254848Y102336D02*
X1281620D01*
G01X1246104Y103048D02*
X1247104D01*
G01Y103974D02*
X1246104D01*
G01X1247104Y104974D02*
X1246104D01*
G01X1246285Y105169D02*
X1246876D01*
G01X1245104Y94578D02*
Y86182D01*
G01X1245900D02*
Y94578D01*
G01X1246372Y91636D02*
Y97542D01*
G01X1247309Y105171D02*
Y96578D01*
G01X1248104Y91636D02*
Y105171D01*
G01X1249704Y96578D02*
Y105171D01*
G01X1251026Y107942D02*
Y106958D01*
G01X1251232Y92636D02*
Y96542D01*
G01X1251624Y104171D02*
Y97578D01*
G01X1252026Y107942D02*
Y106958D01*
G01X1254628Y105958D02*
Y106958D01*
G01X1254848Y105171D02*
Y102336D01*
G01X1255628Y106958D02*
Y105958D01*
G01X1256073Y83790D02*
Y85716D01*
G01Y98750D02*
Y100676D01*
G01X1256773Y83790D02*
Y85716D01*
G01Y98751D02*
Y100677D01*
G01X1257624Y106958D02*
Y105958D01*
G01X1257628Y105171D02*
Y106958D01*
G01X1258644D02*
Y105958D01*
G01X1259026Y93238D02*
Y95164D01*
G01X1259726Y93239D02*
Y95165D01*
G01X1259987Y105958D02*
Y106958D01*
G01X1260799D02*
Y105958D01*
G01X1260892D02*
Y106958D01*
G01X1261378Y105958D02*
Y106958D01*
G01X1261429Y105958D02*
Y106958D01*
G01X1261837Y105958D02*
Y106958D01*
G01X1261978Y81034D02*
Y82960D01*
G01Y95994D02*
Y97920D01*
G01X1262678Y81034D02*
Y82960D01*
G01Y95995D02*
Y97921D01*
G01X1262821Y106958D02*
Y105958D01*
G01X1263233D02*
Y106958D01*
G01X1263284Y105958D02*
Y106958D01*
G01X1263766Y105958D02*
Y106958D01*
G01X1263863Y105958D02*
Y106958D01*
G01X1264514Y105958D02*
Y106958D01*
G01X1264931Y83790D02*
Y85716D01*
G01Y98750D02*
Y100676D01*
G01X1265281Y102336D02*
Y105171D01*
G01Y105958D02*
Y106958D01*
G01X1265631Y83790D02*
Y85716D01*
G01Y98751D02*
Y100677D01*
G01X1266014Y105958D02*
Y106958D01*
G01X1266659Y102336D02*
Y105171D01*
G01X1267884Y93238D02*
Y95164D01*
G01X1248104Y107942D02*
G03X1246381Y106958I0J-2000D01*
G01X1250624Y96578D02*
G03X1251624Y97578I0J1000D01*
G01Y104171D02*
G03X1250624Y105171I-1000J0D01*
G01X1251232Y96542D02*
G03X1250232Y97542I-1000J0D01*
G01Y91636D02*
G03X1251232Y92636I0J1000D01*
G01X1246104Y77812D02*
X1250624D01*
G01X1259026Y78276D02*
X1259726D01*
G01X1267884D02*
X1268584D01*
G01Y78493D02*
X1267884D01*
G01X1259726D02*
X1259026D01*
G01X1268584Y78588D02*
X1267884D01*
G01X1259726D02*
X1259026D01*
G01X1268584Y78650D02*
X1267884D01*
G01X1259726D02*
X1259026D01*
G01X1268584Y78749D02*
X1267884D01*
G01X1259726D02*
X1259026D01*
G01X1247104Y78812D02*
X1246104D01*
G01X1249041Y75643D02*
X1247104Y77580D01*
G01X1250041Y77812D02*
Y96578D01*
G01X1259026Y78278D02*
Y80204D01*
G01X1259726Y78278D02*
Y80204D01*
G01X1267884Y78278D02*
Y80204D01*
G01X1251624Y76812D02*
G03X1250624Y77812I-1000J0D01*
G01X1252026Y107942D02*
X1248104D01*
G01X1275492Y883464D02*
X1273327D01*
G01X1278642D02*
X1276476D01*
G01X1272343D02*
X1270177D01*
G01X1269193Y892519D02*
Y883464D01*
G01X1270177D02*
Y892519D01*
G01X1272343D02*
Y883464D01*
G01X1273327D02*
Y892519D01*
G01X1275492D02*
Y883464D01*
G01X1276476D02*
Y892519D01*
G01X1266043Y883464D02*
X1263878D01*
G01X1269193D02*
X1267028D01*
G01X1262894D02*
X1260728D01*
G01X1256594D02*
X1254429D01*
G01X1259744D02*
X1257579D01*
G01X1253445D02*
X1251280D01*
G01X1247146D02*
X1244980D01*
G01X1250295D02*
X1248130D01*
G01X1244980D02*
Y892519D01*
G01X1247146D02*
Y883464D01*
G01X1248130D02*
Y892519D01*
G01X1250295D02*
Y883464D01*
G01X1251280D02*
Y892519D01*
G01X1253445D02*
Y883464D01*
G01X1254429D02*
Y892519D01*
G01X1256594D02*
Y883464D01*
G01X1257579D02*
Y892519D01*
G01X1259744D02*
Y883464D01*
G01X1260728D02*
Y892519D01*
G01X1262894D02*
Y883464D01*
G01X1263878D02*
Y892519D01*
G01X1266043D02*
Y883464D01*
G01X1267028D02*
Y892519D01*
G01X1270177D02*
X1272343D01*
G01X1273327D02*
X1275492D01*
G01X1276476D02*
X1278642D01*
G01X1244980D02*
X1247146D01*
G01X1248130D02*
X1250295D01*
G01X1251280D02*
X1253445D01*
G01X1254429D02*
X1256594D01*
G01X1257579D02*
X1259744D01*
G01X1260728D02*
X1262894D01*
G01X1263878D02*
X1266043D01*
G01X1267028D02*
X1269193D01*
G01X1283288Y-1120610D02*
Y-1139623D01*
G01X1285204Y-682078D02*
Y-662393D01*
G01Y-642708D02*
Y-662393D01*
G01D02*
Y-602865D01*
G01X1315171Y-622944D02*
X1311562Y-622457D01*
X1309397Y-621970D01*
G01D02*
X1306510Y-620995D01*
Y-624893D01*
G01X1315171Y-599558D02*
X1314450Y-600532D01*
X1313728Y-601020D01*
X1312284Y-601507D01*
X1309397D01*
X1307954Y-601020D01*
X1307231Y-600532D01*
X1306510Y-599558D01*
X1307231Y-598584D01*
X1307954Y-598096D01*
X1309397Y-597609D01*
X1312284D01*
X1313728Y-598096D01*
X1314450Y-598584D01*
X1315171Y-599558D01*
G01Y-607353D02*
X1314450Y-608328D01*
X1313728Y-608815D01*
X1312284Y-609302D01*
X1309397D01*
X1307954Y-608815D01*
X1307231Y-608328D01*
X1306510Y-607353D01*
X1307231Y-606379D01*
X1307954Y-605892D01*
X1309397Y-605405D01*
X1312284D01*
X1313728Y-605892D01*
X1314450Y-606379D01*
X1315171Y-607353D01*
G01X1306510Y-630739D02*
X1315171D01*
G01X1283038Y-622353D02*
Y-622840D01*
X1282316D01*
X1283038Y-622353D01*
G01X1283968Y-442223D02*
X1283481D01*
Y-441501D01*
X1283968Y-442223D01*
G01X1291763D02*
X1290789Y-441501D01*
X1290302Y-440780D01*
X1289814Y-439336D01*
Y-436449D01*
X1290302Y-435005D01*
X1290789Y-434284D01*
X1291763Y-433562D01*
X1292737Y-434284D01*
X1293225Y-435005D01*
X1293712Y-436449D01*
Y-439336D01*
X1293225Y-440780D01*
X1292737Y-441501D01*
X1291763Y-442223D01*
G01X1299558D02*
X1298584Y-441501D01*
X1298097Y-440780D01*
X1297609Y-439336D01*
Y-436449D01*
X1298097Y-435005D01*
X1298584Y-434284D01*
X1299558Y-433562D01*
X1300533Y-434284D01*
X1301020Y-435005D01*
X1301507Y-436449D01*
Y-439336D01*
X1301020Y-440780D01*
X1300533Y-441501D01*
X1299558Y-442223D01*
G01X1307080Y-400157D02*
X1306106Y-399435D01*
X1305619Y-398714D01*
X1305131Y-397270D01*
Y-394383D01*
X1305619Y-392939D01*
X1306106Y-392218D01*
X1307080Y-391496D01*
X1308054Y-392218D01*
X1308541Y-392939D01*
X1309029Y-394383D01*
Y-397270D01*
X1308541Y-398714D01*
X1308054Y-399435D01*
X1307080Y-400157D01*
G01X1289541Y-392939D02*
X1290028Y-392218D01*
X1291002Y-391496D01*
X1291977D01*
X1292951Y-392218D01*
X1293438Y-392939D01*
Y-394383D01*
X1292951Y-395105D01*
X1291977Y-395827D01*
X1291002Y-396548D01*
X1290028Y-397992D01*
X1289541Y-400157D01*
X1293438D01*
G01X1283694Y-391496D02*
Y-400157D01*
G01X1299285D02*
X1298797D01*
Y-399435D01*
X1299285Y-400157D01*
G01X1289322Y-42635D02*
X1289372Y-42626D01*
X1289402Y-42596D01*
X1289411Y-42545D01*
G01X1290608Y-40442D02*
X1290411Y-40444D01*
G01X1289387Y-41640D02*
X1290411Y-41635D01*
G01X1286846Y-31255D02*
X1278678Y-31261D01*
G01X1290411Y-42342D02*
X1289411D01*
G01X1290111Y-42135D02*
X1290011D01*
G01X1290411Y-41928D02*
X1289411D01*
G01X1289404Y-41635D02*
X1290411D01*
G01X1290533Y-41435D02*
X1290411D01*
G01X1290805Y-40845D02*
X1290411D01*
G01X1289411Y-40746D02*
X1289348D01*
G01X1290805Y-40679D02*
X1290411D01*
G01Y-40670D02*
X1290805D01*
G01X1289411Y-40535D02*
X1289311D01*
G01X1290805Y-40442D02*
X1290608D01*
G01X1290411Y-40057D02*
X1290805D01*
G01X1289411Y-39762D02*
X1289348D01*
G01X1289311Y-39535D02*
X1289411D01*
G01X1286506Y-39469D02*
X1282672D01*
G01X1286309Y-39154D02*
X1282081D01*
G01X1290411Y-38336D02*
X1286874D01*
G01X1290411Y-34399D02*
X1286874D01*
G01X1286846Y-33775D02*
X1278663D01*
G01X1286506Y-33249D02*
X1282672D01*
G01X1286846Y-33102D02*
X1278677D01*
G01Y-32967D02*
X1286846D01*
G01X1290805Y-32016D02*
X1287043D01*
G01X1290805Y-31425D02*
X1290411D01*
G01X1290805Y-31261D02*
X1290411D01*
G01X1278677Y-30829D02*
X1286846D01*
G01Y-30744D02*
X1278677D01*
G01X1288411Y-29423D02*
X1290411D01*
G01X1289411Y-28769D02*
X1290411D01*
G01Y-27769D02*
X1289411D01*
G01X1288411Y-27423D02*
X1289411D01*
G01X1278677Y-33647D02*
Y-17548D01*
G01X1278676Y-33663D02*
Y-33682D01*
G01X1282081Y-39154D02*
Y-33339D01*
G01X1285874Y-35399D02*
Y-37336D01*
G01X1286846Y-17548D02*
Y-33866D01*
G01X1286900Y-33339D02*
Y-38564D01*
G01X1287043Y-32016D02*
Y-33866D01*
G01X1287096Y-33839D02*
Y-38879D01*
G01X1288411Y-32749D02*
Y-42635D01*
G01Y-32016D02*
Y106958D01*
G01X1288443Y-41435D02*
Y-32016D01*
G01X1289311Y-39535D02*
Y-41435D01*
G01X1289348Y-41402D02*
Y-39762D01*
G01X1289411Y-42635D02*
Y-32749D01*
G01Y-29423D02*
Y106958D01*
G01X1290411Y-38336D02*
Y-36368D01*
G01Y-42635D02*
Y106958D01*
G01Y-36368D02*
Y-34399D01*
G01X1290805Y-31255D02*
Y-41435D01*
G01Y-40442D02*
X1290803Y-40670D01*
G01X1278676Y-33663D02*
X1278677Y-33621D01*
G01Y-33647D02*
X1278676Y-33682D01*
G01X1290803Y-40670D02*
X1290793Y-40975D01*
X1290757Y-41222D01*
X1290673Y-41381D01*
X1290533Y-41435D01*
G01X1278676Y-33682D02*
X1278674Y-33713D01*
X1278669Y-33744D01*
X1278663Y-33775D01*
G01D02*
X1278669Y-33738D01*
X1278674Y-33701D01*
X1278676Y-33663D01*
G01X1292035Y-23671D02*
X1290468Y-30744D01*
G01X1292420Y-23756D02*
X1290852Y-30829D01*
G01X1290368Y-42635D02*
X1290393Y-42625D01*
X1290407Y-42595D01*
X1290411Y-42545D01*
G01X1286874Y-34399D02*
G03X1285874Y-35399I0J-1000D01*
G01Y-37336D02*
G03X1286874Y-38336I1000J0D01*
G01X1286309Y-39154D02*
G03X1286900Y-38564I0J591D01*
G01X1286506Y-39469D02*
G03X1287096Y-38879I0J590D01*
G01X1282081D02*
G03X1282672Y-39469I590J0D01*
G01X1286846Y-31425D02*
G03X1287437Y-32016I591J0D01*
G01X1282672Y-32749D02*
G03X1282081Y-33339I-1J-590D01*
G01X1282672Y-33249D02*
G03X1282081Y-33839I-1J-590D01*
G01X1286900Y-33339D02*
G03X1286309Y-32749I-591J-1D01*
G01X1287096Y-33839D02*
G03X1286506Y-33249I-590J0D01*
G01X1286900Y-33839D02*
G03X1286309Y-33249I-591J-1D01*
G01X1286846Y-33866D02*
G03X1287043I99J0D01*
G01X1289348Y-41402D02*
G03X1290805I728J0D01*
G01X1289311Y-41435D02*
G03X1290011Y-42135I700J0D01*
G01X1290111D02*
G03X1290413Y-42067I1J700D01*
G01X1290468Y-30744D02*
G03X1290411Y-31261I2305J-516D01*
G01X1290852Y-30829D02*
G03X1290805Y-31261I1922J-428D01*
G01X1288411Y-27423D02*
G03Y-29423I0J-1000D01*
G01X1396063Y-1D02*
X1310039D01*
G01X1396063D02*
X1310039D01*
G01X1302756Y6298D02*
Y9448D01*
G01X1304134D02*
Y6298D01*
G01X1306102Y-15749D02*
Y-3938D01*
G01Y-15749D02*
Y118109D01*
G01X1310039Y-1D02*
G03X1306102Y-3938I0J-3937D01*
G01X1310039Y-1D02*
G03X1306102Y-3938I0J-3937D01*
G01X1279465Y-16798D02*
X1279312Y-16813D01*
X1279165Y-16857D01*
X1279029Y-16929D01*
X1278908Y-17028D01*
X1278810Y-17146D01*
X1278738Y-17281D01*
X1278693Y-17427D01*
X1278677Y-17582D01*
G01X1279465Y-16904D02*
X1279312Y-16917D01*
X1279165Y-16954D01*
X1279029Y-17015D01*
X1278908Y-17099D01*
X1278810Y-17199D01*
X1278738Y-17313D01*
X1278693Y-17437D01*
X1278677Y-17568D01*
G01X1289411Y1845D02*
X1289753Y1853D01*
X1290007Y1897D01*
X1290177Y2018D01*
X1290255Y2231D01*
X1290276Y2505D01*
X1290278Y2845D01*
G01X1289319Y-4525D02*
X1289694Y-4520D01*
X1289970Y-4485D01*
X1290161Y-4371D01*
X1290252Y-4158D01*
X1290276Y-3876D01*
X1290278Y-3525D01*
G01X1286474Y-21261D02*
X1290411D01*
G01X1286846Y-18862D02*
X1278677D01*
G01Y-18845D02*
X1286846D01*
G01Y-18516D02*
X1278677D01*
G01Y-18481D02*
X1286846D01*
G01Y-18138D02*
X1278677D01*
G01Y-18104D02*
X1286846D01*
G01X1278677Y-17890D02*
X1286846D01*
G01Y-17679D02*
X1278677D01*
G01X1279465Y-17116D02*
X1286059D01*
G01Y-16904D02*
X1279465D01*
G01Y-16798D02*
X1286059D01*
G01Y-16764D02*
X1279465D01*
G01X1286474Y-13551D02*
X1290411D01*
G01X1288411Y-12551D02*
X1291671D01*
G01X1290278Y-11551D02*
X1289411D01*
G01X1290411Y-11383D02*
X1291671D01*
G01X1290278Y-10551D02*
X1289411D01*
G01Y-9460D02*
X1290278D01*
G01X1290144Y-8460D02*
X1284900D01*
G01Y-4525D02*
X1290144D01*
G01X1290411Y-2525D02*
X1289411D01*
G01X1291671Y-2040D02*
X1290411D01*
G01X1289411Y-1874D02*
X1290411D01*
G01X1289411Y-1777D02*
X1290411D01*
G01X1289411Y-1273D02*
X1290411D01*
G01X1289411Y-1244D02*
X1290411D01*
G01Y-1208D02*
X1291671D01*
G01X1290411Y-832D02*
X1289411D01*
G01Y153D02*
X1290411D01*
G01X1289411Y560D02*
X1290411D01*
G01X1289411Y590D02*
X1290411D01*
G01X1289411Y1097D02*
X1290411D01*
G01Y1190D02*
X1289411D01*
G01X1290411Y1845D02*
X1289411D01*
G01X1290278Y2845D02*
X1289411D01*
G01X1290411Y3845D02*
X1289411D01*
G01X1290411Y4436D02*
X1289411D01*
G01X1304134Y6298D02*
X1300984D01*
G01X1295079D02*
X1298228D01*
G01X1296457D02*
X1302756D01*
G01X1289412Y-8460D02*
X1289742Y-8467D01*
X1289994Y-8507D01*
X1290168Y-8621D01*
X1290253Y-8831D01*
X1290276Y-9108D01*
X1290278Y-9460D01*
G01X1286059Y-17116D02*
X1286212Y-17128D01*
X1286359Y-17166D01*
X1286495Y-17227D01*
X1286616Y-17310D01*
X1286713Y-17410D01*
X1286786Y-17525D01*
X1286831Y-17649D01*
X1286846Y-17780D01*
G01X1286059Y-16764D02*
X1286212Y-16779D01*
X1286359Y-16823D01*
X1286495Y-16895D01*
X1286616Y-16994D01*
X1286713Y-17112D01*
X1286786Y-17247D01*
X1286831Y-17393D01*
X1286846Y-17548D01*
G01X1289331Y-8460D02*
X1289377Y-8469D01*
X1289403Y-8495D01*
X1289411Y-8541D01*
G01X1292715Y-17568D02*
X1293046Y-17780D01*
G01X1293137Y-16904D02*
X1293470Y-17116D01*
G01X1286846Y-17582D02*
X1286831Y-17430D01*
X1286787Y-17284D01*
X1286715Y-17149D01*
X1286616Y-17028D01*
X1286497Y-16931D01*
X1286362Y-16858D01*
X1286215Y-16814D01*
X1286059Y-16798D01*
G01X1290278Y-3525D02*
X1290276Y-3173D01*
X1290252Y-2895D01*
X1290167Y-2685D01*
X1289993Y-2571D01*
X1289740Y-2531D01*
X1289411Y-2525D01*
G01X1289319Y-4525D02*
X1289322Y-5836D01*
X1289328Y-7148D01*
X1289331Y-8460D01*
G01X1289320Y-4525D02*
X1289278Y18242D01*
G01X1279465Y-16904D02*
Y-17116D01*
G01Y-16798D02*
Y-16764D01*
G01X1281729Y-17318D02*
Y-6688D01*
G01Y-1570D02*
Y9060D01*
G01X1283900Y-5525D02*
Y-7460D01*
G01X1285474Y-20261D02*
Y-14551D01*
G01X1286059Y-16764D02*
Y-16798D01*
G01Y-17116D02*
Y-16904D01*
G01X1286846Y-17568D02*
X1286831Y-17439D01*
X1286787Y-17315D01*
X1286715Y-17201D01*
X1286616Y-17099D01*
X1286497Y-17016D01*
X1286362Y-16955D01*
X1286215Y-16917D01*
X1286059Y-16904D01*
G01X1290144Y-8460D02*
Y-4525D01*
G01X1290278Y3845D02*
Y2845D01*
G01Y-9460D02*
Y-12551D01*
G01X1291671D02*
Y35593D01*
G01X1295079Y9448D02*
Y6298D01*
G01X1296457Y9448D02*
Y6298D01*
G01X1297244D02*
Y9448D01*
G01X1297408D02*
Y6298D01*
G01X1298228D02*
Y9448D01*
G01X1300984Y6298D02*
Y9448D01*
G01X1301805Y6298D02*
Y9448D01*
G01X1301969Y6298D02*
Y9448D01*
G01X1289278Y-12551D02*
X1289319Y-4525D01*
G01X1278677Y-17548D02*
X1278693Y-17396D01*
X1278737Y-17249D01*
X1278809Y-17114D01*
X1278908Y-16994D01*
X1279027Y-16896D01*
X1279162Y-16824D01*
X1279309Y-16779D01*
X1279465Y-16764D01*
G01X1278677Y-17780D02*
X1278693Y-17651D01*
X1278737Y-17527D01*
X1278809Y-17412D01*
X1278908Y-17310D01*
X1279027Y-17228D01*
X1279162Y-17167D01*
X1279309Y-17129D01*
X1279465Y-17116D01*
G01X1289411Y-4444D02*
X1289403Y-4490D01*
X1289376Y-4516D01*
X1289319Y-4525D01*
G01X1293137Y-16904D02*
X1292644Y-17679D01*
G01X1293470Y-17116D02*
X1292976Y-17890D01*
G01X1289411Y-15551D02*
G03X1288411Y-14551I-1000J0D01*
G01X1285474Y-20261D02*
G03X1286474Y-21261I1000J0D01*
G01X1288411Y-12551D02*
G03Y-14551I0J-1000D01*
G01X1286474Y-13551D02*
G03X1285474Y-14551I0J-1000D01*
G01X1283900Y-7460D02*
G03X1284900Y-8460I1000J0D01*
G01X1302165Y-19686D02*
G03X1306102Y-15749I0J3937D01*
G01X1302165Y-19686D02*
G03X1306102Y-15749I0J3937D01*
G01X1292644Y-17679D02*
G03X1292276Y-18845I1992J-1270D01*
G01X1292976Y-17890D02*
G03X1292670Y-18862I1661J-1057D01*
G01X1284900Y-4525D02*
G03X1283900Y-5525I0J-1000D01*
G01X1438388Y58404D02*
G03I-79730J0D01*
G01X1289411Y-24261D02*
X1290411D01*
G01X1278677Y-24077D02*
X1286846D01*
G01Y-23942D02*
X1278677D01*
G01X1286846Y-23756D02*
X1278677D01*
G01Y-23671D02*
X1286846D01*
G01X1278677Y-23348D02*
X1286846D01*
G01Y-23331D02*
X1278677D01*
G01X1289411Y-23261D02*
X1290411D01*
G01X1278677Y-23097D02*
X1286846D01*
G01Y-23063D02*
X1278677D01*
G01X1292276Y-18845D02*
X1292080Y-23331D01*
G01X1292670Y-18862D02*
X1292474Y-23348D01*
G01X1292420Y-23756D02*
G03X1292474Y-23348I-2306J513D01*
G01X1292035Y-23671D02*
G03X1292080Y-23331I-1921J427D01*
G01X1302476Y31239D02*
X1302402D01*
G01X1302894D02*
X1302820D01*
G01X1302771Y31390D02*
X1302525D01*
G01X1302759Y31440D02*
X1302537D01*
G01X1302598Y31830D02*
X1302697D01*
G01D02*
X1302894Y31239D01*
G01X1302820D02*
X1302771Y31390D01*
G01X1302648Y31779D02*
X1302759Y31440D01*
G01X1302756Y29920D02*
Y33070D01*
G01X1304134D02*
Y29920D01*
G01X1302537Y31440D02*
X1302648Y31779D01*
G01X1302525Y31390D02*
X1302476Y31239D01*
G01X1302402D02*
X1302598Y31830D01*
G01X1302476Y7617D02*
X1302402D01*
G01X1302894D02*
X1302820D01*
G01X1302771Y7768D02*
X1302525D01*
G01X1302759Y7818D02*
X1302537D01*
G01X1302598Y8208D02*
X1302697D01*
G01D02*
X1302894Y7617D01*
G01X1302820D02*
X1302771Y7768D01*
G01X1302648Y8157D02*
X1302759Y7818D01*
G01X1302537D02*
X1302648Y8157D01*
G01X1302525Y7768D02*
X1302476Y7617D01*
G01X1302402D02*
X1302598Y8208D01*
G01X1301250Y31616D02*
X1301240Y31613D01*
G01X1300391Y31628D02*
X1300401Y31630D01*
G01X1300167Y31628D02*
X1300177Y31630D01*
G01X1300369Y31716D02*
X1300359Y31714D01*
G01X1300145Y31716D02*
X1300135Y31714D01*
G01X1299274Y31628D02*
X1299284Y31630D01*
G01X1299252Y31716D02*
X1299242Y31714D01*
G01X1301238Y31626D02*
X1301250Y31628D01*
G01X1301088Y31616D02*
X1301076Y31613D01*
G01X1301226Y31719D02*
X1301213Y31716D01*
G01X1300928Y31668D02*
X1300915Y31666D01*
G01X1300571Y31616D02*
X1300559Y31613D01*
G01X1300404Y31616D02*
X1300391Y31613D01*
G01X1300273D02*
X1300285Y31616D01*
G01X1300787Y31719D02*
X1300775Y31716D01*
G01X1300180Y31616D02*
X1300167Y31613D01*
G01X1300261Y31688D02*
X1300249Y31686D01*
G01X1300357Y31729D02*
X1300369Y31731D01*
G01X1299776Y31613D02*
X1299789Y31616D01*
G01X1300261Y31731D02*
X1300249Y31729D01*
G01X1300133D02*
X1300145Y31731D01*
G01X1299776Y31656D02*
X1299789Y31658D01*
G01X1299929Y31719D02*
X1299917Y31716D01*
G01X1299287Y31616D02*
X1299274Y31613D01*
G01X1299764Y31731D02*
X1299752Y31729D01*
G01X1299240D02*
X1299252Y31731D01*
G01X1289330Y26116D02*
X1289376Y26124D01*
X1289403Y26151D01*
X1289411Y26196D01*
G01X1301211Y31729D02*
X1301228Y31731D01*
G01X1300773Y31729D02*
X1300790Y31731D01*
G01X1299914Y31729D02*
X1299931Y31731D01*
G01X1290411Y14915D02*
X1291789D01*
G01X1289411Y17242D02*
X1290278D01*
G01X1291789Y17868D02*
X1290411D01*
G01X1290144Y18242D02*
X1284900D01*
G01X1279695Y18393D02*
X1280395D01*
G01Y21371D02*
X1279695D01*
G01X1280395Y24336D02*
X1279695D01*
G01X1280395Y24561D02*
X1279695D01*
G01X1284900Y26116D02*
X1290144D01*
G01X1290278Y27116D02*
X1289411D01*
G01X1304134Y29920D02*
X1300984D01*
G01X1295079D02*
X1298228D01*
G01X1296457D02*
X1302756D01*
G01X1296821Y31239D02*
X1296722D01*
G01X1296452D02*
X1296378D01*
G01X1300027Y31613D02*
X1300013D01*
G01X1300167D02*
X1300145D01*
G01X1300391D02*
X1300369D01*
G01X1300559D02*
X1300500D01*
G01X1300728D02*
X1300714D01*
G01X1300625D02*
X1300610D01*
G01X1300679D02*
X1300659D01*
G01X1300837D02*
X1300748D01*
G01X1300871D02*
X1300856D01*
G01X1300997D02*
X1300982D01*
G01X1301076D02*
X1301017D01*
G01X1301240D02*
X1301220D01*
G01X1301348D02*
X1301334D01*
G01X1298711D02*
X1298622D01*
G01X1298789D02*
X1298770D01*
G01X1298937D02*
X1298848D01*
G01X1299159D02*
X1299070D01*
G01X1299193D02*
X1299178D01*
G01X1299274D02*
X1299252D01*
G01X1299427D02*
X1299412D01*
G01X1299343D02*
X1299328D01*
G01X1299501D02*
X1299486D01*
G01X1299707D02*
X1299693D01*
G01X1299978D02*
X1299889D01*
G01X1299033D02*
X1299050D01*
G01X1298957D02*
X1298972D01*
G01X1299767D02*
X1299776D01*
G01X1300261D02*
X1300273D01*
G01X1299779Y31626D02*
X1299764D01*
G01X1299909D02*
X1299978D01*
G01X1300259D02*
X1300276D01*
G01X1300768D02*
X1300837D01*
G01X1301223D02*
X1301238D01*
G01X1300561Y31628D02*
X1300515D01*
G01X1301078D02*
X1301031D01*
G01X1298637D02*
X1298711D01*
G01X1298863D02*
X1298937D01*
G01X1299085D02*
X1299159D01*
G01X1299252D02*
X1299274D01*
G01X1300145D02*
X1300167D01*
G01X1300369D02*
X1300391D01*
G01X1299744Y31641D02*
X1299732D01*
G01X1301186D02*
X1301198D01*
G01X1300411Y31643D02*
X1300426D01*
G01X1300480Y31656D02*
X1300446D01*
G01X1299870D02*
X1299835D01*
G01X1299764D02*
X1299776D01*
G01X1300187Y31663D02*
X1300165D01*
G01X1299294D02*
X1299272D01*
G01X1300915Y31666D02*
X1300871D01*
G01X1298972D02*
X1299013D01*
G01X1300515D02*
X1300561D01*
G01X1301031D02*
X1301078D01*
G01X1301235Y31668D02*
X1301226D01*
G01X1298701D02*
X1298637D01*
G01X1298927D02*
X1298863D01*
G01X1299412D02*
X1299343D01*
G01X1299761D02*
X1299779D01*
G01X1299835D02*
X1299870D01*
G01X1300446D02*
X1300480D01*
G01X1300276Y31676D02*
X1300259D01*
G01X1299272Y31679D02*
X1299309D01*
G01X1300165D02*
X1300202D01*
G01X1301226D02*
X1301235D01*
G01X1298972Y31681D02*
X1299019D01*
G01X1300515D02*
X1300561D01*
G01X1300871D02*
X1300918D01*
G01X1301031D02*
X1301078D01*
G01X1298637Y31683D02*
X1298701D01*
G01X1298863D02*
X1298927D01*
G01X1299343D02*
X1299412D01*
G01X1300273Y31688D02*
X1300261D01*
G01X1300202Y31701D02*
X1300187D01*
G01X1300426D02*
X1300411D01*
G01X1299309D02*
X1299294D01*
G01X1300763Y31703D02*
X1300751D01*
G01X1301201D02*
X1301189D01*
G01X1299904D02*
X1299892D01*
G01X1300293D02*
X1300305D01*
G01X1300167Y31716D02*
X1300145D01*
G01X1300391D02*
X1300369D01*
G01X1300561D02*
X1300515D01*
G01X1301078D02*
X1301031D01*
G01X1298711D02*
X1298637D01*
G01X1298937D02*
X1298863D01*
G01X1299274D02*
X1299252D01*
G01X1300797Y31719D02*
X1300787D01*
G01X1300918D02*
X1300871D01*
G01X1301235D02*
X1301226D01*
G01X1301334D02*
X1301294D01*
G01X1301388D02*
X1301348D01*
G01X1299019D02*
X1298972D01*
G01X1299486D02*
X1299446D01*
G01X1299540D02*
X1299501D01*
G01X1299779D02*
X1299761D01*
G01X1299939D02*
X1299929D01*
G01X1300259D02*
X1300273D01*
G01X1300271Y31731D02*
X1300261D01*
G01X1299016D02*
X1298957D01*
G01X1299776D02*
X1299764D01*
G01X1298622D02*
X1298711D01*
G01X1298814D02*
X1298829D01*
G01X1298730D02*
X1298745D01*
G01X1298848D02*
X1298937D01*
G01X1299070D02*
X1299085D01*
G01X1299178D02*
X1299193D01*
G01X1299252D02*
X1299274D01*
G01X1299412D02*
X1299427D01*
G01X1299328D02*
X1299343D01*
G01X1299446D02*
X1299540D01*
G01X1299693D02*
X1299707D01*
G01X1299931D02*
X1299941D01*
G01X1300013D02*
X1300027D01*
G01X1300145D02*
X1300167D01*
G01X1300369D02*
X1300391D01*
G01X1300500D02*
X1300559D01*
G01X1300706D02*
X1300728D01*
G01X1300610D02*
X1300633D01*
G01X1300790D02*
X1300800D01*
G01X1300856D02*
X1300915D01*
G01X1300982D02*
X1300997D01*
G01X1301017D02*
X1301076D01*
G01X1301228D02*
X1301233D01*
G01X1301294D02*
X1301388D01*
G01X1296722Y31830D02*
X1296821D01*
G01X1296378D02*
X1296452D01*
G01X1302756Y33070D02*
X1296457D01*
G01X1298228D02*
X1295079D01*
G01X1300984D02*
X1304134D01*
G01X1291671Y33593D02*
X1290411D01*
G01X1289411Y34908D02*
X1290278D01*
G01X1291671Y35593D02*
X1289671D01*
G01X1290411Y35908D02*
X1289411D01*
G01X1290411Y36908D02*
X1289411D01*
G01Y18242D02*
X1289742Y18235D01*
X1289994Y18195D01*
X1290168Y18080D01*
X1290253Y17871D01*
X1290276Y17593D01*
X1290278Y17242D01*
G01X1301233Y31731D02*
X1301250Y31729D01*
G01X1299941Y31731D02*
X1299956Y31729D01*
G01X1300800Y31731D02*
X1300815Y31729D01*
G01X1301250Y31666D02*
X1301235Y31668D01*
G01X1289331Y18242D02*
X1289377Y18233D01*
X1289403Y18206D01*
X1289411Y18161D01*
G01X1299252Y31613D02*
X1299240Y31616D01*
G01X1299028Y31729D02*
X1299016Y31731D01*
G01X1299754Y31616D02*
X1299767Y31613D01*
G01X1299274Y31731D02*
X1299287Y31729D01*
G01X1299752Y31658D02*
X1299764Y31656D01*
G01X1300145Y31613D02*
X1300133Y31616D01*
G01X1300249D02*
X1300261Y31613D01*
G01X1299789Y31729D02*
X1299776Y31731D01*
G01X1300369Y31613D02*
X1300357Y31616D01*
G01X1299951Y31716D02*
X1299939Y31719D01*
G01X1300285Y31686D02*
X1300273Y31688D01*
G01X1300167Y31731D02*
X1300180Y31729D01*
G01X1300283D02*
X1300271Y31731D01*
G01X1300391D02*
X1300404Y31729D01*
G01X1300559Y31731D02*
X1300571Y31729D01*
G01X1301211Y31628D02*
X1301223Y31626D01*
G01X1300810Y31716D02*
X1300797Y31719D01*
G01X1300915Y31731D02*
X1300928Y31729D01*
G01X1301076Y31731D02*
X1301088Y31729D01*
G01X1301248Y31716D02*
X1301235Y31719D01*
G01X1300359Y31630D02*
X1300369Y31628D01*
G01X1300177Y31714D02*
X1300167Y31716D01*
G01X1301220Y31613D02*
X1301211Y31616D01*
G01X1299242Y31630D02*
X1299252Y31628D01*
G01X1299284Y31714D02*
X1299274Y31716D01*
G01X1300135Y31630D02*
X1300145Y31628D01*
G01X1300401Y31714D02*
X1300391Y31716D01*
G01X1278159Y38588D02*
X1278292Y38552D01*
X1278411Y38447D01*
X1278494Y38288D01*
X1278526Y38088D01*
G01X1299026Y31716D02*
X1299019Y31719D01*
G01X1299764Y31626D02*
X1299757Y31628D01*
G01X1299754Y31671D02*
X1299761Y31668D01*
G01X1299786Y31716D02*
X1299779Y31719D01*
G01X1300251Y31628D02*
X1300259Y31626D01*
G01X1300283Y31673D02*
X1300276Y31676D01*
G01X1300273Y31719D02*
X1300281Y31716D01*
G01X1300561Y31666D02*
X1300569Y31663D01*
G01Y31714D02*
X1300561Y31716D01*
G01X1300925D02*
X1300918Y31719D01*
G01X1301078Y31666D02*
X1301085Y31663D01*
G01Y31714D02*
X1301078Y31716D01*
G01X1301255Y31673D02*
X1301267Y31668D01*
G01X1299240Y31616D02*
X1299230Y31621D01*
G01X1299287Y31729D02*
X1299296Y31724D01*
G01X1300133Y31616D02*
X1300123Y31621D01*
G01X1299956Y31729D02*
X1299966Y31724D01*
G01X1300357Y31616D02*
X1300347Y31621D01*
G01X1300180Y31729D02*
X1300190Y31724D01*
G01X1300404Y31729D02*
X1300413Y31724D01*
G01X1300576Y31673D02*
X1300581Y31671D01*
G01X1300815Y31729D02*
X1300824Y31724D01*
G01X1301093Y31673D02*
X1301098Y31671D01*
G01X1301211Y31616D02*
X1301201Y31621D01*
G01X1301206Y31630D02*
X1301211Y31628D01*
G01X1301250Y31729D02*
X1301260Y31724D01*
G01X1291789Y19836D02*
X1290411Y20632D01*
G01X1299742Y31623D02*
X1299754Y31616D01*
G01X1299739Y31666D02*
X1299752Y31658D01*
G01X1299801Y31721D02*
X1299789Y31729D01*
G01X1300236Y31623D02*
X1300249Y31616D01*
G01X1300298Y31679D02*
X1300285Y31686D01*
G01X1300295Y31721D02*
X1300283Y31729D01*
G01X1299235Y31636D02*
X1299242Y31630D01*
G01X1299291Y31708D02*
X1299284Y31714D01*
G01X1299757Y31628D02*
X1299749Y31633D01*
G01X1299747Y31676D02*
X1299754Y31671D01*
G01X1299793Y31711D02*
X1299786Y31716D01*
G01X1300054Y31638D02*
X1300047Y31643D01*
G01X1299958Y31711D02*
X1299951Y31716D01*
G01X1300128Y31636D02*
X1300135Y31630D01*
G01X1300079Y31706D02*
X1300086Y31701D01*
G01X1300244Y31633D02*
X1300251Y31628D01*
G01X1300185Y31708D02*
X1300177Y31714D01*
G01X1300291Y31668D02*
X1300283Y31673D01*
G01X1300352Y31636D02*
X1300359Y31630D01*
G01X1300281Y31716D02*
X1300288Y31711D01*
G01X1300409Y31708D02*
X1300401Y31714D01*
G01X1300817Y31711D02*
X1300810Y31716D01*
G01X1301135Y31638D02*
X1301127Y31643D01*
G01X1301201Y31621D02*
X1301194Y31626D01*
G01X1301159Y31706D02*
X1301167Y31701D01*
G01X1301257Y31661D02*
X1301250Y31666D01*
G01X1301255Y31711D02*
X1301248Y31716D01*
G01X1299038Y31721D02*
X1299028Y31729D01*
G01X1300571D02*
X1300581Y31721D01*
G01X1300928Y31729D02*
X1300938Y31721D01*
G01X1301088Y31729D02*
X1301098Y31721D01*
G01X1300569Y31663D02*
X1300574Y31658D01*
G01Y31708D02*
X1300569Y31714D01*
G01X1301085Y31663D02*
X1301090Y31658D01*
G01Y31708D02*
X1301085Y31714D01*
G01X1299031Y31711D02*
X1299026Y31716D01*
G01X1299230Y31621D02*
X1299220Y31630D01*
G01X1299296Y31724D02*
X1299306Y31714D01*
G01X1299966Y31724D02*
X1299976Y31714D01*
G01X1300123Y31621D02*
X1300113Y31630D01*
G01X1300190Y31724D02*
X1300200Y31714D01*
G01X1300295Y31663D02*
X1300291Y31668D01*
G01X1300347Y31621D02*
X1300337Y31630D01*
G01X1300305Y31671D02*
X1300298Y31679D01*
G01X1300413Y31724D02*
X1300423Y31714D01*
G01X1300824Y31724D02*
X1300834Y31714D01*
G01X1300930Y31711D02*
X1300925Y31716D01*
G01X1301201Y31636D02*
X1301206Y31630D01*
G01X1301260Y31724D02*
X1301270Y31714D01*
G01X1299045Y31711D02*
X1299038Y31721D01*
G01X1299734Y31633D02*
X1299742Y31623D01*
G01X1299732Y31676D02*
X1299739Y31666D01*
G01X1299808Y31711D02*
X1299801Y31721D01*
G01X1300229Y31633D02*
X1300236Y31623D01*
G01X1300303Y31711D02*
X1300295Y31721D01*
G01X1300581Y31671D02*
X1300588Y31661D01*
G01X1300581Y31721D02*
X1300588Y31711D01*
G01X1300938Y31721D02*
X1300945Y31711D01*
G01X1301098Y31671D02*
X1301105Y31661D01*
G01X1301098Y31721D02*
X1301105Y31711D01*
G01X1299230Y31643D02*
X1299235Y31636D01*
G01X1299749Y31633D02*
X1299744Y31641D01*
G01X1299742Y31683D02*
X1299747Y31676D01*
G01X1299798Y31703D02*
X1299793Y31711D01*
G01X1299963Y31703D02*
X1299958Y31711D01*
G01X1300123Y31643D02*
X1300128Y31636D01*
G01X1300239Y31641D02*
X1300244Y31633D01*
G01X1300288Y31711D02*
X1300293Y31703D01*
G01X1300347Y31643D02*
X1300352Y31636D01*
G01X1300822Y31703D02*
X1300817Y31711D01*
G01X1301194Y31626D02*
X1301189Y31633D01*
G01X1301260Y31703D02*
X1301255Y31711D01*
G01X1301267Y31668D02*
X1301272Y31661D01*
G01X1296722Y31239D02*
X1296538Y31528D01*
G01X1296600Y31591D02*
X1296821Y31239D01*
G01X1299220Y31630D02*
X1299215Y31641D01*
G01X1300113Y31630D02*
X1300108Y31641D01*
G01X1300337Y31630D02*
X1300332Y31641D01*
G01X1301198D02*
X1301201Y31636D01*
G01X1301263Y31651D02*
X1301257Y31661D01*
G01X1299727Y31688D02*
X1299732Y31676D01*
G01X1299813Y31699D02*
X1299808Y31711D01*
G01X1300224Y31646D02*
X1300229Y31633D01*
G01X1300310Y31658D02*
X1300305Y31671D01*
G01X1299050Y31613D02*
X1299028Y31671D01*
G01X1299013Y31666D02*
X1299033Y31613D01*
G01X1300659D02*
X1300625Y31706D01*
G01X1300633Y31731D02*
X1300669Y31626D01*
G01X1298745Y31731D02*
X1298780Y31628D01*
G01X1298770Y31613D02*
X1298730Y31731D01*
G01X1299033Y31703D02*
X1299031Y31711D01*
G01X1299048Y31703D02*
X1299045Y31711D01*
G01X1299294Y31701D02*
X1299291Y31708D01*
G01X1299732Y31641D02*
X1299734Y31633D01*
G01X1299739Y31691D02*
X1299742Y31683D01*
G01X1299801Y31696D02*
X1299798Y31703D01*
G01X1300187Y31701D02*
X1300185Y31708D01*
G01X1300236Y31648D02*
X1300239Y31641D01*
G01X1300298Y31656D02*
X1300295Y31663D01*
G01X1300305Y31703D02*
X1300303Y31711D01*
G01X1300411Y31701D02*
X1300409Y31708D01*
G01X1300574Y31658D02*
X1300576Y31651D01*
G01X1300588Y31661D02*
X1300591Y31653D01*
G01X1300576Y31701D02*
X1300574Y31708D01*
G01X1300588Y31711D02*
X1300591Y31703D01*
G01X1300933D02*
X1300930Y31711D01*
G01X1300945D02*
X1300948Y31703D01*
G01X1301090Y31658D02*
X1301093Y31651D01*
G01X1301105Y31661D02*
X1301107Y31653D01*
G01X1301093Y31701D02*
X1301090Y31708D01*
G01X1301105Y31711D02*
X1301107Y31703D01*
G01X1301189Y31633D02*
X1301186Y31641D01*
G01X1299228Y31653D02*
X1299230Y31643D01*
G01X1299976Y31714D02*
X1299978Y31703D01*
G01X1300121Y31653D02*
X1300123Y31643D01*
G01X1300344Y31653D02*
X1300347Y31643D01*
G01X1300834Y31714D02*
X1300837Y31703D01*
G01X1301272Y31661D02*
X1301275Y31651D01*
G01X1301270Y31714D02*
X1301272Y31703D01*
G01X1299215Y31641D02*
X1299213Y31653D01*
G01X1299306Y31714D02*
X1299309Y31701D01*
G01X1300108Y31641D02*
X1300106Y31653D01*
G01X1300200Y31714D02*
X1300202Y31701D01*
G01X1300332Y31641D02*
X1300330Y31653D01*
G01X1300423Y31714D02*
X1300426Y31701D01*
G01X1290240Y35593D02*
X1290269Y35403D01*
X1290277Y35171D01*
X1290278Y34908D01*
G01X1289321Y26116D02*
X1289278Y35645D01*
G01X1289320Y26116D02*
X1289324Y23491D01*
X1289329Y20866D01*
X1289331Y18242D01*
G01X1278494Y44408D02*
Y36767D01*
G01X1278526Y43930D02*
Y38088D01*
G01X1279695Y24561D02*
Y18393D01*
G01X1280395Y24561D02*
Y18393D01*
G01X1283687Y35141D02*
Y14955D01*
G01X1283900Y25116D02*
Y19242D01*
G01X1299019Y31681D02*
X1299026Y31683D01*
G01X1299761Y31719D02*
X1299754Y31716D01*
G01X1299779Y31668D02*
X1299786Y31671D01*
G01Y31628D02*
X1299779Y31626D01*
G01X1300251Y31716D02*
X1300259Y31719D01*
G01Y31676D02*
X1300251Y31673D01*
G01X1300276Y31626D02*
X1300283Y31628D01*
G01X1300561Y31681D02*
X1300569Y31683D01*
G01Y31630D02*
X1300561Y31628D01*
G01X1300918Y31681D02*
X1300925Y31683D01*
G01X1301078Y31681D02*
X1301085Y31683D01*
G01Y31630D02*
X1301078Y31628D01*
G01X1301235Y31679D02*
X1301250Y31683D01*
G01X1299816Y31681D02*
X1299813Y31699D01*
G01X1300222Y31663D02*
X1300224Y31646D01*
G01X1290144Y18242D02*
Y26116D01*
G01X1290278Y34908D02*
Y27116D01*
G01X1291789Y19836D02*
Y12946D01*
G01X1295079Y33070D02*
Y29920D01*
G01X1296378Y31239D02*
Y31830D01*
G01X1296452Y31440D02*
Y31239D01*
G01Y31830D02*
Y31541D01*
G01X1296457Y33070D02*
Y29920D01*
G01X1297244D02*
Y33070D01*
G01X1297408D02*
Y29920D01*
G01X1298228D02*
Y33070D01*
G01X1298622Y31613D02*
Y31731D01*
G01X1298637Y31668D02*
Y31628D01*
G01Y31716D02*
Y31683D01*
G01X1298701D02*
Y31668D01*
G01X1298711Y31731D02*
Y31716D01*
G01Y31628D02*
Y31613D01*
G01X1298848D02*
Y31731D01*
G01X1298863Y31668D02*
Y31628D01*
G01Y31716D02*
Y31683D01*
G01X1298927D02*
Y31668D01*
G01X1298937Y31731D02*
Y31716D01*
G01Y31628D02*
Y31613D01*
G01X1298957Y31731D02*
Y31613D01*
G01X1298972Y31719D02*
Y31681D01*
G01Y31613D02*
Y31666D01*
G01X1299033Y31696D02*
Y31703D01*
G01X1299048Y31693D02*
Y31703D01*
G01X1299070Y31613D02*
Y31731D01*
G01X1299085D02*
Y31628D01*
G01X1299159D02*
Y31613D01*
G01X1299178D02*
Y31731D01*
G01X1299193D02*
Y31613D01*
G01X1299213Y31653D02*
Y31691D01*
G01X1299228D02*
Y31653D01*
G01X1299272Y31663D02*
Y31679D01*
G01X1299294Y31643D02*
Y31663D01*
G01X1299309Y31679D02*
Y31641D01*
G01X1299328Y31613D02*
Y31731D01*
G01X1299343Y31668D02*
Y31613D01*
G01Y31731D02*
Y31683D01*
G01X1299412Y31613D02*
Y31668D01*
G01Y31683D02*
Y31731D01*
G01X1299427D02*
Y31613D01*
G01X1299446Y31719D02*
Y31731D01*
G01X1299486Y31613D02*
Y31719D01*
G01X1299501D02*
Y31613D01*
G01X1299540Y31731D02*
Y31719D01*
G01X1299678Y31693D02*
Y31714D01*
G01X1299693Y31613D02*
Y31711D01*
G01X1299707Y31731D02*
Y31613D01*
G01X1299727Y31699D02*
Y31688D01*
G01X1299739Y31696D02*
Y31691D01*
G01X1299801D02*
Y31696D01*
G01X1299803Y31668D02*
Y31663D01*
G01X1299816D02*
Y31681D01*
G01X1299835Y31656D02*
Y31668D01*
G01X1299870D02*
Y31656D01*
G01X1299889Y31613D02*
Y31626D01*
G01X1299963Y31699D02*
Y31703D01*
G01X1299978Y31626D02*
Y31613D01*
G01Y31703D02*
Y31699D01*
G01X1299998Y31693D02*
Y31714D01*
G01X1300013Y31613D02*
Y31711D01*
G01X1300027Y31731D02*
Y31613D01*
G01X1300106Y31653D02*
Y31691D01*
G01X1300121D02*
Y31653D01*
G01X1300165Y31663D02*
Y31679D01*
G01X1300187Y31643D02*
Y31663D01*
G01X1300202Y31679D02*
Y31641D01*
G01X1300222Y31681D02*
Y31663D01*
G01X1300234Y31676D02*
Y31681D01*
G01X1300236Y31656D02*
Y31648D01*
G01X1300298D02*
Y31656D01*
G01X1300310Y31646D02*
Y31658D01*
G01X1300330Y31653D02*
Y31691D01*
G01X1300344D02*
Y31653D01*
G01X1300446Y31656D02*
Y31668D01*
G01X1300480D02*
Y31656D01*
G01X1300500Y31613D02*
Y31731D01*
G01X1300515Y31716D02*
Y31681D01*
G01Y31628D02*
Y31666D01*
G01X1300576Y31651D02*
Y31643D01*
G01Y31696D02*
Y31701D01*
G01X1300591Y31703D02*
Y31693D01*
G01Y31653D02*
Y31641D01*
G01X1300610Y31613D02*
Y31731D01*
G01X1300625Y31706D02*
Y31613D01*
G01X1300714D02*
Y31706D01*
G01X1300728Y31731D02*
Y31613D01*
G01X1300748D02*
Y31626D01*
G01X1300822Y31699D02*
Y31703D01*
G01X1300837Y31626D02*
Y31613D01*
G01Y31703D02*
Y31699D01*
G01X1300856Y31613D02*
Y31731D01*
G01X1300871Y31666D02*
Y31613D01*
G01Y31719D02*
Y31681D01*
G01X1300933Y31696D02*
Y31703D01*
G01X1300948D02*
Y31693D01*
G01X1300967D02*
Y31714D01*
G01X1300982Y31613D02*
Y31711D01*
G01X1300984Y29920D02*
Y33070D01*
G01X1300997Y31731D02*
Y31613D01*
G01X1301017D02*
Y31731D01*
G01X1301031Y31716D02*
Y31681D01*
G01Y31628D02*
Y31666D01*
G01X1301093Y31651D02*
Y31643D01*
G01Y31696D02*
Y31701D01*
G01X1301107Y31703D02*
Y31693D01*
G01Y31653D02*
Y31641D01*
G01X1301226Y31668D02*
Y31679D01*
G01X1301260Y31699D02*
Y31703D01*
G01X1301263Y31641D02*
Y31651D01*
G01X1301272Y31703D02*
Y31699D01*
G01X1301275Y31651D02*
Y31641D01*
G01X1301294Y31719D02*
Y31731D01*
G01X1301334Y31613D02*
Y31719D01*
G01X1301348D02*
Y31613D01*
G01X1301388Y31731D02*
Y31719D01*
G01X1301805Y29920D02*
Y33070D01*
G01X1301969Y29920D02*
Y33070D01*
G01X1289278Y18242D02*
X1289320Y26116D01*
G01X1290278Y27116D02*
X1290276Y26754D01*
X1290250Y26472D01*
X1290159Y26266D01*
X1289981Y26158D01*
X1289730Y26121D01*
X1289411Y26116D01*
G01X1299028Y31671D02*
X1299038Y31676D01*
G01X1299230Y31724D02*
X1299240Y31729D01*
G01X1299296Y31621D02*
X1299287Y31616D01*
G01X1299904Y31724D02*
X1299914Y31729D01*
G01X1300123Y31724D02*
X1300133Y31729D01*
G01X1300347Y31724D02*
X1300357Y31729D01*
G01X1300190Y31621D02*
X1300180Y31616D01*
G01X1300413Y31621D02*
X1300404Y31616D01*
G01X1300581Y31676D02*
X1300576Y31673D01*
G01X1300763Y31724D02*
X1300773Y31729D01*
G01X1301098Y31676D02*
X1301093Y31673D01*
G01X1301201Y31724D02*
X1301211Y31729D01*
G01X1301250Y31628D02*
X1301255Y31630D01*
G01X1301260Y31621D02*
X1301250Y31616D01*
G01X1299813Y31646D02*
X1299816Y31663D01*
G01X1300224Y31699D02*
X1300222Y31681D01*
G01X1299803Y31663D02*
X1299801Y31648D01*
G01X1300234Y31681D02*
X1300236Y31696D01*
G01X1299213Y31691D02*
X1299215Y31703D01*
G01X1300106Y31691D02*
X1300108Y31703D01*
G01X1300330Y31691D02*
X1300332Y31703D01*
G01X1300426Y31643D02*
X1300423Y31630D01*
G01X1299230Y31701D02*
X1299228Y31691D01*
G01X1299309Y31641D02*
X1299306Y31630D01*
G01X1299892Y31703D02*
X1299894Y31714D01*
G01X1299978Y31699D02*
X1299976Y31688D01*
G01X1300123Y31701D02*
X1300121Y31691D01*
G01X1300202Y31641D02*
X1300200Y31630D01*
G01X1300347Y31701D02*
X1300344Y31691D01*
G01X1300751Y31703D02*
X1300753Y31714D01*
G01X1300837Y31699D02*
X1300834Y31688D01*
G01X1301189Y31703D02*
X1301191Y31714D01*
G01X1301272Y31699D02*
X1301270Y31688D01*
G01X1299031D02*
X1299033Y31696D01*
G01X1299045Y31686D02*
X1299048Y31693D01*
G01X1299291Y31636D02*
X1299294Y31643D01*
G01X1299742Y31703D02*
X1299739Y31696D01*
G01X1299798Y31683D02*
X1299801Y31691D01*
G01Y31648D02*
X1299798Y31641D01*
G01X1300185Y31636D02*
X1300187Y31643D01*
G01X1300236Y31696D02*
X1300239Y31703D01*
G01Y31663D02*
X1300236Y31656D01*
G01X1300295Y31641D02*
X1300298Y31648D01*
G01X1300409Y31636D02*
X1300411Y31643D01*
G01X1300574Y31688D02*
X1300576Y31696D01*
G01X1300591Y31693D02*
X1300588Y31686D01*
G01X1300576Y31643D02*
X1300574Y31636D01*
G01X1300591Y31641D02*
X1300588Y31633D01*
G01X1300930Y31688D02*
X1300933Y31696D01*
G01X1300948Y31693D02*
X1300945Y31686D01*
G01X1301090Y31688D02*
X1301093Y31696D01*
G01X1301107Y31693D02*
X1301105Y31686D01*
G01X1301093Y31643D02*
X1301090Y31636D01*
G01X1301107Y31641D02*
X1301105Y31633D01*
G01X1301275Y31641D02*
X1301272Y31633D01*
G01X1298829Y31731D02*
X1298789Y31613D01*
G01X1298780Y31628D02*
X1298814Y31731D01*
G01X1300669Y31626D02*
X1300706Y31731D01*
G01X1300714Y31706D02*
X1300679Y31613D01*
G01X1299732Y31711D02*
X1299727Y31699D01*
G01X1299808Y31633D02*
X1299813Y31646D01*
G01X1300229Y31711D02*
X1300224Y31699D01*
G01X1300305Y31633D02*
X1300310Y31646D01*
G01X1296538Y31528D02*
X1296452Y31440D01*
G01X1299026Y31683D02*
X1299031Y31688D01*
G01X1299220Y31714D02*
X1299230Y31724D01*
G01X1299306Y31630D02*
X1299296Y31621D01*
G01X1299894Y31714D02*
X1299904Y31724D01*
G01X1300113Y31714D02*
X1300123Y31724D01*
G01X1299889Y31626D02*
X1299958Y31688D01*
G01X1300748Y31626D02*
X1300817Y31688D01*
G01X1299970Y31681D02*
X1299909Y31626D01*
G01X1300830Y31681D02*
X1300768Y31626D01*
G01X1300581Y31623D02*
X1300571Y31616D01*
G01X1300938Y31676D02*
X1300928Y31668D01*
G01X1301098Y31623D02*
X1301088Y31616D01*
G01X1301265Y31681D02*
X1301255Y31673D01*
G01X1299242Y31714D02*
X1299235Y31708D01*
G01X1299284Y31630D02*
X1299291Y31636D01*
G01X1299754Y31716D02*
X1299747Y31711D01*
G01X1299786Y31671D02*
X1299793Y31676D01*
G01X1299789Y31658D02*
X1299803Y31668D01*
G01X1299793Y31633D02*
X1299786Y31628D01*
G01X1299917Y31716D02*
X1299909Y31711D01*
G01X1300135Y31714D02*
X1300128Y31708D01*
G01X1300244Y31711D02*
X1300251Y31716D01*
G01X1300249Y31686D02*
X1300234Y31676D01*
G01X1300177Y31630D02*
X1300185Y31636D01*
G01X1300251Y31673D02*
X1300244Y31668D01*
G01X1300359Y31714D02*
X1300352Y31708D01*
G01X1300283Y31628D02*
X1300291Y31633D01*
G01X1300401Y31630D02*
X1300409Y31636D01*
G01X1300775Y31716D02*
X1300768Y31711D01*
G01X1301213Y31716D02*
X1301206Y31711D01*
G01X1301267Y31626D02*
X1301260Y31621D01*
G01X1299752Y31729D02*
X1299739Y31721D01*
G01X1299789Y31616D02*
X1299801Y31623D01*
G01X1300249Y31729D02*
X1300236Y31721D01*
G01X1300285Y31616D02*
X1300298Y31623D01*
G01X1291789Y12946D02*
X1290411Y12151D01*
G01X1299215Y31703D02*
X1299220Y31714D01*
G01X1299958Y31688D02*
X1299963Y31699D01*
G01X1300108Y31703D02*
X1300113Y31714D01*
G01X1300332Y31703D02*
X1300337Y31714D01*
G01X1300817Y31688D02*
X1300822Y31699D01*
G01X1301255Y31688D02*
X1301260Y31699D01*
G01Y31636D02*
X1301263Y31641D01*
G01X1300047Y31643D02*
X1300079Y31706D01*
G01X1300086Y31701D02*
X1300054Y31638D01*
G01X1301127Y31643D02*
X1301159Y31706D01*
G01X1301167Y31701D02*
X1301135Y31638D01*
G01X1299235Y31708D02*
X1299230Y31701D01*
G01X1299747Y31711D02*
X1299742Y31703D01*
G01X1299793Y31676D02*
X1299798Y31683D01*
G01Y31641D02*
X1299793Y31633D01*
G01X1299909Y31711D02*
X1299904Y31703D01*
G01X1299976Y31688D02*
X1299970Y31681D01*
G01X1300128Y31708D02*
X1300123Y31701D01*
G01X1300239Y31703D02*
X1300244Y31711D01*
G01X1300291Y31633D02*
X1300295Y31641D01*
G01X1300352Y31708D02*
X1300347Y31701D01*
G01X1300768Y31711D02*
X1300763Y31703D01*
G01X1300834Y31688D02*
X1300830Y31681D01*
G01X1301206Y31711D02*
X1301201Y31703D01*
G01X1301270Y31688D02*
X1301265Y31681D01*
G01X1301272Y31633D02*
X1301267Y31626D01*
G01X1299038Y31676D02*
X1299045Y31686D01*
G01X1299739Y31721D02*
X1299732Y31711D01*
G01X1299801Y31623D02*
X1299808Y31633D01*
G01X1300236Y31721D02*
X1300229Y31711D01*
G01X1300298Y31623D02*
X1300305Y31633D01*
G01X1300588Y31686D02*
X1300581Y31676D01*
G01X1300588Y31633D02*
X1300581Y31623D01*
G01X1300945Y31686D02*
X1300938Y31676D01*
G01X1301105Y31686D02*
X1301098Y31676D01*
G01X1301105Y31633D02*
X1301098Y31623D01*
G01X1299678Y31714D02*
X1299693Y31731D01*
G01Y31711D02*
X1299678Y31693D01*
G01X1299998Y31714D02*
X1300013Y31731D01*
G01Y31711D02*
X1299998Y31693D01*
G01X1300967Y31714D02*
X1300982Y31731D01*
G01Y31711D02*
X1300967Y31693D01*
G01X1296821Y31830D02*
X1296600Y31591D01*
G01X1296452Y31541D02*
X1296722Y31830D01*
G01X1300200Y31630D02*
X1300190Y31621D01*
G01X1300244Y31668D02*
X1300239Y31663D01*
G01X1300337Y31714D02*
X1300347Y31724D01*
G01X1300423Y31630D02*
X1300413Y31621D01*
G01X1300569Y31683D02*
X1300574Y31688D01*
G01Y31636D02*
X1300569Y31630D01*
G01X1300753Y31714D02*
X1300763Y31724D01*
G01X1300925Y31683D02*
X1300930Y31688D01*
G01X1301085Y31683D02*
X1301090Y31688D01*
G01Y31636D02*
X1301085Y31630D01*
G01X1301191Y31714D02*
X1301201Y31724D01*
G01X1301250Y31683D02*
X1301255Y31688D01*
G01Y31630D02*
X1301260Y31636D01*
G01X1284900Y26116D02*
G03X1283900Y25116I0J-1000D01*
G01Y19242D02*
G03X1284900Y18242I1000J0D01*
G01X1289411Y38570D02*
G03X1289671Y35593I261J-1477D01*
G01X1301250Y7993D02*
X1301240Y7991D01*
G01X1300391Y8006D02*
X1300401Y8008D01*
G01X1300167Y8006D02*
X1300177Y8008D01*
G01X1300369Y8094D02*
X1300359Y8092D01*
G01X1300145Y8094D02*
X1300135Y8092D01*
G01X1299274Y8006D02*
X1299284Y8008D01*
G01X1299252Y8094D02*
X1299242Y8092D01*
G01X1301238Y8004D02*
X1301250Y8006D01*
G01X1301088Y7993D02*
X1301076Y7991D01*
G01X1301226Y8097D02*
X1301213Y8094D01*
G01X1300928Y8046D02*
X1300915Y8044D01*
G01X1300571Y7993D02*
X1300559Y7991D01*
G01X1300404Y7993D02*
X1300391Y7991D01*
G01X1300273D02*
X1300285Y7993D01*
G01X1300787Y8097D02*
X1300775Y8094D01*
G01X1300180Y7993D02*
X1300167Y7991D01*
G01X1300261Y8066D02*
X1300249Y8064D01*
G01X1300357Y8106D02*
X1300369Y8109D01*
G01X1299776Y7991D02*
X1299789Y7993D01*
G01X1300261Y8109D02*
X1300249Y8106D01*
G01X1300133D02*
X1300145Y8109D01*
G01X1299776Y8034D02*
X1299789Y8036D01*
G01X1299929Y8097D02*
X1299917Y8094D01*
G01X1299287Y7993D02*
X1299274Y7991D01*
G01X1299764Y8109D02*
X1299752Y8106D01*
G01X1299240D02*
X1299252Y8109D01*
G01X1301211Y8106D02*
X1301228Y8109D01*
G01X1300773Y8106D02*
X1300790Y8109D01*
G01X1299914Y8106D02*
X1299931Y8109D01*
G01X1289411Y6877D02*
X1290411D01*
G01Y7468D02*
X1289411D01*
G01X1296821Y7617D02*
X1296722D01*
G01X1296452D02*
X1296378D01*
G01X1300027Y7991D02*
X1300013D01*
G01X1300167D02*
X1300145D01*
G01X1300391D02*
X1300369D01*
G01X1300559D02*
X1300500D01*
G01X1300728D02*
X1300714D01*
G01X1300625D02*
X1300610D01*
G01X1300679D02*
X1300659D01*
G01X1300837D02*
X1300748D01*
G01X1300871D02*
X1300856D01*
G01X1300997D02*
X1300982D01*
G01X1301076D02*
X1301017D01*
G01X1301240D02*
X1301220D01*
G01X1301348D02*
X1301334D01*
G01X1298711D02*
X1298622D01*
G01X1298789D02*
X1298770D01*
G01X1298937D02*
X1298848D01*
G01X1299159D02*
X1299070D01*
G01X1299193D02*
X1299178D01*
G01X1299274D02*
X1299252D01*
G01X1299427D02*
X1299412D01*
G01X1299343D02*
X1299328D01*
G01X1299501D02*
X1299486D01*
G01X1299707D02*
X1299693D01*
G01X1299978D02*
X1299889D01*
G01X1299033D02*
X1299050D01*
G01X1298957D02*
X1298972D01*
G01X1299767D02*
X1299776D01*
G01X1300261D02*
X1300273D01*
G01X1299779Y8004D02*
X1299764D01*
G01X1299909D02*
X1299978D01*
G01X1300259D02*
X1300276D01*
G01X1300768D02*
X1300837D01*
G01X1301223D02*
X1301238D01*
G01X1300561Y8006D02*
X1300515D01*
G01X1301078D02*
X1301031D01*
G01X1298637D02*
X1298711D01*
G01X1298863D02*
X1298937D01*
G01X1299085D02*
X1299159D01*
G01X1299252D02*
X1299274D01*
G01X1300145D02*
X1300167D01*
G01X1300369D02*
X1300391D01*
G01X1299744Y8019D02*
X1299732D01*
G01X1301186D02*
X1301198D01*
G01X1300411Y8021D02*
X1300426D01*
G01X1300480Y8034D02*
X1300446D01*
G01X1299870D02*
X1299835D01*
G01X1299764D02*
X1299776D01*
G01X1300187Y8041D02*
X1300165D01*
G01X1299294D02*
X1299272D01*
G01X1300915Y8044D02*
X1300871D01*
G01X1298972D02*
X1299013D01*
G01X1300515D02*
X1300561D01*
G01X1301031D02*
X1301078D01*
G01X1301235Y8046D02*
X1301226D01*
G01X1298701D02*
X1298637D01*
G01X1298927D02*
X1298863D01*
G01X1299412D02*
X1299343D01*
G01X1299761D02*
X1299779D01*
G01X1299835D02*
X1299870D01*
G01X1300446D02*
X1300480D01*
G01X1300276Y8054D02*
X1300259D01*
G01X1299272Y8056D02*
X1299309D01*
G01X1300165D02*
X1300202D01*
G01X1301226D02*
X1301235D01*
G01X1298972Y8059D02*
X1299019D01*
G01X1300515D02*
X1300561D01*
G01X1300871D02*
X1300918D01*
G01X1301031D02*
X1301078D01*
G01X1298637Y8061D02*
X1298701D01*
G01X1298863D02*
X1298927D01*
G01X1299343D02*
X1299412D01*
G01X1300273Y8066D02*
X1300261D01*
G01X1300202Y8079D02*
X1300187D01*
G01X1300426D02*
X1300411D01*
G01X1299309D02*
X1299294D01*
G01X1300763Y8081D02*
X1300751D01*
G01X1301201D02*
X1301189D01*
G01X1299904D02*
X1299892D01*
G01X1300293D02*
X1300305D01*
G01X1300167Y8094D02*
X1300145D01*
G01X1300391D02*
X1300369D01*
G01X1300561D02*
X1300515D01*
G01X1301078D02*
X1301031D01*
G01X1298711D02*
X1298637D01*
G01X1298937D02*
X1298863D01*
G01X1299274D02*
X1299252D01*
G01X1300797Y8097D02*
X1300787D01*
G01X1300918D02*
X1300871D01*
G01X1301235D02*
X1301226D01*
G01X1301334D02*
X1301294D01*
G01X1301388D02*
X1301348D01*
G01X1299019D02*
X1298972D01*
G01X1299486D02*
X1299446D01*
G01X1299540D02*
X1299501D01*
G01X1299779D02*
X1299761D01*
G01X1299939D02*
X1299929D01*
G01X1300259D02*
X1300273D01*
G01X1300271Y8109D02*
X1300261D01*
G01X1299016D02*
X1298957D01*
G01X1299776D02*
X1299764D01*
G01X1298622D02*
X1298711D01*
G01X1298814D02*
X1298829D01*
G01X1298730D02*
X1298745D01*
G01X1298848D02*
X1298937D01*
G01X1299070D02*
X1299085D01*
G01X1299178D02*
X1299193D01*
G01X1299252D02*
X1299274D01*
G01X1299412D02*
X1299427D01*
G01X1299328D02*
X1299343D01*
G01X1299446D02*
X1299540D01*
G01X1299693D02*
X1299707D01*
G01X1299931D02*
X1299941D01*
G01X1300013D02*
X1300027D01*
G01X1300145D02*
X1300167D01*
G01X1300369D02*
X1300391D01*
G01X1300500D02*
X1300559D01*
G01X1300706D02*
X1300728D01*
G01X1300610D02*
X1300633D01*
G01X1300790D02*
X1300800D01*
G01X1300856D02*
X1300915D01*
G01X1300982D02*
X1300997D01*
G01X1301017D02*
X1301076D01*
G01X1301228D02*
X1301233D01*
G01X1301294D02*
X1301388D01*
G01X1296722Y8208D02*
X1296821D01*
G01X1296378D02*
X1296452D01*
G01X1302756Y9448D02*
X1296457D01*
G01X1298228D02*
X1295079D01*
G01X1300984D02*
X1304134D01*
G01X1301233Y8109D02*
X1301250Y8106D01*
G01X1299941Y8109D02*
X1299956Y8106D01*
G01X1300800Y8109D02*
X1300815Y8106D01*
G01X1301250Y8044D02*
X1301235Y8046D01*
G01X1299252Y7991D02*
X1299240Y7993D01*
G01X1299028Y8106D02*
X1299016Y8109D01*
G01X1299754Y7993D02*
X1299767Y7991D01*
G01X1299274Y8109D02*
X1299287Y8106D01*
G01X1299752Y8036D02*
X1299764Y8034D01*
G01X1300145Y7991D02*
X1300133Y7993D01*
G01X1300249D02*
X1300261Y7991D01*
G01X1299789Y8106D02*
X1299776Y8109D01*
G01X1300369Y7991D02*
X1300357Y7993D01*
G01X1299951Y8094D02*
X1299939Y8097D01*
G01X1300285Y8064D02*
X1300273Y8066D01*
G01X1300167Y8109D02*
X1300180Y8106D01*
G01X1300283D02*
X1300271Y8109D01*
G01X1300391D02*
X1300404Y8106D01*
G01X1300559Y8109D02*
X1300571Y8106D01*
G01X1301211Y8006D02*
X1301223Y8004D01*
G01X1300810Y8094D02*
X1300797Y8097D01*
G01X1300915Y8109D02*
X1300928Y8106D01*
G01X1301076Y8109D02*
X1301088Y8106D01*
G01X1301248Y8094D02*
X1301235Y8097D01*
G01X1300359Y8008D02*
X1300369Y8006D01*
G01X1300177Y8092D02*
X1300167Y8094D01*
G01X1301220Y7991D02*
X1301211Y7993D01*
G01X1299242Y8008D02*
X1299252Y8006D01*
G01X1299284Y8092D02*
X1299274Y8094D01*
G01X1300135Y8008D02*
X1300145Y8006D01*
G01X1300401Y8092D02*
X1300391Y8094D01*
G01X1299026D02*
X1299019Y8097D01*
G01X1299764Y8004D02*
X1299757Y8006D01*
G01X1299754Y8049D02*
X1299761Y8046D01*
G01X1299786Y8094D02*
X1299779Y8097D01*
G01X1300251Y8006D02*
X1300259Y8004D01*
G01X1300283Y8051D02*
X1300276Y8054D01*
G01X1300273Y8097D02*
X1300281Y8094D01*
G01X1300561Y8044D02*
X1300569Y8041D01*
G01Y8092D02*
X1300561Y8094D01*
G01X1300925D02*
X1300918Y8097D01*
G01X1301078Y8044D02*
X1301085Y8041D01*
G01Y8092D02*
X1301078Y8094D01*
G01X1301255Y8051D02*
X1301267Y8046D01*
G01X1299240Y7993D02*
X1299230Y7999D01*
G01X1299287Y8106D02*
X1299296Y8102D01*
G01X1300133Y7993D02*
X1300123Y7999D01*
G01X1299956Y8106D02*
X1299966Y8102D01*
G01X1300357Y7993D02*
X1300347Y7999D01*
G01X1300180Y8106D02*
X1300190Y8102D01*
G01X1300404Y8106D02*
X1300413Y8102D01*
G01X1300576Y8051D02*
X1300581Y8049D01*
G01X1300815Y8106D02*
X1300824Y8102D01*
G01X1301093Y8051D02*
X1301098Y8049D01*
G01X1301211Y7993D02*
X1301201Y7999D01*
G01X1301206Y8008D02*
X1301211Y8006D01*
G01X1301250Y8106D02*
X1301260Y8102D01*
G01X1299742Y8001D02*
X1299754Y7993D01*
G01X1299739Y8044D02*
X1299752Y8036D01*
G01X1299801Y8099D02*
X1299789Y8106D01*
G01X1300236Y8001D02*
X1300249Y7993D01*
G01X1300298Y8056D02*
X1300285Y8064D01*
G01X1300295Y8099D02*
X1300283Y8106D01*
G01X1299235Y8014D02*
X1299242Y8008D01*
G01X1299291Y8086D02*
X1299284Y8092D01*
G01X1299757Y8006D02*
X1299749Y8011D01*
G01X1299747Y8054D02*
X1299754Y8049D01*
G01X1299793Y8089D02*
X1299786Y8094D01*
G01X1300054Y8016D02*
X1300047Y8021D01*
G01X1299958Y8089D02*
X1299951Y8094D01*
G01X1300128Y8014D02*
X1300135Y8008D01*
G01X1300079Y8084D02*
X1300086Y8079D01*
G01X1300244Y8011D02*
X1300251Y8006D01*
G01X1300185Y8086D02*
X1300177Y8092D01*
G01X1300291Y8046D02*
X1300283Y8051D01*
G01X1300352Y8014D02*
X1300359Y8008D01*
G01X1300281Y8094D02*
X1300288Y8089D01*
G01X1300409Y8086D02*
X1300401Y8092D01*
G01X1300817Y8089D02*
X1300810Y8094D01*
G01X1301135Y8016D02*
X1301127Y8021D01*
G01X1301201Y7999D02*
X1301194Y8004D01*
G01X1301159Y8084D02*
X1301167Y8079D01*
G01X1301257Y8039D02*
X1301250Y8044D01*
G01X1301255Y8089D02*
X1301248Y8094D01*
G01X1299038Y8099D02*
X1299028Y8106D01*
G01X1300571D02*
X1300581Y8099D01*
G01X1300928Y8106D02*
X1300938Y8099D01*
G01X1301088Y8106D02*
X1301098Y8099D01*
G01X1300569Y8041D02*
X1300574Y8036D01*
G01Y8086D02*
X1300569Y8092D01*
G01X1301085Y8041D02*
X1301090Y8036D01*
G01Y8086D02*
X1301085Y8092D01*
G01X1299031Y8089D02*
X1299026Y8094D01*
G01X1299230Y7999D02*
X1299220Y8008D01*
G01X1299296Y8102D02*
X1299306Y8092D01*
G01X1299966Y8102D02*
X1299976Y8092D01*
G01X1300123Y7999D02*
X1300113Y8008D01*
G01X1300190Y8102D02*
X1300200Y8092D01*
G01X1300295Y8041D02*
X1300291Y8046D01*
G01X1300347Y7999D02*
X1300337Y8008D01*
G01X1300305Y8049D02*
X1300298Y8056D01*
G01X1300413Y8102D02*
X1300423Y8092D01*
G01X1300824Y8102D02*
X1300834Y8092D01*
G01X1300930Y8089D02*
X1300925Y8094D01*
G01X1301201Y8014D02*
X1301206Y8008D01*
G01X1301260Y8102D02*
X1301270Y8092D01*
G01X1299045Y8089D02*
X1299038Y8099D01*
G01X1299734Y8011D02*
X1299742Y8001D01*
G01X1299732Y8054D02*
X1299739Y8044D01*
G01X1299808Y8089D02*
X1299801Y8099D01*
G01X1300229Y8011D02*
X1300236Y8001D01*
G01X1300303Y8089D02*
X1300295Y8099D01*
G01X1300581Y8049D02*
X1300588Y8039D01*
G01X1300581Y8099D02*
X1300588Y8089D01*
G01X1300938Y8099D02*
X1300945Y8089D01*
G01X1301098Y8049D02*
X1301105Y8039D01*
G01X1301098Y8099D02*
X1301105Y8089D01*
G01X1299230Y8021D02*
X1299235Y8014D01*
G01X1299749Y8011D02*
X1299744Y8019D01*
G01X1299742Y8061D02*
X1299747Y8054D01*
G01X1299798Y8081D02*
X1299793Y8089D01*
G01X1299963Y8081D02*
X1299958Y8089D01*
G01X1300123Y8021D02*
X1300128Y8014D01*
G01X1300239Y8019D02*
X1300244Y8011D01*
G01X1300288Y8089D02*
X1300293Y8081D01*
G01X1300347Y8021D02*
X1300352Y8014D01*
G01X1300822Y8081D02*
X1300817Y8089D01*
G01X1301194Y8004D02*
X1301189Y8011D01*
G01X1301260Y8081D02*
X1301255Y8089D01*
G01X1301267Y8046D02*
X1301272Y8039D01*
G01X1296722Y7617D02*
X1296538Y7906D01*
G01X1296600Y7969D02*
X1296821Y7617D01*
G01X1299220Y8008D02*
X1299215Y8019D01*
G01X1300113Y8008D02*
X1300108Y8019D01*
G01X1300337Y8008D02*
X1300332Y8019D01*
G01X1301198D02*
X1301201Y8014D01*
G01X1301263Y8029D02*
X1301257Y8039D01*
G01X1299727Y8066D02*
X1299732Y8054D01*
G01X1299813Y8077D02*
X1299808Y8089D01*
G01X1300224Y8024D02*
X1300229Y8011D01*
G01X1300310Y8036D02*
X1300305Y8049D01*
G01X1299050Y7991D02*
X1299028Y8049D01*
G01X1299013Y8044D02*
X1299033Y7991D01*
G01X1300659D02*
X1300625Y8084D01*
G01X1300633Y8109D02*
X1300669Y8004D01*
G01X1298745Y8109D02*
X1298780Y8006D01*
G01X1298770Y7991D02*
X1298730Y8109D01*
G01X1299033Y8081D02*
X1299031Y8089D01*
G01X1299048Y8081D02*
X1299045Y8089D01*
G01X1299294Y8079D02*
X1299291Y8086D01*
G01X1299732Y8019D02*
X1299734Y8011D01*
G01X1299739Y8069D02*
X1299742Y8061D01*
G01X1299801Y8074D02*
X1299798Y8081D01*
G01X1300187Y8079D02*
X1300185Y8086D01*
G01X1300236Y8026D02*
X1300239Y8019D01*
G01X1300298Y8034D02*
X1300295Y8041D01*
G01X1300305Y8081D02*
X1300303Y8089D01*
G01X1300411Y8079D02*
X1300409Y8086D01*
G01X1300574Y8036D02*
X1300576Y8029D01*
G01X1300588Y8039D02*
X1300591Y8031D01*
G01X1300576Y8079D02*
X1300574Y8086D01*
G01X1300588Y8089D02*
X1300591Y8081D01*
G01X1300933D02*
X1300930Y8089D01*
G01X1300945D02*
X1300948Y8081D01*
G01X1301090Y8036D02*
X1301093Y8029D01*
G01X1301105Y8039D02*
X1301107Y8031D01*
G01X1301093Y8079D02*
X1301090Y8086D01*
G01X1301105Y8089D02*
X1301107Y8081D01*
G01X1301189Y8011D02*
X1301186Y8019D01*
G01X1283687Y14955D02*
X1284868Y11019D01*
G01X1283687Y14955D02*
X1284868Y11019D01*
G01X1299228Y8031D02*
X1299230Y8021D01*
G01X1299976Y8092D02*
X1299978Y8081D01*
G01X1300121Y8031D02*
X1300123Y8021D01*
G01X1300344Y8031D02*
X1300347Y8021D01*
G01X1300834Y8092D02*
X1300837Y8081D01*
G01X1301272Y8039D02*
X1301275Y8029D01*
G01X1301270Y8092D02*
X1301272Y8081D01*
G01X1299215Y8019D02*
X1299213Y8031D01*
G01X1299306Y8092D02*
X1299309Y8079D01*
G01X1300108Y8019D02*
X1300106Y8031D01*
G01X1300200Y8092D02*
X1300202Y8079D01*
G01X1300332Y8019D02*
X1300330Y8031D01*
G01X1300423Y8092D02*
X1300426Y8079D01*
G01X1285852Y11019D02*
Y44408D01*
G01X1299816Y8059D02*
X1299813Y8077D01*
G01X1300222Y8041D02*
X1300224Y8024D01*
G01X1290278Y17242D02*
Y7468D01*
G01X1296378Y7617D02*
Y8208D01*
G01X1296452Y7818D02*
Y7617D01*
G01Y8208D02*
Y7919D01*
G01X1298622Y7991D02*
Y8109D01*
G01X1298637Y8046D02*
Y8006D01*
G01Y8094D02*
Y8061D01*
G01X1298701D02*
Y8046D01*
G01X1298711Y8109D02*
Y8094D01*
G01Y8006D02*
Y7991D01*
G01X1298848D02*
Y8109D01*
G01X1298863Y8046D02*
Y8006D01*
G01Y8094D02*
Y8061D01*
G01X1298927D02*
Y8046D01*
G01X1298937Y8109D02*
Y8094D01*
G01Y8006D02*
Y7991D01*
G01X1298957Y8109D02*
Y7991D01*
G01X1298972Y8097D02*
Y8059D01*
G01Y7991D02*
Y8044D01*
G01X1299033Y8074D02*
Y8081D01*
G01X1299048Y8071D02*
Y8081D01*
G01X1299070Y7991D02*
Y8109D01*
G01X1299085D02*
Y8006D01*
G01X1299159D02*
Y7991D01*
G01X1299178D02*
Y8109D01*
G01X1299193D02*
Y7991D01*
G01X1299213Y8031D02*
Y8069D01*
G01X1299228D02*
Y8031D01*
G01X1299272Y8041D02*
Y8056D01*
G01X1299294Y8021D02*
Y8041D01*
G01X1299309Y8056D02*
Y8019D01*
G01X1299328Y7991D02*
Y8109D01*
G01X1299343Y8046D02*
Y7991D01*
G01Y8109D02*
Y8061D01*
G01X1299412Y7991D02*
Y8046D01*
G01Y8061D02*
Y8109D01*
G01X1299427D02*
Y7991D01*
G01X1299446Y8097D02*
Y8109D01*
G01X1299486Y7991D02*
Y8097D01*
G01X1299501D02*
Y7991D01*
G01X1299540Y8109D02*
Y8097D01*
G01X1299678Y8071D02*
Y8092D01*
G01X1299693Y7991D02*
Y8089D01*
G01X1299707Y8109D02*
Y7991D01*
G01X1299727Y8077D02*
Y8066D01*
G01X1299739Y8074D02*
Y8069D01*
G01X1299801D02*
Y8074D01*
G01X1299803Y8046D02*
Y8041D01*
G01X1299816D02*
Y8059D01*
G01X1299835Y8034D02*
Y8046D01*
G01X1299870D02*
Y8034D01*
G01X1299889Y7991D02*
Y8004D01*
G01X1299963Y8077D02*
Y8081D01*
G01X1299978Y8004D02*
Y7991D01*
G01Y8081D02*
Y8077D01*
G01X1299998Y8071D02*
Y8092D01*
G01X1300013Y7991D02*
Y8089D01*
G01X1300027Y8109D02*
Y7991D01*
G01X1300106Y8031D02*
Y8069D01*
G01X1300121D02*
Y8031D01*
G01X1300165Y8041D02*
Y8056D01*
G01X1300187Y8021D02*
Y8041D01*
G01X1300202Y8056D02*
Y8019D01*
G01X1300222Y8059D02*
Y8041D01*
G01X1300234Y8054D02*
Y8059D01*
G01X1300236Y8034D02*
Y8026D01*
G01X1300298D02*
Y8034D01*
G01X1300310Y8024D02*
Y8036D01*
G01X1300330Y8031D02*
Y8069D01*
G01X1300344D02*
Y8031D01*
G01X1300446Y8034D02*
Y8046D01*
G01X1300480D02*
Y8034D01*
G01X1300500Y7991D02*
Y8109D01*
G01X1300515Y8094D02*
Y8059D01*
G01Y8006D02*
Y8044D01*
G01X1300576Y8029D02*
Y8021D01*
G01Y8074D02*
Y8079D01*
G01X1300591Y8081D02*
Y8071D01*
G01Y8031D02*
Y8019D01*
G01X1300610Y7991D02*
Y8109D01*
G01X1300625Y8084D02*
Y7991D01*
G01X1300714D02*
Y8084D01*
G01X1300728Y8109D02*
Y7991D01*
G01X1300748D02*
Y8004D01*
G01X1300822Y8077D02*
Y8081D01*
G01X1300837Y8004D02*
Y7991D01*
G01Y8081D02*
Y8077D01*
G01X1300856Y7991D02*
Y8109D01*
G01X1300871Y8044D02*
Y7991D01*
G01Y8097D02*
Y8059D01*
G01X1300933Y8074D02*
Y8081D01*
G01X1300948D02*
Y8071D01*
G01X1300967D02*
Y8092D01*
G01X1300982Y7991D02*
Y8089D01*
G01X1300997Y8109D02*
Y7991D01*
G01X1301017D02*
Y8109D01*
G01X1301031Y8094D02*
Y8059D01*
G01Y8006D02*
Y8044D01*
G01X1301093Y8029D02*
Y8021D01*
G01Y8074D02*
Y8079D01*
G01X1301107Y8081D02*
Y8071D01*
G01Y8031D02*
Y8019D01*
G01X1301226Y8046D02*
Y8056D01*
G01X1301260Y8077D02*
Y8081D01*
G01X1301263Y8019D02*
Y8029D01*
G01X1301272Y8081D02*
Y8077D01*
G01X1301275Y8029D02*
Y8019D01*
G01X1301294Y8097D02*
Y8109D01*
G01X1301334Y7991D02*
Y8097D01*
G01X1301348D02*
Y7991D01*
G01X1301388Y8109D02*
Y8097D01*
G01X1299028Y8049D02*
X1299038Y8054D01*
G01X1299230Y8102D02*
X1299240Y8106D01*
G01X1299296Y7999D02*
X1299287Y7993D01*
G01X1299904Y8102D02*
X1299914Y8106D01*
G01X1300123Y8102D02*
X1300133Y8106D01*
G01X1300347Y8102D02*
X1300357Y8106D01*
G01X1300190Y7999D02*
X1300180Y7993D01*
G01X1300413Y7999D02*
X1300404Y7993D01*
G01X1300581Y8054D02*
X1300576Y8051D01*
G01X1300763Y8102D02*
X1300773Y8106D01*
G01X1301098Y8054D02*
X1301093Y8051D01*
G01X1301201Y8102D02*
X1301211Y8106D01*
G01X1301250Y8006D02*
X1301255Y8008D01*
G01X1301260Y7999D02*
X1301250Y7993D01*
G01X1299019Y8059D02*
X1299026Y8061D01*
G01X1299761Y8097D02*
X1299754Y8094D01*
G01X1299779Y8046D02*
X1299786Y8049D01*
G01Y8006D02*
X1299779Y8004D01*
G01X1300251Y8094D02*
X1300259Y8097D01*
G01Y8054D02*
X1300251Y8051D01*
G01X1300276Y8004D02*
X1300283Y8006D01*
G01X1300561Y8059D02*
X1300569Y8061D01*
G01Y8008D02*
X1300561Y8006D01*
G01X1300918Y8059D02*
X1300925Y8061D01*
G01X1301078Y8059D02*
X1301085Y8061D01*
G01Y8008D02*
X1301078Y8006D01*
G01X1301235Y8056D02*
X1301250Y8061D01*
G01X1299813Y8024D02*
X1299816Y8041D01*
G01X1300224Y8077D02*
X1300222Y8059D01*
G01X1299803Y8041D02*
X1299801Y8026D01*
G01X1300234Y8059D02*
X1300236Y8074D01*
G01X1299213Y8069D02*
X1299215Y8081D01*
G01X1300106Y8069D02*
X1300108Y8081D01*
G01X1300330Y8069D02*
X1300332Y8081D01*
G01X1300426Y8021D02*
X1300423Y8008D01*
G01X1299230Y8079D02*
X1299228Y8069D01*
G01X1299309Y8019D02*
X1299306Y8008D01*
G01X1299892Y8081D02*
X1299894Y8092D01*
G01X1299978Y8077D02*
X1299976Y8066D01*
G01X1300123Y8079D02*
X1300121Y8069D01*
G01X1300202Y8019D02*
X1300200Y8008D01*
G01X1300347Y8079D02*
X1300344Y8069D01*
G01X1300751Y8081D02*
X1300753Y8092D01*
G01X1300837Y8077D02*
X1300834Y8066D01*
G01X1301189Y8081D02*
X1301191Y8092D01*
G01X1301272Y8077D02*
X1301270Y8066D01*
G01X1299031D02*
X1299033Y8074D01*
G01X1299045Y8064D02*
X1299048Y8071D01*
G01X1299291Y8014D02*
X1299294Y8021D01*
G01X1299742Y8081D02*
X1299739Y8074D01*
G01X1299798Y8061D02*
X1299801Y8069D01*
G01Y8026D02*
X1299798Y8019D01*
G01X1300185Y8014D02*
X1300187Y8021D01*
G01X1300236Y8074D02*
X1300239Y8081D01*
G01Y8041D02*
X1300236Y8034D01*
G01X1300295Y8019D02*
X1300298Y8026D01*
G01X1300409Y8014D02*
X1300411Y8021D01*
G01X1300574Y8066D02*
X1300576Y8074D01*
G01X1300591Y8071D02*
X1300588Y8064D01*
G01X1300576Y8021D02*
X1300574Y8014D01*
G01X1300591Y8019D02*
X1300588Y8011D01*
G01X1300930Y8066D02*
X1300933Y8074D01*
G01X1300948Y8071D02*
X1300945Y8064D01*
G01X1301090Y8066D02*
X1301093Y8074D01*
G01X1301107Y8071D02*
X1301105Y8064D01*
G01X1301093Y8021D02*
X1301090Y8014D01*
G01X1301107Y8019D02*
X1301105Y8011D01*
G01X1301275Y8019D02*
X1301272Y8011D01*
G01X1298829Y8109D02*
X1298789Y7991D01*
G01X1298780Y8006D02*
X1298814Y8109D01*
G01X1300669Y8004D02*
X1300706Y8109D01*
G01X1300581Y8001D02*
X1300571Y7993D01*
G01X1300938Y8054D02*
X1300928Y8046D01*
G01X1301098Y8001D02*
X1301088Y7993D01*
G01X1301265Y8059D02*
X1301255Y8051D01*
G01X1299242Y8092D02*
X1299235Y8086D01*
G01X1299284Y8008D02*
X1299291Y8014D01*
G01X1299754Y8094D02*
X1299747Y8089D01*
G01X1299786Y8049D02*
X1299793Y8054D01*
G01X1299789Y8036D02*
X1299803Y8046D01*
G01X1299793Y8011D02*
X1299786Y8006D01*
G01X1299917Y8094D02*
X1299909Y8089D01*
G01X1300135Y8092D02*
X1300128Y8086D01*
G01X1300244Y8089D02*
X1300251Y8094D01*
G01X1300249Y8064D02*
X1300234Y8054D01*
G01X1300177Y8008D02*
X1300185Y8014D01*
G01X1300251Y8051D02*
X1300244Y8046D01*
G01X1300359Y8092D02*
X1300352Y8086D01*
G01X1300283Y8006D02*
X1300291Y8011D01*
G01X1300401Y8008D02*
X1300409Y8014D01*
G01X1300775Y8094D02*
X1300768Y8089D01*
G01X1301213Y8094D02*
X1301206Y8089D01*
G01X1301267Y8004D02*
X1301260Y7999D01*
G01X1299752Y8106D02*
X1299739Y8099D01*
G01X1299789Y7993D02*
X1299801Y8001D01*
G01X1300249Y8106D02*
X1300236Y8099D01*
G01X1300285Y7993D02*
X1300298Y8001D01*
G01X1300714Y8084D02*
X1300679Y7991D01*
G01X1299732Y8089D02*
X1299727Y8077D01*
G01X1299808Y8011D02*
X1299813Y8024D01*
G01X1300229Y8089D02*
X1300224Y8077D01*
G01X1300305Y8011D02*
X1300310Y8024D01*
G01X1299215Y8081D02*
X1299220Y8092D01*
G01X1299958Y8066D02*
X1299963Y8077D01*
G01X1300108Y8081D02*
X1300113Y8092D01*
G01X1300332Y8081D02*
X1300337Y8092D01*
G01X1300817Y8066D02*
X1300822Y8077D01*
G01X1301255Y8066D02*
X1301260Y8077D01*
G01Y8014D02*
X1301263Y8019D01*
G01X1300047Y8021D02*
X1300079Y8084D01*
G01X1300086Y8079D02*
X1300054Y8016D01*
G01X1301127Y8021D02*
X1301159Y8084D01*
G01X1301167Y8079D02*
X1301135Y8016D01*
G01X1299235Y8086D02*
X1299230Y8079D01*
G01X1299747Y8089D02*
X1299742Y8081D01*
G01X1299793Y8054D02*
X1299798Y8061D01*
G01Y8019D02*
X1299793Y8011D01*
G01X1299909Y8089D02*
X1299904Y8081D01*
G01X1299976Y8066D02*
X1299970Y8059D01*
G01X1300128Y8086D02*
X1300123Y8079D01*
G01X1300239Y8081D02*
X1300244Y8089D01*
G01X1300291Y8011D02*
X1300295Y8019D01*
G01X1300352Y8086D02*
X1300347Y8079D01*
G01X1300768Y8089D02*
X1300763Y8081D01*
G01X1300834Y8066D02*
X1300830Y8059D01*
G01X1301206Y8089D02*
X1301201Y8081D01*
G01X1301270Y8066D02*
X1301265Y8059D01*
G01X1301272Y8011D02*
X1301267Y8004D01*
G01X1299038Y8054D02*
X1299045Y8064D01*
G01X1299739Y8099D02*
X1299732Y8089D01*
G01X1299801Y8001D02*
X1299808Y8011D01*
G01X1300236Y8099D02*
X1300229Y8089D01*
G01X1300298Y8001D02*
X1300305Y8011D01*
G01X1300588Y8064D02*
X1300581Y8054D01*
G01X1300588Y8011D02*
X1300581Y8001D01*
G01X1300945Y8064D02*
X1300938Y8054D01*
G01X1301105Y8064D02*
X1301098Y8054D01*
G01X1301105Y8011D02*
X1301098Y8001D01*
G01X1299678Y8092D02*
X1299693Y8109D01*
G01Y8089D02*
X1299678Y8071D01*
G01X1299998Y8092D02*
X1300013Y8109D01*
G01Y8089D02*
X1299998Y8071D01*
G01X1300967Y8092D02*
X1300982Y8109D01*
G01Y8089D02*
X1300967Y8071D01*
G01X1296821Y8208D02*
X1296600Y7969D01*
G01X1296452Y7919D02*
X1296722Y8208D01*
G01X1296538Y7906D02*
X1296452Y7818D01*
G01X1299026Y8061D02*
X1299031Y8066D01*
G01X1299220Y8092D02*
X1299230Y8102D01*
G01X1299306Y8008D02*
X1299296Y7999D01*
G01X1299894Y8092D02*
X1299904Y8102D01*
G01X1300113Y8092D02*
X1300123Y8102D01*
G01X1300200Y8008D02*
X1300190Y7999D01*
G01X1300244Y8046D02*
X1300239Y8041D01*
G01X1300337Y8092D02*
X1300347Y8102D01*
G01X1300423Y8008D02*
X1300413Y7999D01*
G01X1300569Y8061D02*
X1300574Y8066D01*
G01Y8014D02*
X1300569Y8008D01*
G01X1300753Y8092D02*
X1300763Y8102D01*
G01X1300925Y8061D02*
X1300930Y8066D01*
G01X1301085Y8061D02*
X1301090Y8066D01*
G01Y8014D02*
X1301085Y8008D01*
G01X1301191Y8092D02*
X1301201Y8102D01*
G01X1301250Y8061D02*
X1301255Y8066D01*
G01Y8008D02*
X1301260Y8014D01*
G01X1299889Y8004D02*
X1299958Y8066D01*
G01X1300748Y8004D02*
X1300817Y8066D01*
G01X1299970Y8059D02*
X1299909Y8004D01*
G01X1300830Y8059D02*
X1300768Y8004D01*
G01X1302476Y54861D02*
X1302402D01*
G01X1302894D02*
X1302820D01*
G01X1302771Y55012D02*
X1302525D01*
G01X1302759Y55062D02*
X1302537D01*
G01X1302598Y55452D02*
X1302697D01*
G01D02*
X1302894Y54861D01*
G01X1302820D02*
X1302771Y55012D01*
G01X1302648Y55401D02*
X1302759Y55062D01*
G01X1302756Y53542D02*
Y56692D01*
G01X1304134D02*
Y53542D01*
G01X1302537Y55062D02*
X1302648Y55401D01*
G01X1302525Y55012D02*
X1302476Y54861D01*
G01X1302402D02*
X1302598Y55452D01*
G01X1301250Y55238D02*
X1301240Y55235D01*
G01X1300391Y55250D02*
X1300401Y55253D01*
G01X1300167Y55250D02*
X1300177Y55253D01*
G01X1300369Y55338D02*
X1300359Y55336D01*
G01X1300145Y55338D02*
X1300135Y55336D01*
G01X1299274Y55250D02*
X1299284Y55253D01*
G01X1299252Y55338D02*
X1299242Y55336D01*
G01X1301238Y55248D02*
X1301250Y55250D01*
G01X1301088Y55238D02*
X1301076Y55235D01*
G01X1301226Y55341D02*
X1301213Y55338D01*
G01X1300928Y55290D02*
X1300915Y55288D01*
G01X1300571Y55238D02*
X1300559Y55235D01*
G01X1300404Y55238D02*
X1300391Y55235D01*
G01X1300273D02*
X1300285Y55238D01*
G01X1300787Y55341D02*
X1300775Y55338D01*
G01X1300180Y55238D02*
X1300167Y55235D01*
G01X1300261Y55310D02*
X1300249Y55308D01*
G01X1300357Y55351D02*
X1300369Y55353D01*
G01X1299776Y55235D02*
X1299789Y55238D01*
G01X1300261Y55353D02*
X1300249Y55351D01*
G01X1300133D02*
X1300145Y55353D01*
G01X1299776Y55278D02*
X1299789Y55280D01*
G01X1299929Y55341D02*
X1299917Y55338D01*
G01X1299287Y55238D02*
X1299274Y55235D01*
G01X1299764Y55353D02*
X1299752Y55351D01*
G01X1299240D02*
X1299252Y55353D01*
G01X1289331Y68775D02*
X1289376Y68783D01*
X1289403Y68810D01*
X1289411Y68855D01*
G01X1301211Y55351D02*
X1301228Y55353D01*
G01X1300773Y55351D02*
X1300790Y55353D01*
G01X1299914Y55351D02*
X1299931Y55353D01*
G01X1289411Y50541D02*
X1290411D01*
G01X1289411Y50638D02*
X1290411D01*
G01X1279695Y51111D02*
X1280395D01*
G01X1289411Y51142D02*
X1290411D01*
G01X1289411Y51171D02*
X1290411D01*
G01X1280395Y51327D02*
X1279695D01*
G01X1280395Y51423D02*
X1279695D01*
G01X1280395Y51485D02*
X1279695D01*
G01X1280395Y51583D02*
X1279695D01*
G01X1290411D02*
X1289411D01*
G01X1280395Y52568D02*
X1279695D01*
G01X1289411D02*
X1290411D01*
G01X1280395Y52666D02*
X1279695D01*
G01X1280395Y52729D02*
X1279695D01*
G01X1280395Y52823D02*
X1279695D01*
G01X1289411Y52975D02*
X1290411D01*
G01X1289411Y53005D02*
X1290411D01*
G01X1279695Y53040D02*
X1280395D01*
G01X1289411Y53512D02*
X1290411D01*
G01X1304134Y53542D02*
X1300984D01*
G01X1295079D02*
X1298228D01*
G01X1296457D02*
X1302756D01*
G01X1290411Y53605D02*
X1289411D01*
G01X1290411Y54260D02*
X1289411D01*
G01X1290411Y54275D02*
X1289411D01*
G01X1296821Y54861D02*
X1296722D01*
G01X1296452D02*
X1296378D01*
G01X1300027Y55235D02*
X1300013D01*
G01X1300167D02*
X1300145D01*
G01X1300391D02*
X1300369D01*
G01X1300559D02*
X1300500D01*
G01X1300728D02*
X1300714D01*
G01X1300625D02*
X1300610D01*
G01X1300679D02*
X1300659D01*
G01X1300837D02*
X1300748D01*
G01X1300871D02*
X1300856D01*
G01X1300997D02*
X1300982D01*
G01X1301076D02*
X1301017D01*
G01X1301240D02*
X1301220D01*
G01X1301348D02*
X1301334D01*
G01X1298711D02*
X1298622D01*
G01X1298789D02*
X1298770D01*
G01X1298937D02*
X1298848D01*
G01X1299159D02*
X1299070D01*
G01X1299193D02*
X1299178D01*
G01X1299274D02*
X1299252D01*
G01X1299427D02*
X1299412D01*
G01X1299343D02*
X1299328D01*
G01X1299501D02*
X1299486D01*
G01X1299707D02*
X1299693D01*
G01X1299978D02*
X1299889D01*
G01X1299033D02*
X1299050D01*
G01X1298957D02*
X1298972D01*
G01X1299767D02*
X1299776D01*
G01X1300261D02*
X1300273D01*
G01X1299779Y55248D02*
X1299764D01*
G01X1299909D02*
X1299978D01*
G01X1300259D02*
X1300276D01*
G01X1300768D02*
X1300837D01*
G01X1301223D02*
X1301238D01*
G01X1300561Y55250D02*
X1300515D01*
G01X1301078D02*
X1301031D01*
G01X1298637D02*
X1298711D01*
G01X1298863D02*
X1298937D01*
G01X1299085D02*
X1299159D01*
G01X1299252D02*
X1299274D01*
G01X1300145D02*
X1300167D01*
G01X1300369D02*
X1300391D01*
G01X1299744Y55263D02*
X1299732D01*
G01X1301186D02*
X1301198D01*
G01X1300411Y55265D02*
X1300426D01*
G01X1300480Y55278D02*
X1300446D01*
G01X1299870D02*
X1299835D01*
G01X1299764D02*
X1299776D01*
G01X1300187Y55285D02*
X1300165D01*
G01X1299294D02*
X1299272D01*
G01X1300915Y55288D02*
X1300871D01*
G01X1298972D02*
X1299013D01*
G01X1300515D02*
X1300561D01*
G01X1301031D02*
X1301078D01*
G01X1301235Y55290D02*
X1301226D01*
G01X1298701D02*
X1298637D01*
G01X1298927D02*
X1298863D01*
G01X1299412D02*
X1299343D01*
G01X1299761D02*
X1299779D01*
G01X1299835D02*
X1299870D01*
G01X1300446D02*
X1300480D01*
G01X1300276Y55298D02*
X1300259D01*
G01X1299272Y55301D02*
X1299309D01*
G01X1300165D02*
X1300202D01*
G01X1301226D02*
X1301235D01*
G01X1298972Y55303D02*
X1299019D01*
G01X1300515D02*
X1300561D01*
G01X1300871D02*
X1300918D01*
G01X1301031D02*
X1301078D01*
G01X1298637Y55305D02*
X1298701D01*
G01X1298863D02*
X1298927D01*
G01X1299343D02*
X1299412D01*
G01X1300273Y55310D02*
X1300261D01*
G01X1300202Y55323D02*
X1300187D01*
G01X1300426D02*
X1300411D01*
G01X1299309D02*
X1299294D01*
G01X1300763Y55325D02*
X1300751D01*
G01X1301201D02*
X1301189D01*
G01X1299904D02*
X1299892D01*
G01X1300293D02*
X1300305D01*
G01X1300167Y55338D02*
X1300145D01*
G01X1300391D02*
X1300369D01*
G01X1300561D02*
X1300515D01*
G01X1301078D02*
X1301031D01*
G01X1298711D02*
X1298637D01*
G01X1298937D02*
X1298863D01*
G01X1299274D02*
X1299252D01*
G01X1300797Y55341D02*
X1300787D01*
G01X1300918D02*
X1300871D01*
G01X1301235D02*
X1301226D01*
G01X1301334D02*
X1301294D01*
G01X1301388D02*
X1301348D01*
G01X1299019D02*
X1298972D01*
G01X1299486D02*
X1299446D01*
G01X1299540D02*
X1299501D01*
G01X1299779D02*
X1299761D01*
G01X1299939D02*
X1299929D01*
G01X1300259D02*
X1300273D01*
G01X1300271Y55353D02*
X1300261D01*
G01X1299016D02*
X1298957D01*
G01X1299776D02*
X1299764D01*
G01X1298622D02*
X1298711D01*
G01X1298814D02*
X1298829D01*
G01X1298730D02*
X1298745D01*
G01X1298848D02*
X1298937D01*
G01X1299070D02*
X1299085D01*
G01X1299178D02*
X1299193D01*
G01X1299252D02*
X1299274D01*
G01X1299412D02*
X1299427D01*
G01X1299328D02*
X1299343D01*
G01X1299446D02*
X1299540D01*
G01X1299693D02*
X1299707D01*
G01X1299931D02*
X1299941D01*
G01X1300013D02*
X1300027D01*
G01X1300145D02*
X1300167D01*
G01X1300369D02*
X1300391D01*
G01X1300500D02*
X1300559D01*
G01X1300706D02*
X1300728D01*
G01X1300610D02*
X1300633D01*
G01X1300790D02*
X1300800D01*
G01X1300856D02*
X1300915D01*
G01X1300982D02*
X1300997D01*
G01X1301017D02*
X1301076D01*
G01X1301228D02*
X1301233D01*
G01X1301294D02*
X1301388D01*
G01X1296722Y55452D02*
X1296821D01*
G01X1296378D02*
X1296452D01*
G01X1290411Y56275D02*
X1285892D01*
G01X1302756Y56692D02*
X1296457D01*
G01X1298228D02*
X1295079D01*
G01X1300984D02*
X1304134D01*
G01X1279695Y66071D02*
X1280395D01*
G01Y66288D02*
X1279695D01*
G01X1280395Y66383D02*
X1279695D01*
G01X1280395Y66445D02*
X1279695D01*
G01X1280395Y66544D02*
X1279695D01*
G01X1280395Y67528D02*
X1279695D01*
G01X1280395Y67627D02*
X1279695D01*
G01X1280395Y67689D02*
X1279695D01*
G01X1280395Y67784D02*
X1279695D01*
G01Y68001D02*
X1280395D01*
G01X1285892Y68775D02*
X1290411D01*
G01Y70775D02*
X1289411D01*
G01X1290411Y71775D02*
X1289411D01*
G01X1301233Y55353D02*
X1301250Y55351D01*
G01X1299941Y55353D02*
X1299956Y55351D01*
G01X1300800Y55353D02*
X1300815Y55351D01*
G01X1301250Y55288D02*
X1301235Y55290D01*
G01X1289331Y56275D02*
X1289377Y56266D01*
X1289403Y56240D01*
X1289411Y56195D01*
G01X1299252Y55235D02*
X1299240Y55238D01*
G01X1299028Y55351D02*
X1299016Y55353D01*
G01X1299754Y55238D02*
X1299767Y55235D01*
G01X1299274Y55353D02*
X1299287Y55351D01*
G01X1299752Y55280D02*
X1299764Y55278D01*
G01X1300145Y55235D02*
X1300133Y55238D01*
G01X1300249D02*
X1300261Y55235D01*
G01X1299789Y55351D02*
X1299776Y55353D01*
G01X1300369Y55235D02*
X1300357Y55238D01*
G01X1299951Y55338D02*
X1299939Y55341D01*
G01X1300285Y55308D02*
X1300273Y55310D01*
G01X1300167Y55353D02*
X1300180Y55351D01*
G01X1300283D02*
X1300271Y55353D01*
G01X1300391D02*
X1300404Y55351D01*
G01X1300559Y55353D02*
X1300571Y55351D01*
G01X1301211Y55250D02*
X1301223Y55248D01*
G01X1300810Y55338D02*
X1300797Y55341D01*
G01X1300915Y55353D02*
X1300928Y55351D01*
G01X1301076Y55353D02*
X1301088Y55351D01*
G01X1301248Y55338D02*
X1301235Y55341D01*
G01X1300359Y55253D02*
X1300369Y55250D01*
G01X1300177Y55336D02*
X1300167Y55338D01*
G01X1301220Y55235D02*
X1301211Y55238D01*
G01X1299242Y55253D02*
X1299252Y55250D01*
G01X1299284Y55336D02*
X1299274Y55338D01*
G01X1300135Y55253D02*
X1300145Y55250D01*
G01X1300401Y55336D02*
X1300391Y55338D01*
G01X1299026D02*
X1299019Y55341D01*
G01X1299764Y55248D02*
X1299757Y55250D01*
G01X1299754Y55293D02*
X1299761Y55290D01*
G01X1299786Y55338D02*
X1299779Y55341D01*
G01X1300251Y55250D02*
X1300259Y55248D01*
G01X1300283Y55295D02*
X1300276Y55298D01*
G01X1300273Y55341D02*
X1300281Y55338D01*
G01X1300561Y55288D02*
X1300569Y55285D01*
G01Y55336D02*
X1300561Y55338D01*
G01X1300925D02*
X1300918Y55341D01*
G01X1301078Y55288D02*
X1301085Y55285D01*
G01Y55336D02*
X1301078Y55338D01*
G01X1301255Y55295D02*
X1301267Y55290D01*
G01X1299240Y55238D02*
X1299230Y55243D01*
G01X1299287Y55351D02*
X1299296Y55346D01*
G01X1300133Y55238D02*
X1300123Y55243D01*
G01X1299956Y55351D02*
X1299966Y55346D01*
G01X1300357Y55238D02*
X1300347Y55243D01*
G01X1300180Y55351D02*
X1300190Y55346D01*
G01X1300404Y55351D02*
X1300413Y55346D01*
G01X1300576Y55295D02*
X1300581Y55293D01*
G01X1300815Y55351D02*
X1300824Y55346D01*
G01X1301093Y55295D02*
X1301098Y55293D01*
G01X1301211Y55238D02*
X1301201Y55243D01*
G01X1301206Y55253D02*
X1301211Y55250D01*
G01X1301250Y55351D02*
X1301260Y55346D01*
G01X1299742Y55245D02*
X1299754Y55238D01*
G01X1299739Y55288D02*
X1299752Y55280D01*
G01X1299801Y55343D02*
X1299789Y55351D01*
G01X1300236Y55245D02*
X1300249Y55238D01*
G01X1300298Y55301D02*
X1300285Y55308D01*
G01X1300295Y55343D02*
X1300283Y55351D01*
G01X1299235Y55258D02*
X1299242Y55253D01*
G01X1299291Y55330D02*
X1299284Y55336D01*
G01X1299757Y55250D02*
X1299749Y55255D01*
G01X1299747Y55298D02*
X1299754Y55293D01*
G01X1299793Y55333D02*
X1299786Y55338D01*
G01X1300054Y55260D02*
X1300047Y55265D01*
G01X1299958Y55333D02*
X1299951Y55338D01*
G01X1300128Y55258D02*
X1300135Y55253D01*
G01X1300079Y55328D02*
X1300086Y55323D01*
G01X1300244Y55255D02*
X1300251Y55250D01*
G01X1300185Y55330D02*
X1300177Y55336D01*
G01X1300291Y55290D02*
X1300283Y55295D01*
G01X1300352Y55258D02*
X1300359Y55253D01*
G01X1300281Y55338D02*
X1300288Y55333D01*
G01X1300409Y55330D02*
X1300401Y55336D01*
G01X1300817Y55333D02*
X1300810Y55338D01*
G01X1301135Y55260D02*
X1301127Y55265D01*
G01X1301201Y55243D02*
X1301194Y55248D01*
G01X1301159Y55328D02*
X1301167Y55323D01*
G01X1301257Y55283D02*
X1301250Y55288D01*
G01X1301255Y55333D02*
X1301248Y55338D01*
G01X1299038Y55343D02*
X1299028Y55351D01*
G01X1300571D02*
X1300581Y55343D01*
G01X1300928Y55351D02*
X1300938Y55343D01*
G01X1301088Y55351D02*
X1301098Y55343D01*
G01X1300569Y55285D02*
X1300574Y55280D01*
G01Y55330D02*
X1300569Y55336D01*
G01X1301085Y55285D02*
X1301090Y55280D01*
G01Y55330D02*
X1301085Y55336D01*
G01X1299031Y55333D02*
X1299026Y55338D01*
G01X1299230Y55243D02*
X1299220Y55253D01*
G01X1299296Y55346D02*
X1299306Y55336D01*
G01X1299966Y55346D02*
X1299976Y55336D01*
G01X1300123Y55243D02*
X1300113Y55253D01*
G01X1300190Y55346D02*
X1300200Y55336D01*
G01X1300295Y55285D02*
X1300291Y55290D01*
G01X1300347Y55243D02*
X1300337Y55253D01*
G01X1300305Y55293D02*
X1300298Y55301D01*
G01X1300413Y55346D02*
X1300423Y55336D01*
G01X1300824Y55346D02*
X1300834Y55336D01*
G01X1300930Y55333D02*
X1300925Y55338D01*
G01X1301201Y55258D02*
X1301206Y55253D01*
G01X1301260Y55346D02*
X1301270Y55336D01*
G01X1299045Y55333D02*
X1299038Y55343D01*
G01X1299734Y55255D02*
X1299742Y55245D01*
G01X1299732Y55298D02*
X1299739Y55288D01*
G01X1299808Y55333D02*
X1299801Y55343D01*
G01X1300229Y55255D02*
X1300236Y55245D01*
G01X1300303Y55333D02*
X1300295Y55343D01*
G01X1300581Y55293D02*
X1300588Y55283D01*
G01X1300581Y55343D02*
X1300588Y55333D01*
G01X1300938Y55343D02*
X1300945Y55333D01*
G01X1301098Y55293D02*
X1301105Y55283D01*
G01X1301098Y55343D02*
X1301105Y55333D01*
G01X1299230Y55265D02*
X1299235Y55258D01*
G01X1299749Y55255D02*
X1299744Y55263D01*
G01X1299742Y55305D02*
X1299747Y55298D01*
G01X1299798Y55325D02*
X1299793Y55333D01*
G01X1299963Y55325D02*
X1299958Y55333D01*
G01X1300123Y55265D02*
X1300128Y55258D01*
G01X1300239Y55263D02*
X1300244Y55255D01*
G01X1300288Y55333D02*
X1300293Y55325D01*
G01X1300347Y55265D02*
X1300352Y55258D01*
G01X1300822Y55325D02*
X1300817Y55333D01*
G01X1301194Y55248D02*
X1301189Y55255D01*
G01X1301260Y55325D02*
X1301255Y55333D01*
G01X1301267Y55290D02*
X1301272Y55283D01*
G01X1296722Y54861D02*
X1296538Y55150D01*
G01X1296600Y55213D02*
X1296821Y54861D01*
G01X1299220Y55253D02*
X1299215Y55263D01*
G01X1300113Y55253D02*
X1300108Y55263D01*
G01X1300337Y55253D02*
X1300332Y55263D01*
G01X1301198D02*
X1301201Y55258D01*
G01X1301263Y55273D02*
X1301257Y55283D01*
G01X1299727Y55310D02*
X1299732Y55298D01*
G01X1299813Y55321D02*
X1299808Y55333D01*
G01X1300224Y55268D02*
X1300229Y55255D01*
G01X1300310Y55280D02*
X1300305Y55293D01*
G01X1299050Y55235D02*
X1299028Y55293D01*
G01X1299013Y55288D02*
X1299033Y55235D01*
G01X1300659D02*
X1300625Y55328D01*
G01X1300633Y55353D02*
X1300669Y55248D01*
G01X1298745Y55353D02*
X1298780Y55250D01*
G01X1298770Y55235D02*
X1298730Y55353D01*
G01X1299033Y55325D02*
X1299031Y55333D01*
G01X1299048Y55325D02*
X1299045Y55333D01*
G01X1299294Y55323D02*
X1299291Y55330D01*
G01X1299732Y55263D02*
X1299734Y55255D01*
G01X1299739Y55313D02*
X1299742Y55305D01*
G01X1299801Y55318D02*
X1299798Y55325D01*
G01X1300187Y55323D02*
X1300185Y55330D01*
G01X1300236Y55270D02*
X1300239Y55263D01*
G01X1300298Y55278D02*
X1300295Y55285D01*
G01X1300305Y55325D02*
X1300303Y55333D01*
G01X1300411Y55323D02*
X1300409Y55330D01*
G01X1300574Y55280D02*
X1300576Y55273D01*
G01X1300588Y55283D02*
X1300591Y55275D01*
G01X1300576Y55323D02*
X1300574Y55330D01*
G01X1300588Y55333D02*
X1300591Y55325D01*
G01X1300933D02*
X1300930Y55333D01*
G01X1300945D02*
X1300948Y55325D01*
G01X1301090Y55280D02*
X1301093Y55273D01*
G01X1301105Y55283D02*
X1301107Y55275D01*
G01X1301093Y55323D02*
X1301090Y55330D01*
G01X1301105Y55333D02*
X1301107Y55325D01*
G01X1301189Y55255D02*
X1301186Y55263D01*
G01X1299228Y55275D02*
X1299230Y55265D01*
G01X1299976Y55336D02*
X1299978Y55325D01*
G01X1300121Y55275D02*
X1300123Y55265D01*
G01X1300344Y55275D02*
X1300347Y55265D01*
G01X1300834Y55336D02*
X1300837Y55325D01*
G01X1301272Y55283D02*
X1301275Y55273D01*
G01X1301270Y55336D02*
X1301272Y55325D01*
G01X1299215Y55263D02*
X1299213Y55275D01*
G01X1299306Y55336D02*
X1299309Y55323D01*
G01X1300108Y55263D02*
X1300106Y55275D01*
G01X1300200Y55336D02*
X1300202Y55323D01*
G01X1300332Y55263D02*
X1300330Y55275D01*
G01X1300423Y55336D02*
X1300426Y55323D01*
G01X1279695Y51112D02*
Y53038D01*
G01Y66073D02*
Y67999D01*
G01X1280395Y51113D02*
Y53039D01*
G01Y66073D02*
Y67999D01*
G01X1284892Y67775D02*
Y57275D01*
G01X1286427Y68775D02*
Y92474D01*
G01X1286765Y68775D02*
Y56275D01*
G01X1299019Y55303D02*
X1299026Y55305D01*
G01X1299761Y55341D02*
X1299754Y55338D01*
G01X1299779Y55290D02*
X1299786Y55293D01*
G01Y55250D02*
X1299779Y55248D01*
G01X1300251Y55338D02*
X1300259Y55341D01*
G01Y55298D02*
X1300251Y55295D01*
G01X1300276Y55248D02*
X1300283Y55250D01*
G01X1300561Y55303D02*
X1300569Y55305D01*
G01Y55253D02*
X1300561Y55250D01*
G01X1300918Y55303D02*
X1300925Y55305D01*
G01X1301078Y55303D02*
X1301085Y55305D01*
G01Y55253D02*
X1301078Y55250D01*
G01X1301235Y55301D02*
X1301250Y55305D01*
G01X1299816Y55303D02*
X1299813Y55321D01*
G01X1300222Y55285D02*
X1300224Y55268D01*
G01X1291789Y72001D02*
Y78891D01*
G01X1295079Y56692D02*
Y53542D01*
G01X1296378Y54861D02*
Y55452D01*
G01X1296452Y55062D02*
Y54861D01*
G01Y55452D02*
Y55163D01*
G01X1296457Y56692D02*
Y53542D01*
G01X1297244D02*
Y56692D01*
G01X1297408D02*
Y53542D01*
G01X1298228D02*
Y56692D01*
G01X1298622Y55235D02*
Y55353D01*
G01X1298637Y55290D02*
Y55250D01*
G01Y55338D02*
Y55305D01*
G01X1298701D02*
Y55290D01*
G01X1298711Y55353D02*
Y55338D01*
G01Y55250D02*
Y55235D01*
G01X1298848D02*
Y55353D01*
G01X1298863Y55290D02*
Y55250D01*
G01Y55338D02*
Y55305D01*
G01X1298927D02*
Y55290D01*
G01X1298937Y55353D02*
Y55338D01*
G01Y55250D02*
Y55235D01*
G01X1298957Y55353D02*
Y55235D01*
G01X1298972Y55341D02*
Y55303D01*
G01Y55235D02*
Y55288D01*
G01X1299033Y55318D02*
Y55325D01*
G01X1299048Y55316D02*
Y55325D01*
G01X1299070Y55235D02*
Y55353D01*
G01X1299085D02*
Y55250D01*
G01X1299159D02*
Y55235D01*
G01X1299178D02*
Y55353D01*
G01X1299193D02*
Y55235D01*
G01X1299213Y55275D02*
Y55313D01*
G01X1299228D02*
Y55275D01*
G01X1299272Y55285D02*
Y55301D01*
G01X1299294Y55265D02*
Y55285D01*
G01X1299309Y55301D02*
Y55263D01*
G01X1299328Y55235D02*
Y55353D01*
G01X1299343Y55290D02*
Y55235D01*
G01Y55353D02*
Y55305D01*
G01X1299412Y55235D02*
Y55290D01*
G01Y55305D02*
Y55353D01*
G01X1299427D02*
Y55235D01*
G01X1299446Y55341D02*
Y55353D01*
G01X1299486Y55235D02*
Y55341D01*
G01X1299501D02*
Y55235D01*
G01X1299540Y55353D02*
Y55341D01*
G01X1299678Y55316D02*
Y55336D01*
G01X1299693Y55235D02*
Y55333D01*
G01X1299707Y55353D02*
Y55235D01*
G01X1299727Y55321D02*
Y55310D01*
G01X1299739Y55318D02*
Y55313D01*
G01X1299801D02*
Y55318D01*
G01X1299803Y55290D02*
Y55285D01*
G01X1299816D02*
Y55303D01*
G01X1299835Y55278D02*
Y55290D01*
G01X1299870D02*
Y55278D01*
G01X1299889Y55235D02*
Y55248D01*
G01X1299963Y55321D02*
Y55325D01*
G01X1299978Y55248D02*
Y55235D01*
G01Y55325D02*
Y55321D01*
G01X1299998Y55316D02*
Y55336D01*
G01X1300013Y55235D02*
Y55333D01*
G01X1300027Y55353D02*
Y55235D01*
G01X1300106Y55275D02*
Y55313D01*
G01X1300121D02*
Y55275D01*
G01X1300165Y55285D02*
Y55301D01*
G01X1300187Y55265D02*
Y55285D01*
G01X1300202Y55301D02*
Y55263D01*
G01X1300222Y55303D02*
Y55285D01*
G01X1300234Y55298D02*
Y55303D01*
G01X1300236Y55278D02*
Y55270D01*
G01X1300298D02*
Y55278D01*
G01X1300310Y55268D02*
Y55280D01*
G01X1300330Y55275D02*
Y55313D01*
G01X1300344D02*
Y55275D01*
G01X1300446Y55278D02*
Y55290D01*
G01X1300480D02*
Y55278D01*
G01X1300500Y55235D02*
Y55353D01*
G01X1300515Y55338D02*
Y55303D01*
G01Y55250D02*
Y55288D01*
G01X1300576Y55273D02*
Y55265D01*
G01Y55318D02*
Y55323D01*
G01X1300591Y55325D02*
Y55316D01*
G01Y55275D02*
Y55263D01*
G01X1300610Y55235D02*
Y55353D01*
G01X1300625Y55328D02*
Y55235D01*
G01X1300714D02*
Y55328D01*
G01X1300728Y55353D02*
Y55235D01*
G01X1300748D02*
Y55248D01*
G01X1300822Y55321D02*
Y55325D01*
G01X1300837Y55248D02*
Y55235D01*
G01Y55325D02*
Y55321D01*
G01X1300856Y55235D02*
Y55353D01*
G01X1300871Y55288D02*
Y55235D01*
G01Y55341D02*
Y55303D01*
G01X1300933Y55318D02*
Y55325D01*
G01X1300948D02*
Y55316D01*
G01X1300967D02*
Y55336D01*
G01X1300982Y55235D02*
Y55333D01*
G01X1300984Y53542D02*
Y56692D01*
G01X1300997Y55353D02*
Y55235D01*
G01X1301017D02*
Y55353D01*
G01X1301031Y55338D02*
Y55303D01*
G01Y55250D02*
Y55288D01*
G01X1301093Y55273D02*
Y55265D01*
G01Y55318D02*
Y55323D01*
G01X1301107Y55325D02*
Y55316D01*
G01Y55275D02*
Y55263D01*
G01X1301226Y55290D02*
Y55301D01*
G01X1301260Y55321D02*
Y55325D01*
G01X1301263Y55263D02*
Y55273D01*
G01X1301272Y55325D02*
Y55321D01*
G01X1301275Y55273D02*
Y55263D01*
G01X1301294Y55341D02*
Y55353D01*
G01X1301334Y55235D02*
Y55341D01*
G01X1301348D02*
Y55235D01*
G01X1301388Y55353D02*
Y55341D01*
G01X1301805Y53542D02*
Y56692D01*
G01X1301969Y53542D02*
Y56692D01*
G01X1299813Y55268D02*
X1299816Y55285D01*
G01X1300224Y55321D02*
X1300222Y55303D01*
G01X1299242Y55336D02*
X1299235Y55330D01*
G01X1299284Y55253D02*
X1299291Y55258D01*
G01X1299754Y55338D02*
X1299747Y55333D01*
G01X1299786Y55293D02*
X1299793Y55298D01*
G01X1299789Y55280D02*
X1299803Y55290D01*
G01X1299793Y55255D02*
X1299786Y55250D01*
G01X1299917Y55338D02*
X1299909Y55333D01*
G01X1300135Y55336D02*
X1300128Y55330D01*
G01X1300244Y55333D02*
X1300251Y55338D01*
G01X1300249Y55308D02*
X1300234Y55298D01*
G01X1300177Y55253D02*
X1300185Y55258D01*
G01X1300251Y55295D02*
X1300244Y55290D01*
G01X1300359Y55336D02*
X1300352Y55330D01*
G01X1300283Y55250D02*
X1300291Y55255D01*
G01X1300401Y55253D02*
X1300409Y55258D01*
G01X1300775Y55338D02*
X1300768Y55333D01*
G01X1301213Y55338D02*
X1301206Y55333D01*
G01X1301267Y55248D02*
X1301260Y55243D01*
G01X1299752Y55351D02*
X1299739Y55343D01*
G01X1299789Y55238D02*
X1299801Y55245D01*
G01X1300249Y55351D02*
X1300236Y55343D01*
G01X1300285Y55238D02*
X1300298Y55245D01*
G01X1291789Y72001D02*
X1290411Y71206D01*
G01X1299028Y55293D02*
X1299038Y55298D01*
G01X1299230Y55346D02*
X1299240Y55351D01*
G01X1299296Y55243D02*
X1299287Y55238D01*
G01X1299904Y55346D02*
X1299914Y55351D01*
G01X1300123Y55346D02*
X1300133Y55351D01*
G01X1300347Y55346D02*
X1300357Y55351D01*
G01X1300190Y55243D02*
X1300180Y55238D01*
G01X1300413Y55243D02*
X1300404Y55238D01*
G01X1300581Y55298D02*
X1300576Y55295D01*
G01X1300763Y55346D02*
X1300773Y55351D01*
G01X1301098Y55298D02*
X1301093Y55295D01*
G01X1301201Y55346D02*
X1301211Y55351D01*
G01X1301250Y55250D02*
X1301255Y55253D01*
G01X1301260Y55243D02*
X1301250Y55238D01*
G01X1299803Y55285D02*
X1299801Y55270D01*
G01X1300234Y55303D02*
X1300236Y55318D01*
G01X1299213Y55313D02*
X1299215Y55325D01*
G01X1300106Y55313D02*
X1300108Y55325D01*
G01X1300330Y55313D02*
X1300332Y55325D01*
G01X1300426Y55265D02*
X1300423Y55253D01*
G01X1299230Y55323D02*
X1299228Y55313D01*
G01X1299309Y55263D02*
X1299306Y55253D01*
G01X1299892Y55325D02*
X1299894Y55336D01*
G01X1299978Y55321D02*
X1299976Y55310D01*
G01X1300123Y55323D02*
X1300121Y55313D01*
G01X1300202Y55263D02*
X1300200Y55253D01*
G01X1300347Y55323D02*
X1300344Y55313D01*
G01X1300751Y55325D02*
X1300753Y55336D01*
G01X1300837Y55321D02*
X1300834Y55310D01*
G01X1301189Y55325D02*
X1301191Y55336D01*
G01X1301272Y55321D02*
X1301270Y55310D01*
G01X1299031D02*
X1299033Y55318D01*
G01X1299045Y55308D02*
X1299048Y55316D01*
G01X1299291Y55258D02*
X1299294Y55265D01*
G01X1299742Y55325D02*
X1299739Y55318D01*
G01X1299798Y55305D02*
X1299801Y55313D01*
G01Y55270D02*
X1299798Y55263D01*
G01X1300185Y55258D02*
X1300187Y55265D01*
G01X1300236Y55318D02*
X1300239Y55325D01*
G01Y55285D02*
X1300236Y55278D01*
G01X1300295Y55263D02*
X1300298Y55270D01*
G01X1300409Y55258D02*
X1300411Y55265D01*
G01X1300574Y55310D02*
X1300576Y55318D01*
G01X1300591Y55316D02*
X1300588Y55308D01*
G01X1300576Y55265D02*
X1300574Y55258D01*
G01X1300591Y55263D02*
X1300588Y55255D01*
G01X1300930Y55310D02*
X1300933Y55318D01*
G01X1300948Y55316D02*
X1300945Y55308D01*
G01X1301090Y55310D02*
X1301093Y55318D01*
G01X1301107Y55316D02*
X1301105Y55308D01*
G01X1301093Y55265D02*
X1301090Y55258D01*
G01X1301107Y55263D02*
X1301105Y55255D01*
G01X1301275Y55263D02*
X1301272Y55255D01*
G01X1298829Y55353D02*
X1298789Y55235D01*
G01X1298780Y55250D02*
X1298814Y55353D01*
G01X1300669Y55248D02*
X1300706Y55353D01*
G01X1300714Y55328D02*
X1300679Y55235D01*
G01X1299732Y55333D02*
X1299727Y55321D01*
G01X1299808Y55255D02*
X1299813Y55268D01*
G01X1300229Y55333D02*
X1300224Y55321D01*
G01X1300305Y55255D02*
X1300310Y55268D01*
G01X1299215Y55325D02*
X1299220Y55336D01*
G01X1299958Y55310D02*
X1299963Y55321D01*
G01X1300108Y55325D02*
X1300113Y55336D01*
G01X1300332Y55325D02*
X1300337Y55336D01*
G01X1300817Y55310D02*
X1300822Y55321D01*
G01X1301255Y55310D02*
X1301260Y55321D01*
G01Y55258D02*
X1301263Y55263D01*
G01X1300047Y55265D02*
X1300079Y55328D01*
G01X1300086Y55323D02*
X1300054Y55260D01*
G01X1301127Y55265D02*
X1301159Y55328D01*
G01X1301167Y55323D02*
X1301135Y55260D01*
G01X1299235Y55330D02*
X1299230Y55323D01*
G01X1299038Y55298D02*
X1299045Y55308D01*
G01X1299739Y55343D02*
X1299732Y55333D01*
G01X1299801Y55245D02*
X1299808Y55255D01*
G01X1300236Y55343D02*
X1300229Y55333D01*
G01X1300298Y55245D02*
X1300305Y55255D01*
G01X1300588Y55308D02*
X1300581Y55298D01*
G01X1300588Y55255D02*
X1300581Y55245D01*
G01X1300945Y55308D02*
X1300938Y55298D01*
G01X1301105Y55308D02*
X1301098Y55298D01*
G01X1301105Y55255D02*
X1301098Y55245D01*
G01X1299678Y55336D02*
X1299693Y55353D01*
G01Y55333D02*
X1299678Y55316D01*
G01X1299998Y55336D02*
X1300013Y55353D01*
G01Y55333D02*
X1299998Y55316D01*
G01X1300967Y55336D02*
X1300982Y55353D01*
G01Y55333D02*
X1300967Y55316D01*
G01X1296821Y55452D02*
X1296600Y55213D01*
G01X1296452Y55163D02*
X1296722Y55452D01*
G01X1296538Y55150D02*
X1296452Y55062D01*
G01X1299026Y55305D02*
X1299031Y55310D01*
G01X1299220Y55336D02*
X1299230Y55346D01*
G01X1299306Y55253D02*
X1299296Y55243D01*
G01X1299894Y55336D02*
X1299904Y55346D01*
G01X1300113Y55336D02*
X1300123Y55346D01*
G01X1300200Y55253D02*
X1300190Y55243D01*
G01X1300244Y55290D02*
X1300239Y55285D01*
G01X1300337Y55336D02*
X1300347Y55346D01*
G01X1300423Y55253D02*
X1300413Y55243D01*
G01X1300569Y55305D02*
X1300574Y55310D01*
G01Y55258D02*
X1300569Y55253D01*
G01X1300753Y55336D02*
X1300763Y55346D01*
G01X1300925Y55305D02*
X1300930Y55310D01*
G01X1301085Y55305D02*
X1301090Y55310D01*
G01Y55258D02*
X1301085Y55253D01*
G01X1301191Y55336D02*
X1301201Y55346D01*
G01X1301250Y55305D02*
X1301255Y55310D01*
G01Y55253D02*
X1301260Y55258D01*
G01X1299889Y55248D02*
X1299958Y55310D01*
G01X1300748Y55248D02*
X1300817Y55310D01*
G01X1299970Y55303D02*
X1299909Y55248D01*
G01X1300830Y55303D02*
X1300768Y55248D01*
G01X1300581Y55245D02*
X1300571Y55238D01*
G01X1300938Y55298D02*
X1300928Y55290D01*
G01X1301098Y55245D02*
X1301088Y55238D01*
G01X1301265Y55303D02*
X1301255Y55295D01*
G01X1299747Y55333D02*
X1299742Y55325D01*
G01X1299793Y55298D02*
X1299798Y55305D01*
G01Y55263D02*
X1299793Y55255D01*
G01X1299909Y55333D02*
X1299904Y55325D01*
G01X1299976Y55310D02*
X1299970Y55303D01*
G01X1300128Y55330D02*
X1300123Y55323D01*
G01X1300239Y55325D02*
X1300244Y55333D01*
G01X1300291Y55255D02*
X1300295Y55263D01*
G01X1300352Y55330D02*
X1300347Y55323D01*
G01X1300768Y55333D02*
X1300763Y55325D01*
G01X1300834Y55310D02*
X1300830Y55303D01*
G01X1301206Y55333D02*
X1301201Y55325D01*
G01X1301270Y55310D02*
X1301265Y55303D01*
G01X1301272Y55255D02*
X1301267Y55248D01*
G01X1285892Y68775D02*
G03X1284892Y67775I0J-1000D01*
G01Y57275D02*
G03X1285892Y56275I1000J0D01*
G01X1284386Y105171D02*
Y44408D01*
G01X1285799Y105171D02*
Y44408D01*
G01X1286427D02*
Y56275D01*
G01X1287427Y44408D02*
Y105171D01*
G01X1302598Y79074D02*
X1302697D01*
G01X1302476Y78483D02*
X1302402D01*
G01X1302894D02*
X1302820D01*
G01X1302771Y78634D02*
X1302525D01*
G01X1302759Y78684D02*
X1302537D01*
G01X1302697Y79074D02*
X1302894Y78483D01*
G01X1302820D02*
X1302771Y78634D01*
G01X1302648Y79023D02*
X1302759Y78684D01*
G01X1302756Y77164D02*
Y80314D01*
G01X1304134D02*
Y77164D01*
G01X1302537Y78684D02*
X1302648Y79023D01*
G01X1302525Y78634D02*
X1302476Y78483D01*
G01X1302402D02*
X1302598Y79074D01*
G01X1300391Y78872D02*
X1300401Y78875D01*
G01X1300167Y78872D02*
X1300177Y78875D01*
G01X1300369Y78960D02*
X1300359Y78958D01*
G01X1300145Y78960D02*
X1300135Y78958D01*
G01X1299274Y78872D02*
X1299284Y78875D01*
G01X1299252Y78960D02*
X1299242Y78958D01*
G01X1301238Y78870D02*
X1301250Y78872D01*
G01X1301226Y78963D02*
X1301213Y78960D01*
G01X1300928Y78912D02*
X1300915Y78910D01*
G01X1300787Y78963D02*
X1300775Y78960D01*
G01X1300261Y78932D02*
X1300249Y78930D01*
G01X1300357Y78973D02*
X1300369Y78975D01*
G01X1300261D02*
X1300249Y78973D01*
G01X1300133D02*
X1300145Y78975D01*
G01X1299776Y78900D02*
X1299789Y78903D01*
G01X1299929Y78963D02*
X1299917Y78960D01*
G01X1299764Y78975D02*
X1299752Y78973D01*
G01X1299240D02*
X1299252Y78975D01*
G01X1301211Y78973D02*
X1301228Y78975D01*
G01X1300773Y78973D02*
X1300790Y78975D01*
G01X1299914Y78973D02*
X1299931Y78975D01*
G01X1299779Y78870D02*
X1299764D01*
G01X1299909D02*
X1299978D01*
G01X1300259D02*
X1300276D01*
G01X1300768D02*
X1300837D01*
G01X1301223D02*
X1301238D01*
G01X1300561Y78872D02*
X1300515D01*
G01X1301078D02*
X1301031D01*
G01X1298637D02*
X1298711D01*
G01X1298863D02*
X1298937D01*
G01X1299085D02*
X1299159D01*
G01X1299252D02*
X1299274D01*
G01X1300145D02*
X1300167D01*
G01X1300369D02*
X1300391D01*
G01X1299744Y78885D02*
X1299732D01*
G01X1301186D02*
X1301198D01*
G01X1300411Y78887D02*
X1300426D01*
G01X1300480Y78900D02*
X1300446D01*
G01X1299870D02*
X1299835D01*
G01X1299764D02*
X1299776D01*
G01X1300187Y78907D02*
X1300165D01*
G01X1299294D02*
X1299272D01*
G01X1300915Y78910D02*
X1300871D01*
G01X1298972D02*
X1299013D01*
G01X1300515D02*
X1300561D01*
G01X1301031D02*
X1301078D01*
G01X1301235Y78912D02*
X1301226D01*
G01X1298701D02*
X1298637D01*
G01X1298927D02*
X1298863D01*
G01X1299412D02*
X1299343D01*
G01X1299761D02*
X1299779D01*
G01X1299835D02*
X1299870D01*
G01X1300446D02*
X1300480D01*
G01X1300276Y78920D02*
X1300259D01*
G01X1299272Y78923D02*
X1299309D01*
G01X1300165D02*
X1300202D01*
G01X1301226D02*
X1301235D01*
G01X1298972Y78925D02*
X1299019D01*
G01X1300515D02*
X1300561D01*
G01X1300871D02*
X1300918D01*
G01X1301031D02*
X1301078D01*
G01X1298637Y78927D02*
X1298701D01*
G01X1298863D02*
X1298927D01*
G01X1299343D02*
X1299412D01*
G01X1300273Y78932D02*
X1300261D01*
G01X1300202Y78945D02*
X1300187D01*
G01X1300426D02*
X1300411D01*
G01X1299309D02*
X1299294D01*
G01X1300763Y78947D02*
X1300751D01*
G01X1301201D02*
X1301189D01*
G01X1299904D02*
X1299892D01*
G01X1300293D02*
X1300305D01*
G01X1300167Y78960D02*
X1300145D01*
G01X1300391D02*
X1300369D01*
G01X1300561D02*
X1300515D01*
G01X1301078D02*
X1301031D01*
G01X1298711D02*
X1298637D01*
G01X1298937D02*
X1298863D01*
G01X1299274D02*
X1299252D01*
G01X1300797Y78963D02*
X1300787D01*
G01X1300918D02*
X1300871D01*
G01X1301235D02*
X1301226D01*
G01X1301334D02*
X1301294D01*
G01X1301388D02*
X1301348D01*
G01X1299019D02*
X1298972D01*
G01X1299486D02*
X1299446D01*
G01X1299540D02*
X1299501D01*
G01X1299779D02*
X1299761D01*
G01X1299939D02*
X1299929D01*
G01X1300259D02*
X1300273D01*
G01X1300271Y78975D02*
X1300261D01*
G01X1299016D02*
X1298957D01*
G01X1299776D02*
X1299764D01*
G01X1298622D02*
X1298711D01*
G01X1298814D02*
X1298829D01*
G01X1298730D02*
X1298745D01*
G01X1298848D02*
X1298937D01*
G01X1299070D02*
X1299085D01*
G01X1299178D02*
X1299193D01*
G01X1299252D02*
X1299274D01*
G01X1299412D02*
X1299427D01*
G01X1299328D02*
X1299343D01*
G01X1299446D02*
X1299540D01*
G01X1299693D02*
X1299707D01*
G01X1299931D02*
X1299941D01*
G01X1300013D02*
X1300027D01*
G01X1300145D02*
X1300167D01*
G01X1300369D02*
X1300391D01*
G01X1300500D02*
X1300559D01*
G01X1300706D02*
X1300728D01*
G01X1300610D02*
X1300633D01*
G01X1300790D02*
X1300800D01*
G01X1300856D02*
X1300915D01*
G01X1300982D02*
X1300997D01*
G01X1301017D02*
X1301076D01*
G01X1301228D02*
X1301233D01*
G01X1301294D02*
X1301388D01*
G01X1296722Y79074D02*
X1296821D01*
G01X1296378D02*
X1296452D01*
G01X1302756Y80314D02*
X1296457D01*
G01X1298228D02*
X1295079D01*
G01X1300984D02*
X1304134D01*
G01X1279695Y81032D02*
X1280395D01*
G01Y81249D02*
X1279695D01*
G01X1280395Y81344D02*
X1279695D01*
G01X1280395Y81406D02*
X1279695D01*
G01X1280395Y81505D02*
X1279695D01*
G01X1280395Y82489D02*
X1279695D01*
G01X1280395Y82587D02*
X1279695D01*
G01X1280395Y82650D02*
X1279695D01*
G01X1280395Y82745D02*
X1279695D01*
G01Y82961D02*
X1280395D01*
G01X1289411Y89474D02*
X1290411D01*
G01Y90474D02*
X1289411D01*
G01X1285892Y92474D02*
X1290411D01*
G01X1291593Y94974D02*
X1290411D01*
G01X1279695Y95993D02*
X1280395D01*
G01Y96209D02*
X1279695D01*
G01X1280395Y96305D02*
X1279695D01*
G01X1280395Y96367D02*
X1279695D01*
G01X1280395Y96465D02*
X1279695D01*
G01X1290411Y96942D02*
X1291593D01*
G01Y96974D02*
X1290199D01*
G01X1280395Y97449D02*
X1279695D01*
G01X1280395Y97548D02*
X1279695D01*
G01X1280395Y97610D02*
X1279695D01*
G01X1280395Y97705D02*
X1279695D01*
G01Y97922D02*
X1280395D01*
G01X1289411Y104974D02*
X1290199D01*
G01X1289593Y105169D02*
X1290199D01*
G01Y105191D02*
X1290411D01*
G01Y105464D02*
X1289411D01*
G01X1301233Y78975D02*
X1301250Y78973D01*
G01X1299941Y78975D02*
X1299956Y78973D01*
G01X1300800Y78975D02*
X1300815Y78973D01*
G01X1301250Y78910D02*
X1301235Y78912D01*
G01X1289331Y92474D02*
X1289377Y92466D01*
X1289403Y92439D01*
X1289411Y92394D01*
G01X1299028Y78973D02*
X1299016Y78975D01*
G01X1299274D02*
X1299287Y78973D01*
G01X1299752Y78903D02*
X1299764Y78900D01*
G01X1299789Y78973D02*
X1299776Y78975D01*
G01X1299951Y78960D02*
X1299939Y78963D01*
G01X1300285Y78930D02*
X1300273Y78932D01*
G01X1300167Y78975D02*
X1300180Y78973D01*
G01X1300283D02*
X1300271Y78975D01*
G01X1300391D02*
X1300404Y78973D01*
G01X1300559Y78975D02*
X1300571Y78973D01*
G01X1301211Y78872D02*
X1301223Y78870D01*
G01X1300810Y78960D02*
X1300797Y78963D01*
G01X1300915Y78975D02*
X1300928Y78973D01*
G01X1301076Y78975D02*
X1301088Y78973D01*
G01X1301248Y78960D02*
X1301235Y78963D01*
G01X1300359Y78875D02*
X1300369Y78872D01*
G01X1300177Y78958D02*
X1300167Y78960D01*
G01X1299242Y78875D02*
X1299252Y78872D01*
G01X1299284Y78958D02*
X1299274Y78960D01*
G01X1300135Y78875D02*
X1300145Y78872D01*
G01X1300401Y78958D02*
X1300391Y78960D01*
G01X1299026D02*
X1299019Y78963D01*
G01X1299764Y78870D02*
X1299757Y78872D01*
G01X1299754Y78915D02*
X1299761Y78912D01*
G01X1299786Y78960D02*
X1299779Y78963D01*
G01X1300251Y78872D02*
X1300259Y78870D01*
G01X1300283Y78918D02*
X1300276Y78920D01*
G01X1300273Y78963D02*
X1300281Y78960D01*
G01X1300561Y78910D02*
X1300569Y78907D01*
G01Y78958D02*
X1300561Y78960D01*
G01X1300925D02*
X1300918Y78963D01*
G01X1301078Y78910D02*
X1301085Y78907D01*
G01Y78958D02*
X1301078Y78960D01*
G01X1301255Y78918D02*
X1301267Y78912D01*
G01X1299287Y78973D02*
X1299296Y78968D01*
G01X1299956Y78973D02*
X1299966Y78968D01*
G01X1300180Y78973D02*
X1300190Y78968D01*
G01X1300404Y78973D02*
X1300413Y78968D01*
G01X1300576Y78918D02*
X1300581Y78915D01*
G01X1300815Y78973D02*
X1300824Y78968D01*
G01X1301093Y78918D02*
X1301098Y78915D01*
G01X1301206Y78875D02*
X1301211Y78872D01*
G01X1301250Y78973D02*
X1301260Y78968D01*
G01X1291789Y78891D02*
X1290411Y79687D01*
G01X1299739Y78910D02*
X1299752Y78903D01*
G01X1299801Y78965D02*
X1299789Y78973D01*
G01X1300298Y78923D02*
X1300285Y78930D01*
G01X1300295Y78965D02*
X1300283Y78973D01*
G01X1299235Y78880D02*
X1299242Y78875D01*
G01X1299291Y78953D02*
X1299284Y78958D01*
G01X1299757Y78872D02*
X1299749Y78877D01*
G01X1299747Y78920D02*
X1299754Y78915D01*
G01X1299793Y78955D02*
X1299786Y78960D01*
G01X1300054Y78882D02*
X1300047Y78887D01*
G01X1299958Y78955D02*
X1299951Y78960D01*
G01X1300128Y78880D02*
X1300135Y78875D01*
G01X1300079Y78950D02*
X1300086Y78945D01*
G01X1300244Y78877D02*
X1300251Y78872D01*
G01X1300185Y78953D02*
X1300177Y78958D01*
G01X1300291Y78912D02*
X1300283Y78918D01*
G01X1300352Y78880D02*
X1300359Y78875D01*
G01X1300281Y78960D02*
X1300288Y78955D01*
G01X1300409Y78953D02*
X1300401Y78958D01*
G01X1300817Y78955D02*
X1300810Y78960D01*
G01X1301135Y78882D02*
X1301127Y78887D01*
G01X1301159Y78950D02*
X1301167Y78945D01*
G01X1301257Y78905D02*
X1301250Y78910D01*
G01X1301255Y78955D02*
X1301248Y78960D01*
G01X1299038Y78965D02*
X1299028Y78973D01*
G01X1300571D02*
X1300581Y78965D01*
G01X1300928Y78973D02*
X1300938Y78965D01*
G01X1301088Y78973D02*
X1301098Y78965D01*
G01X1290411Y94974D02*
X1290199Y95186D01*
G01X1300569Y78907D02*
X1300574Y78903D01*
G01Y78953D02*
X1300569Y78958D01*
G01X1301085Y78907D02*
X1301090Y78903D01*
G01Y78953D02*
X1301085Y78958D01*
G01X1299031Y78955D02*
X1299026Y78960D01*
G01X1299296Y78968D02*
X1299306Y78958D01*
G01X1299966Y78968D02*
X1299976Y78958D01*
G01X1300190Y78968D02*
X1300200Y78958D01*
G01X1300295Y78907D02*
X1300291Y78912D01*
G01X1300305Y78915D02*
X1300298Y78923D01*
G01X1300413Y78968D02*
X1300423Y78958D01*
G01X1300824Y78968D02*
X1300834Y78958D01*
G01X1300930Y78955D02*
X1300925Y78960D01*
G01X1301201Y78880D02*
X1301206Y78875D01*
G01X1301260Y78968D02*
X1301270Y78958D01*
G01X1299045Y78955D02*
X1299038Y78965D01*
G01X1299732Y78920D02*
X1299739Y78910D01*
G01X1299808Y78955D02*
X1299801Y78965D01*
G01X1300303Y78955D02*
X1300295Y78965D01*
G01X1300581Y78915D02*
X1300588Y78905D01*
G01X1300581Y78965D02*
X1300588Y78955D01*
G01X1300938Y78965D02*
X1300945Y78955D01*
G01X1301098Y78915D02*
X1301105Y78905D01*
G01X1301098Y78965D02*
X1301105Y78955D01*
G01X1299230Y78887D02*
X1299235Y78880D01*
G01X1299749Y78877D02*
X1299744Y78885D01*
G01X1299742Y78927D02*
X1299747Y78920D01*
G01X1299798Y78947D02*
X1299793Y78955D01*
G01X1299963Y78947D02*
X1299958Y78955D01*
G01X1300123Y78887D02*
X1300128Y78880D01*
G01X1300239Y78885D02*
X1300244Y78877D01*
G01X1300288Y78955D02*
X1300293Y78947D01*
G01X1300347Y78887D02*
X1300352Y78880D01*
G01X1300822Y78947D02*
X1300817Y78955D01*
G01X1301194Y78870D02*
X1301189Y78877D01*
G01X1301267Y78912D02*
X1301272Y78905D01*
G01X1301260Y78947D02*
X1301255Y78955D01*
G01X1299220Y78875D02*
X1299215Y78885D01*
G01X1300113Y78875D02*
X1300108Y78885D01*
G01X1300337Y78875D02*
X1300332Y78885D01*
G01X1301198D02*
X1301201Y78880D01*
G01X1301263Y78895D02*
X1301257Y78905D01*
G01X1299727Y78932D02*
X1299732Y78920D01*
G01X1299813Y78943D02*
X1299808Y78955D01*
G01X1300224Y78890D02*
X1300229Y78877D01*
G01X1300310Y78903D02*
X1300305Y78915D01*
G01X1300633Y78975D02*
X1300669Y78870D01*
G01X1298745Y78975D02*
X1298780Y78872D01*
G01X1299033Y78947D02*
X1299031Y78955D01*
G01X1299048Y78947D02*
X1299045Y78955D01*
G01X1299294Y78945D02*
X1299291Y78953D01*
G01X1299732Y78885D02*
X1299734Y78877D01*
G01X1299739Y78935D02*
X1299742Y78927D01*
G01X1299801Y78940D02*
X1299798Y78947D01*
G01X1300187Y78945D02*
X1300185Y78953D01*
G01X1300236Y78892D02*
X1300239Y78885D01*
G01X1300298Y78900D02*
X1300295Y78907D01*
G01X1300305Y78947D02*
X1300303Y78955D01*
G01X1300411Y78945D02*
X1300409Y78953D01*
G01X1300574Y78903D02*
X1300576Y78895D01*
G01X1300588Y78905D02*
X1300591Y78897D01*
G01X1300576Y78945D02*
X1300574Y78953D01*
G01X1300588Y78955D02*
X1300591Y78947D01*
G01X1300933D02*
X1300930Y78955D01*
G01X1300945D02*
X1300948Y78947D01*
G01X1301090Y78903D02*
X1301093Y78895D01*
G01X1301105Y78905D02*
X1301107Y78897D01*
G01X1301093Y78945D02*
X1301090Y78953D01*
G01X1301105Y78955D02*
X1301107Y78947D01*
G01X1301189Y78877D02*
X1301186Y78885D01*
G01X1299019Y78925D02*
X1299026Y78927D01*
G01X1299761Y78963D02*
X1299754Y78960D01*
G01X1299779Y78912D02*
X1299786Y78915D01*
G01Y78872D02*
X1299779Y78870D01*
G01X1300251Y78960D02*
X1300259Y78963D01*
G01Y78920D02*
X1300251Y78918D01*
G01X1300276Y78870D02*
X1300283Y78872D01*
G01X1300561Y78925D02*
X1300569Y78927D01*
G01Y78875D02*
X1300561Y78872D01*
G01X1300918Y78925D02*
X1300925Y78927D01*
G01X1301078Y78925D02*
X1301085Y78927D01*
G01Y78875D02*
X1301078Y78872D01*
G01X1301235Y78923D02*
X1301250Y78927D01*
G01X1299228Y78897D02*
X1299230Y78887D01*
G01X1299976Y78958D02*
X1299978Y78947D01*
G01X1300121Y78897D02*
X1300123Y78887D01*
G01X1300344Y78897D02*
X1300347Y78887D01*
G01X1300834Y78958D02*
X1300837Y78947D01*
G01X1301272Y78905D02*
X1301275Y78895D01*
G01X1301270Y78958D02*
X1301272Y78947D01*
G01X1299215Y78885D02*
X1299213Y78897D01*
G01X1299306Y78958D02*
X1299309Y78945D01*
G01X1300108Y78885D02*
X1300106Y78897D01*
G01X1300200Y78958D02*
X1300202Y78945D01*
G01X1300332Y78885D02*
X1300330Y78897D01*
G01X1300423Y78958D02*
X1300426Y78945D01*
G01X1278516Y106958D02*
Y105958D01*
G01X1278608D02*
Y106958D01*
G01X1278869D02*
Y105958D01*
G01X1278872Y105171D02*
Y106958D01*
G01X1279094Y105958D02*
Y106958D01*
G01X1279146Y105958D02*
Y106958D01*
G01X1279553Y105958D02*
Y106958D01*
G01X1279695Y81034D02*
Y82960D01*
G01Y95994D02*
Y97920D01*
G01X1280395Y81034D02*
Y82960D01*
G01Y95995D02*
Y97921D01*
G01X1280537Y106958D02*
Y105958D01*
G01X1280869Y106958D02*
Y105958D01*
G01X1280949D02*
Y106958D01*
G01X1281000Y105958D02*
Y106958D01*
G01X1281482Y105958D02*
Y106958D01*
G01X1281579Y105958D02*
Y106958D01*
G01X1281620Y105171D02*
Y102336D01*
G01X1281869Y106958D02*
Y105958D01*
G01X1282387Y106958D02*
Y105958D01*
G01X1283730D02*
Y106958D01*
G01X1284490Y107942D02*
Y106958D01*
G01X1284892Y104171D02*
Y93474D01*
G01X1285490Y107942D02*
Y106958D01*
G01X1286765Y105171D02*
Y92474D01*
G01X1287715Y105958D02*
Y106958D01*
G01X1288215Y105958D02*
Y106958D01*
G01X1288715D02*
Y105958D01*
G01X1299028Y78915D02*
X1299038Y78920D01*
G01X1299230Y78968D02*
X1299240Y78973D01*
G01X1299904Y78968D02*
X1299914Y78973D01*
G01X1300123Y78968D02*
X1300133Y78973D01*
G01X1300347Y78968D02*
X1300357Y78973D01*
G01X1300581Y78920D02*
X1300576Y78918D01*
G01X1300763Y78968D02*
X1300773Y78973D01*
G01X1301098Y78920D02*
X1301093Y78918D01*
G01X1301201Y78968D02*
X1301211Y78973D01*
G01X1301250Y78872D02*
X1301255Y78875D01*
G01X1299816Y78925D02*
X1299813Y78943D01*
G01X1300222Y78907D02*
X1300224Y78890D01*
G01X1289215Y105958D02*
Y106958D01*
G01X1290199Y95186D02*
Y105753D01*
G01X1291593Y104958D02*
Y94974D01*
G01X1298637Y78912D02*
Y78872D01*
G01Y78960D02*
Y78927D01*
G01X1298701D02*
Y78912D01*
G01X1298711Y78975D02*
Y78960D01*
G01X1298863Y78912D02*
Y78872D01*
G01Y78960D02*
Y78927D01*
G01X1298927D02*
Y78912D01*
G01X1298937Y78975D02*
Y78960D01*
G01X1298972Y78963D02*
Y78925D01*
G01X1299033Y78940D02*
Y78947D01*
G01X1299048Y78938D02*
Y78947D01*
G01X1299085Y78975D02*
Y78872D01*
G01X1299213Y78897D02*
Y78935D01*
G01X1299228D02*
Y78897D01*
G01X1299272Y78907D02*
Y78923D01*
G01X1299294Y78887D02*
Y78907D01*
G01X1299309Y78923D02*
Y78885D01*
G01X1299343Y78975D02*
Y78927D01*
G01X1299412D02*
Y78975D01*
G01X1299446Y78963D02*
Y78975D01*
G01X1299540D02*
Y78963D01*
G01X1299678Y78938D02*
Y78958D01*
G01X1299727Y78943D02*
Y78932D01*
G01X1299739Y78940D02*
Y78935D01*
G01X1299801D02*
Y78940D01*
G01X1299803Y78912D02*
Y78907D01*
G01X1299816D02*
Y78925D01*
G01X1299835Y78900D02*
Y78912D01*
G01X1299870D02*
Y78900D01*
G01X1299963Y78943D02*
Y78947D01*
G01X1299978D02*
Y78943D01*
G01X1299998Y78938D02*
Y78958D01*
G01X1300106Y78897D02*
Y78935D01*
G01X1300121D02*
Y78897D01*
G01X1300165Y78907D02*
Y78923D01*
G01X1300187Y78887D02*
Y78907D01*
G01X1300202Y78923D02*
Y78885D01*
G01X1300222Y78925D02*
Y78907D01*
G01X1300234Y78920D02*
Y78925D01*
G01X1300236Y78900D02*
Y78892D01*
G01X1300298D02*
Y78900D01*
G01X1300310Y78890D02*
Y78903D01*
G01X1300330Y78897D02*
Y78935D01*
G01X1300344D02*
Y78897D01*
G01X1300446Y78900D02*
Y78912D01*
G01X1300480D02*
Y78900D01*
G01X1300515Y78960D02*
Y78925D01*
G01Y78872D02*
Y78910D01*
G01X1300576Y78895D02*
Y78887D01*
G01Y78940D02*
Y78945D01*
G01X1300591Y78947D02*
Y78938D01*
G01Y78897D02*
Y78885D01*
G01X1300822Y78943D02*
Y78947D01*
G01X1300837D02*
Y78943D01*
G01X1300871Y78963D02*
Y78925D01*
G01X1300933Y78940D02*
Y78947D01*
G01X1300948D02*
Y78938D01*
G01X1300967D02*
Y78958D01*
G01X1301031Y78960D02*
Y78925D01*
G01Y78872D02*
Y78910D01*
G01X1301093Y78895D02*
Y78887D01*
G01Y78940D02*
Y78945D01*
G01X1301107Y78947D02*
Y78938D01*
G01Y78897D02*
Y78885D01*
G01X1301226Y78912D02*
Y78923D01*
G01X1301260Y78943D02*
Y78947D01*
G01X1301263Y78885D02*
Y78895D01*
G01X1301272Y78947D02*
Y78943D01*
G01X1301275Y78895D02*
Y78885D01*
G01X1301294Y78963D02*
Y78975D01*
G01X1301388D02*
Y78963D01*
G01X1299813Y78890D02*
X1299816Y78907D01*
G01X1300224Y78943D02*
X1300222Y78925D01*
G01X1300938Y78920D02*
X1300928Y78912D01*
G01X1301265Y78925D02*
X1301255Y78918D01*
G01X1299242Y78958D02*
X1299235Y78953D01*
G01X1299284Y78875D02*
X1299291Y78880D01*
G01X1299754Y78960D02*
X1299747Y78955D01*
G01X1299786Y78915D02*
X1299793Y78920D01*
G01X1299789Y78903D02*
X1299803Y78912D01*
G01X1299793Y78877D02*
X1299786Y78872D01*
G01X1299917Y78960D02*
X1299909Y78955D01*
G01X1300135Y78958D02*
X1300128Y78953D01*
G01X1300244Y78955D02*
X1300251Y78960D01*
G01X1300249Y78930D02*
X1300234Y78920D01*
G01X1300177Y78875D02*
X1300185Y78880D01*
G01X1300251Y78918D02*
X1300244Y78912D01*
G01X1300359Y78958D02*
X1300352Y78953D01*
G01X1300283Y78872D02*
X1300291Y78877D01*
G01X1300401Y78875D02*
X1300409Y78880D01*
G01X1300775Y78960D02*
X1300768Y78955D01*
G01X1301213Y78960D02*
X1301206Y78955D01*
G01X1299752Y78973D02*
X1299739Y78965D01*
G01X1300249Y78973D02*
X1300236Y78965D01*
G01X1299803Y78907D02*
X1299801Y78892D01*
G01X1300234Y78925D02*
X1300236Y78940D01*
G01X1299213Y78935D02*
X1299215Y78947D01*
G01X1300106Y78935D02*
X1300108Y78947D01*
G01X1300330Y78935D02*
X1300332Y78947D01*
G01X1300426Y78887D02*
X1300423Y78875D01*
G01X1299230Y78945D02*
X1299228Y78935D01*
G01X1299309Y78885D02*
X1299306Y78875D01*
G01X1299892Y78947D02*
X1299894Y78958D01*
G01X1299978Y78943D02*
X1299976Y78932D01*
G01X1300123Y78945D02*
X1300121Y78935D01*
G01X1300202Y78885D02*
X1300200Y78875D01*
G01X1300347Y78945D02*
X1300344Y78935D01*
G01X1300751Y78947D02*
X1300753Y78958D01*
G01X1300837Y78943D02*
X1300834Y78932D01*
G01X1301189Y78947D02*
X1301191Y78958D01*
G01X1301272Y78943D02*
X1301270Y78932D01*
G01X1299031D02*
X1299033Y78940D01*
G01X1299045Y78930D02*
X1299048Y78938D01*
G01X1299291Y78880D02*
X1299294Y78887D01*
G01X1299742Y78947D02*
X1299739Y78940D01*
G01X1299798Y78927D02*
X1299801Y78935D01*
G01Y78892D02*
X1299798Y78885D01*
G01X1300185Y78880D02*
X1300187Y78887D01*
G01X1300236Y78940D02*
X1300239Y78947D01*
G01Y78907D02*
X1300236Y78900D01*
G01X1300295Y78885D02*
X1300298Y78892D01*
G01X1300409Y78880D02*
X1300411Y78887D01*
G01X1300574Y78932D02*
X1300576Y78940D01*
G01X1300591Y78938D02*
X1300588Y78930D01*
G01X1300576Y78887D02*
X1300574Y78880D01*
G01X1300591Y78885D02*
X1300588Y78877D01*
G01X1300930Y78932D02*
X1300933Y78940D01*
G01X1300948Y78938D02*
X1300945Y78930D01*
G01X1301090Y78932D02*
X1301093Y78940D01*
G01X1301107Y78938D02*
X1301105Y78930D01*
G01X1301093Y78887D02*
X1301090Y78880D01*
G01X1301107Y78885D02*
X1301105Y78877D01*
G01X1301275Y78885D02*
X1301272Y78877D01*
G01X1298780Y78872D02*
X1298814Y78975D01*
G01X1300669Y78870D02*
X1300706Y78975D01*
G01X1299732Y78955D02*
X1299727Y78943D01*
G01X1299808Y78877D02*
X1299813Y78890D01*
G01X1300229Y78955D02*
X1300224Y78943D01*
G01X1300305Y78877D02*
X1300310Y78890D01*
G01X1299215Y78947D02*
X1299220Y78958D01*
G01X1299958Y78932D02*
X1299963Y78943D01*
G01X1300108Y78947D02*
X1300113Y78958D01*
G01X1300332Y78947D02*
X1300337Y78958D01*
G01X1300817Y78932D02*
X1300822Y78943D01*
G01X1301255Y78932D02*
X1301260Y78943D01*
G01Y78880D02*
X1301263Y78885D01*
G01X1300047Y78887D02*
X1300079Y78950D01*
G01X1300086Y78945D02*
X1300054Y78882D01*
G01X1301127Y78887D02*
X1301159Y78950D01*
G01X1301167Y78945D02*
X1301135Y78882D01*
G01X1299235Y78953D02*
X1299230Y78945D01*
G01X1299747Y78955D02*
X1299742Y78947D01*
G01X1299793Y78920D02*
X1299798Y78927D01*
G01Y78885D02*
X1299793Y78877D01*
G01X1299909Y78955D02*
X1299904Y78947D01*
G01X1299976Y78932D02*
X1299970Y78925D01*
G01X1300128Y78953D02*
X1300123Y78945D01*
G01X1300239Y78947D02*
X1300244Y78955D01*
G01X1300291Y78877D02*
X1300295Y78885D01*
G01X1300352Y78953D02*
X1300347Y78945D01*
G01X1300768Y78955D02*
X1300763Y78947D01*
G01X1300834Y78932D02*
X1300830Y78925D01*
G01X1301206Y78955D02*
X1301201Y78947D01*
G01X1301270Y78932D02*
X1301265Y78925D01*
G01X1301272Y78877D02*
X1301267Y78870D01*
G01X1299038Y78920D02*
X1299045Y78930D01*
G01X1299739Y78965D02*
X1299732Y78955D01*
G01X1300236Y78965D02*
X1300229Y78955D01*
G01X1300588Y78930D02*
X1300581Y78920D01*
G01X1300945Y78930D02*
X1300938Y78920D01*
G01X1301105Y78930D02*
X1301098Y78920D01*
G01X1299678Y78958D02*
X1299693Y78975D01*
G01Y78955D02*
X1299678Y78938D01*
G01X1299998Y78958D02*
X1300013Y78975D01*
G01Y78955D02*
X1299998Y78938D01*
G01X1300967Y78958D02*
X1300982Y78975D01*
G01Y78955D02*
X1300967Y78938D01*
G01X1299026Y78927D02*
X1299031Y78932D01*
G01X1299220Y78958D02*
X1299230Y78968D01*
G01X1299894Y78958D02*
X1299904Y78968D01*
G01X1300113Y78958D02*
X1300123Y78968D01*
G01X1300244Y78912D02*
X1300239Y78907D01*
G01X1300337Y78958D02*
X1300347Y78968D01*
G01X1300569Y78927D02*
X1300574Y78932D01*
G01Y78880D02*
X1300569Y78875D01*
G01X1300753Y78958D02*
X1300763Y78968D01*
G01X1300925Y78927D02*
X1300930Y78932D01*
G01X1301085Y78927D02*
X1301090Y78932D01*
G01Y78880D02*
X1301085Y78875D01*
G01X1301191Y78958D02*
X1301201Y78968D01*
G01X1301250Y78927D02*
X1301255Y78932D01*
G01Y78875D02*
X1301260Y78880D01*
G01X1299889Y78870D02*
X1299958Y78932D01*
G01X1300748Y78870D02*
X1300817Y78932D01*
G01X1299970Y78925D02*
X1299909Y78870D01*
G01X1300830Y78925D02*
X1300768Y78870D01*
G01X1291593Y104958D02*
G03X1289593Y106958I-2000J0D01*
G01X1290184Y106869D02*
G03X1288411Y107942I-1772J-927D01*
G01X1284892Y93474D02*
G03X1285892Y92474I1000J0D01*
G01Y105171D02*
G03X1284892Y104171I0J-1000D01*
G01X1289411Y105549D02*
G03X1289324Y105958I-1000J1D01*
G01X1290199Y105753D02*
G03X1289593Y105958I-607J-795D01*
G01X1301250Y78860D02*
X1301240Y78857D01*
G01X1301088Y78860D02*
X1301076Y78857D01*
G01X1300571Y78860D02*
X1300559Y78857D01*
G01X1300404Y78860D02*
X1300391Y78857D01*
G01X1300273D02*
X1300285Y78860D01*
G01X1300180D02*
X1300167Y78857D01*
G01X1299776D02*
X1299789Y78860D01*
G01X1299287D02*
X1299274Y78857D01*
G01X1290411Y73970D02*
X1291789D01*
G01Y76923D02*
X1290411D01*
G01X1304134Y77164D02*
X1300984D01*
G01X1295079D02*
X1298228D01*
G01X1296457D02*
X1302756D01*
G01X1296821Y78483D02*
X1296722D01*
G01X1296452D02*
X1296378D01*
G01X1300027Y78857D02*
X1300013D01*
G01X1300167D02*
X1300145D01*
G01X1300391D02*
X1300369D01*
G01X1300559D02*
X1300500D01*
G01X1300728D02*
X1300714D01*
G01X1300625D02*
X1300610D01*
G01X1300679D02*
X1300659D01*
G01X1300837D02*
X1300748D01*
G01X1300871D02*
X1300856D01*
G01X1300997D02*
X1300982D01*
G01X1301076D02*
X1301017D01*
G01X1301240D02*
X1301220D01*
G01X1301348D02*
X1301334D01*
G01X1298711D02*
X1298622D01*
G01X1298789D02*
X1298770D01*
G01X1298937D02*
X1298848D01*
G01X1299159D02*
X1299070D01*
G01X1299193D02*
X1299178D01*
G01X1299274D02*
X1299252D01*
G01X1299427D02*
X1299412D01*
G01X1299343D02*
X1299328D01*
G01X1299501D02*
X1299486D01*
G01X1299707D02*
X1299693D01*
G01X1299978D02*
X1299889D01*
G01X1299033D02*
X1299050D01*
G01X1298957D02*
X1298972D01*
G01X1299767D02*
X1299776D01*
G01X1300261D02*
X1300273D01*
G01X1299252D02*
X1299240Y78860D01*
G01X1299754D02*
X1299767Y78857D01*
G01X1300145D02*
X1300133Y78860D01*
G01X1300249D02*
X1300261Y78857D01*
G01X1300369D02*
X1300357Y78860D01*
G01X1301220Y78857D02*
X1301211Y78860D01*
G01X1299240D02*
X1299230Y78865D01*
G01X1300133Y78860D02*
X1300123Y78865D01*
G01X1300357Y78860D02*
X1300347Y78865D01*
G01X1301211Y78860D02*
X1301201Y78865D01*
G01X1299742Y78867D02*
X1299754Y78860D01*
G01X1300236Y78867D02*
X1300249Y78860D01*
G01X1301201Y78865D02*
X1301194Y78870D01*
G01X1299230Y78865D02*
X1299220Y78875D01*
G01X1300123Y78865D02*
X1300113Y78875D01*
G01X1300347Y78865D02*
X1300337Y78875D01*
G01X1299734Y78877D02*
X1299742Y78867D01*
G01X1300229Y78877D02*
X1300236Y78867D01*
G01X1296722Y78483D02*
X1296538Y78772D01*
G01X1296600Y78835D02*
X1296821Y78483D01*
G01X1299050Y78857D02*
X1299028Y78915D01*
G01X1299013Y78910D02*
X1299033Y78857D01*
G01X1300659D02*
X1300625Y78950D01*
G01X1298770Y78857D02*
X1298730Y78975D01*
G01X1299296Y78865D02*
X1299287Y78860D01*
G01X1300190Y78865D02*
X1300180Y78860D01*
G01X1300413Y78865D02*
X1300404Y78860D01*
G01X1301260Y78865D02*
X1301250Y78860D01*
G01X1295079Y80314D02*
Y77164D01*
G01X1296378Y78483D02*
Y79074D01*
G01X1296452Y78684D02*
Y78483D01*
G01Y79074D02*
Y78785D01*
G01X1296457Y80314D02*
Y77164D01*
G01X1297244D02*
Y80314D01*
G01X1297408D02*
Y77164D01*
G01X1298228D02*
Y80314D01*
G01X1298622Y78857D02*
Y78975D01*
G01X1298711Y78872D02*
Y78857D01*
G01X1298848D02*
Y78975D01*
G01X1298937Y78872D02*
Y78857D01*
G01X1298957Y78975D02*
Y78857D01*
G01X1298972D02*
Y78910D01*
G01X1299070Y78857D02*
Y78975D01*
G01X1299159Y78872D02*
Y78857D01*
G01X1299178D02*
Y78975D01*
G01X1299193D02*
Y78857D01*
G01X1299328D02*
Y78975D01*
G01X1299343Y78912D02*
Y78857D01*
G01X1299412D02*
Y78912D01*
G01X1299427Y78975D02*
Y78857D01*
G01X1299486D02*
Y78963D01*
G01X1299501D02*
Y78857D01*
G01X1299693D02*
Y78955D01*
G01X1299707Y78975D02*
Y78857D01*
G01X1299889D02*
Y78870D01*
G01X1299978D02*
Y78857D01*
G01X1300013D02*
Y78955D01*
G01X1300027Y78975D02*
Y78857D01*
G01X1300500D02*
Y78975D01*
G01X1300610Y78857D02*
Y78975D01*
G01X1300625Y78950D02*
Y78857D01*
G01X1300714D02*
Y78950D01*
G01X1300728Y78975D02*
Y78857D01*
G01X1300748D02*
Y78870D01*
G01X1300837D02*
Y78857D01*
G01X1300856D02*
Y78975D01*
G01X1300871Y78910D02*
Y78857D01*
G01X1300982D02*
Y78955D01*
G01X1300984Y77164D02*
Y80314D01*
G01X1300997Y78975D02*
Y78857D01*
G01X1301017D02*
Y78975D01*
G01X1301334Y78857D02*
Y78963D01*
G01X1301348D02*
Y78857D01*
G01X1301805Y77164D02*
Y80314D01*
G01X1301969Y77164D02*
Y80314D01*
G01X1300581Y78867D02*
X1300571Y78860D01*
G01X1301098Y78867D02*
X1301088Y78860D01*
G01X1301267Y78870D02*
X1301260Y78865D01*
G01X1299789Y78860D02*
X1299801Y78867D01*
G01X1300285Y78860D02*
X1300298Y78867D01*
G01X1298829Y78975D02*
X1298789Y78857D01*
G01X1300714Y78950D02*
X1300679Y78857D01*
G01X1299801Y78867D02*
X1299808Y78877D01*
G01X1300298Y78867D02*
X1300305Y78877D01*
G01X1300588D02*
X1300581Y78867D01*
G01X1301105Y78877D02*
X1301098Y78867D01*
G01X1296821Y79074D02*
X1296600Y78835D01*
G01X1296452Y78785D02*
X1296722Y79074D01*
G01X1296538Y78772D02*
X1296452Y78684D01*
G01X1299306Y78875D02*
X1299296Y78865D01*
G01X1300200Y78875D02*
X1300190Y78865D01*
G01X1300423Y78875D02*
X1300413Y78865D01*
G01X1289411Y77628D02*
X1287427Y75643D01*
G01X1380315Y118109D02*
X1306102D01*
G01X1288411Y107942D02*
X1284490D01*
G01X1313287Y883464D02*
X1311122D01*
G01X1306988D02*
X1304823D01*
G01X1310138D02*
X1307972D01*
G01X1303839Y892519D02*
Y883464D01*
G01X1304823D02*
Y892519D01*
G01X1306988D02*
Y883464D01*
G01X1307972D02*
Y892519D01*
G01X1310138D02*
Y883464D01*
G01X1311122D02*
Y892519D01*
G01X1303839Y883464D02*
X1301673D01*
G01X1297539D02*
X1295374D01*
G01X1300689D02*
X1298524D01*
G01X1294390D02*
X1292224D01*
G01X1288091D02*
X1285925D01*
G01X1291240D02*
X1289075D01*
G01X1284941D02*
X1282776D01*
G01X1281791D02*
X1279626D01*
G01X1278642Y892519D02*
Y883464D01*
G01X1279626D02*
Y892519D01*
G01X1281791D02*
Y883464D01*
G01X1282776D02*
Y892519D01*
G01X1284941D02*
Y883464D01*
G01X1285925D02*
Y892519D01*
G01X1288091D02*
Y883464D01*
G01X1289075D02*
Y892519D01*
G01X1291240D02*
Y883464D01*
G01X1292224D02*
Y892519D01*
G01X1294390D02*
Y883464D01*
G01X1295374D02*
Y892519D01*
G01X1297539D02*
Y883464D01*
G01X1298524D02*
Y892519D01*
G01X1300689D02*
Y883464D01*
G01X1301673D02*
Y892519D01*
G01X1304823D02*
X1306988D01*
G01X1307972D02*
X1310138D01*
G01X1311122D02*
X1313287D01*
G01X1279626D02*
X1281791D01*
G01X1282776D02*
X1284941D01*
G01X1285925D02*
X1288091D01*
G01X1289075D02*
X1291240D01*
G01X1292224D02*
X1294390D01*
G01X1295374D02*
X1297539D01*
G01X1298524D02*
X1300689D01*
G01X1301673D02*
X1303839D01*
G01X1283288Y2171102D02*
Y2152090D01*
G01X1317337Y-682078D02*
Y-615149D01*
G01X1339229Y-613003D02*
X1338507Y-612516D01*
X1337785Y-611541D01*
Y-610567D01*
X1338507Y-609592D01*
X1339229Y-609105D01*
X1340672D01*
X1341394Y-609592D01*
G01X1339229Y-605208D02*
X1338507Y-604720D01*
X1337785Y-603746D01*
Y-602771D01*
X1338507Y-601797D01*
X1339229Y-601310D01*
X1340672D01*
X1341394Y-601797D01*
X1342116Y-602771D01*
X1342838Y-603746D01*
X1344281Y-604720D01*
X1346447Y-605208D01*
Y-601310D01*
G01X1341394Y-609592D02*
X1342838Y-611541D01*
X1344281Y-612516D01*
X1346447Y-613003D01*
Y-609105D01*
G01X1317337Y-548220D02*
Y-615149D01*
G01X1315171D02*
Y-615636D01*
X1314450D01*
X1315171Y-615149D01*
G01X1346447Y-579873D02*
X1345725Y-580847D01*
X1345003Y-581334D01*
X1343559Y-581822D01*
X1340672D01*
X1339229Y-581334D01*
X1338507Y-580847D01*
X1337785Y-579873D01*
X1338507Y-578899D01*
X1339229Y-578411D01*
X1340672Y-577924D01*
X1343559D01*
X1345003Y-578411D01*
X1345725Y-578899D01*
X1346447Y-579873D01*
G01Y-587668D02*
X1345725Y-588643D01*
X1345003Y-589130D01*
X1343559Y-589617D01*
X1340672D01*
X1339229Y-589130D01*
X1338507Y-588643D01*
X1337785Y-587668D01*
X1338507Y-586694D01*
X1339229Y-586207D01*
X1340672Y-585720D01*
X1343559D01*
X1345003Y-586207D01*
X1345725Y-586694D01*
X1346447Y-587668D01*
G01X1314875Y-400157D02*
X1313901Y-399435D01*
X1313413Y-398714D01*
X1312926Y-397270D01*
Y-394383D01*
X1313413Y-392939D01*
X1313901Y-392218D01*
X1314875Y-391496D01*
X1315850Y-392218D01*
X1316337Y-392939D01*
X1316824Y-394383D01*
Y-397270D01*
X1316337Y-398714D01*
X1315850Y-399435D01*
X1314875Y-400157D01*
G01X1329331Y-112634D02*
X1330774Y-113608D01*
X1331496Y-114582D01*
Y-115557D01*
X1330774Y-116531D01*
X1330053Y-117018D01*
G01X1323557Y-116531D02*
X1322835Y-115557D01*
Y-114582D01*
X1323557Y-113608D01*
X1324278Y-113121D01*
X1325000D01*
X1325722Y-113608D01*
X1326444Y-114582D01*
X1327166Y-113608D01*
G01X1326444Y-123352D02*
Y-122378D01*
G01Y-115557D02*
Y-114582D01*
G01X1331496Y-99479D02*
Y-99966D01*
X1330774D01*
X1331496Y-99479D01*
G01X1326444Y-107762D02*
X1325722Y-108736D01*
X1325000Y-109223D01*
X1324278D01*
X1323557Y-108736D01*
X1322835Y-107762D01*
Y-106787D01*
X1323557Y-105812D01*
X1324278Y-105325D01*
X1325000D01*
X1325722Y-105812D01*
X1326444Y-106787D01*
G01X1331496Y-107762D02*
X1330774Y-108736D01*
X1330053Y-109223D01*
X1329331Y-109710D01*
X1328609D01*
X1327887Y-109223D01*
X1327166Y-108736D01*
X1326444Y-107762D01*
Y-106787D01*
X1327166Y-105812D01*
X1327887Y-105325D01*
X1328609Y-104838D01*
X1329331D01*
X1330053Y-105325D01*
X1330774Y-105812D01*
X1331496Y-106787D01*
Y-107762D01*
G01X1327166Y-113608D02*
X1328609Y-112634D01*
X1329331D01*
G01X1323557Y-124327D02*
X1322835Y-123352D01*
Y-122378D01*
X1323557Y-121403D01*
X1324278Y-120916D01*
X1325000D01*
X1325722Y-121403D01*
X1326444Y-122378D01*
X1327166Y-121403D01*
X1327887Y-120916D01*
X1328609Y-120429D01*
X1329331D01*
X1330053Y-120916D01*
X1330774Y-121403D01*
X1331496Y-122378D01*
Y-123352D01*
X1330774Y-124327D01*
X1330053Y-124814D01*
G01X1333661Y51968D02*
Y-75660D01*
G01X1322835Y-81940D02*
Y-84863D01*
X1326444Y-85350D01*
X1325722Y-84376D01*
Y-83401D01*
X1326444Y-82427D01*
X1327166Y-81940D01*
X1328609Y-81453D01*
X1330053Y-81940D01*
X1330774Y-82427D01*
X1331496Y-83401D01*
Y-84376D01*
X1330774Y-85350D01*
X1330053Y-85837D01*
G01X1331496Y-91684D02*
X1327887Y-91196D01*
X1325722Y-90709D01*
X1324278Y-90222D01*
X1322835Y-89735D01*
Y-93632D01*
G01X1344987Y5812D02*
X1345774Y5008D01*
G01X1344462Y6884D02*
X1344987Y5812D01*
G01X1335538Y3936D02*
X1333963D01*
G01X1326614D02*
X1325039D01*
G01D02*
Y16534D01*
G01X1326614Y9833D02*
Y3936D01*
G01X1333963D02*
Y9833D01*
G01X1335538Y16534D02*
Y3936D01*
G01X1396063Y-1D02*
X1313976D01*
G01D02*
Y110235D01*
G01X1341837Y11442D02*
X1337638D01*
G01Y12514D02*
X1341837D01*
G01X1337638Y11442D02*
Y12514D01*
G01X1341837D02*
Y11442D01*
G01X1344200Y12782D02*
X1343937Y11442D01*
G01X1344462Y13586D02*
X1344200Y12782D01*
G01X1344987Y14658D02*
X1344462Y13586D01*
G01X1345774Y15462D02*
X1344987Y14658D01*
G01X1346562Y14390D02*
X1345512Y12782D01*
G01X1341837Y8225D02*
X1337638D01*
G01Y9297D02*
X1341837D01*
G01X1345512Y7689D02*
X1346562Y6080D01*
G01X1344200Y7689D02*
X1344462Y6884D01*
G01X1343937Y9029D02*
X1344200Y7689D01*
G01X1345250Y9297D02*
X1345512Y7689D01*
G01X1337638Y8225D02*
Y9297D01*
G01X1341837D02*
Y8225D01*
G01X1343937Y11442D02*
Y9029D01*
G01X1345250Y11173D02*
Y9297D01*
G01X1345512Y12782D02*
X1345250Y11173D01*
G01X1326614Y11442D02*
X1333963D01*
G01X1325039Y16534D02*
X1326614D01*
G01X1333963D02*
X1335538D01*
G01X1326614D02*
Y11442D01*
G01X1333963D02*
Y16534D01*
G01Y9833D02*
X1326614D01*
G01X1337598Y55905D02*
X1462241D01*
G01X1339961Y55904D02*
G03I-6299J0D01*
G01D02*
G03I-6299J0D01*
G01X1313976Y94842D02*
X1329370Y110235D01*
G01X1376378Y135826D02*
G03I-15748J0D01*
G01X1313976Y110235D02*
X1400000D01*
G01X1376378Y801180D02*
G03I-15748J0D01*
G01X1344783Y883464D02*
X1342618D01*
G01X1341634D02*
X1339469D01*
G01X1338484D02*
X1336319D01*
G01D02*
Y892519D01*
G01X1338484D02*
Y883464D01*
G01X1339469D02*
Y892519D01*
G01X1341634D02*
Y883464D01*
G01X1342618D02*
Y892519D01*
G01X1344783D02*
Y883464D01*
G01X1335335D02*
X1333169D01*
G01X1332185D02*
X1330020D01*
G01X1325886D02*
X1323720D01*
G01X1329035D02*
X1326870D01*
G01X1322736D02*
X1320571D01*
G01X1316437D02*
X1314272D01*
G01X1319587D02*
X1317421D01*
G01X1313287Y892519D02*
Y883464D01*
G01X1314272D02*
Y892519D01*
G01X1316437D02*
Y883464D01*
G01X1317421D02*
Y892519D01*
G01X1319587D02*
Y883464D01*
G01X1320571D02*
Y892519D01*
G01X1322736D02*
Y883464D01*
G01X1323720D02*
Y892519D01*
G01X1325886D02*
Y883464D01*
G01X1326870D02*
Y892519D01*
G01X1329035D02*
Y883464D01*
G01X1330020D02*
Y892519D01*
G01X1332185D02*
Y883464D01*
G01X1333169D02*
Y892519D01*
G01X1335335D02*
Y883464D01*
G01X1336319Y892519D02*
X1338484D01*
G01X1339469D02*
X1341634D01*
G01X1342618D02*
X1344783D01*
G01X1314272D02*
X1316437D01*
G01X1317421D02*
X1319587D01*
G01X1320571D02*
X1322736D01*
G01X1323720D02*
X1325886D01*
G01X1326870D02*
X1329035D01*
G01X1330020D02*
X1332185D01*
G01X1333169D02*
X1335335D01*
G01X1348612Y-682078D02*
Y-595464D01*
G01Y-508849D02*
Y-595464D01*
G01X1346447D02*
Y-595951D01*
X1345725D01*
X1346447Y-595464D01*
G01X1369751Y-136994D02*
X1371194Y-138943D01*
X1372638Y-139917D01*
X1374803Y-140404D01*
Y-136507D01*
G01Y-132121D02*
X1369029Y-129198D01*
G01X1367585Y-140404D02*
X1366864Y-139917D01*
X1366142Y-138943D01*
Y-137968D01*
X1366864Y-136994D01*
X1367585Y-136507D01*
X1369029D01*
X1369751Y-136994D01*
G01X1369029Y-132121D02*
X1374803Y-129198D01*
G01X1369751Y-123352D02*
Y-122378D01*
G01X1374803Y-99479D02*
Y-99966D01*
X1374081D01*
X1374803Y-99479D01*
G01Y-113608D02*
X1366142D01*
X1372638Y-117018D01*
Y-112634D01*
G01X1369029Y-105325D02*
X1370472Y-105812D01*
X1371194Y-107274D01*
X1370472Y-108736D01*
X1369029Y-109223D01*
X1367585Y-108736D01*
X1366864Y-108249D01*
X1366142Y-107274D01*
X1366864Y-106300D01*
X1367585Y-105812D01*
X1369029Y-105325D01*
X1371916D01*
X1373360Y-105812D01*
X1374081Y-106300D01*
X1374803Y-107274D01*
X1374081Y-108249D01*
X1373360Y-108736D01*
G01X1366864Y-124327D02*
X1366142Y-123352D01*
Y-122378D01*
X1366864Y-121403D01*
X1367585Y-120916D01*
X1368307D01*
X1369029Y-121403D01*
X1369751Y-122378D01*
X1370472Y-121403D01*
X1371194Y-120916D01*
X1371916Y-120429D01*
X1372638D01*
X1373360Y-120916D01*
X1374081Y-121403D01*
X1374803Y-122378D01*
Y-123352D01*
X1374081Y-124327D01*
X1373360Y-124814D01*
G01X1376969Y17322D02*
Y-75660D01*
G01X1366142Y-81940D02*
Y-84863D01*
X1369751Y-85350D01*
X1369029Y-84376D01*
Y-83401D01*
X1369751Y-82427D01*
X1370472Y-81940D01*
X1371916Y-81453D01*
X1373360Y-81940D01*
X1374081Y-82427D01*
X1374803Y-83401D01*
Y-84376D01*
X1374081Y-85350D01*
X1373360Y-85837D01*
G01X1374803Y-91684D02*
X1371194Y-91196D01*
X1369029Y-90709D01*
X1367585Y-90222D01*
X1366142Y-89735D01*
Y-93632D01*
G01X1377008Y3936D02*
X1375696D01*
G01X1372809D02*
X1371496D01*
G01D02*
Y10369D01*
G01X1372809D02*
Y3936D01*
G01X1375696D02*
Y10369D01*
G01X1377008D02*
Y3936D01*
G01X1348661Y5276D02*
X1349974Y5544D01*
G01X1348661Y3936D02*
X1350236Y4204D01*
G01X1368609Y3936D02*
X1367297D01*
G01X1365197D02*
X1363885D01*
G01X1360998D02*
X1359685D01*
G01X1356798D02*
X1355486D01*
G01X1347087Y4204D02*
X1348661Y3936D01*
G01X1347349Y5544D02*
X1348661Y5276D01*
G01X1345774Y5008D02*
X1347087Y4204D01*
G01X1346562Y6080D02*
X1347349Y5544D01*
G01X1355486Y3936D02*
Y12514D01*
G01X1356798Y10637D02*
Y3936D01*
G01X1359685D02*
Y10369D01*
G01X1360998D02*
Y3936D01*
G01X1363885D02*
Y10369D01*
G01X1365197D02*
Y3936D01*
G01X1367297D02*
Y12514D01*
G01X1368609Y10637D02*
Y3936D01*
G01X1350236Y4204D02*
X1351549Y5008D01*
G01D02*
X1352336Y5812D01*
G01X1349974Y5544D02*
X1350761Y6080D01*
G01X1352336Y5812D02*
X1352861Y6884D01*
G01X1350761Y6080D02*
X1351811Y7689D01*
G01X1351535Y-1D02*
X1370947Y19410D01*
G01X1374646Y11442D02*
X1373858D01*
G01X1370446D02*
X1369921D01*
G01Y12514D02*
X1370971D01*
G01X1374121D02*
X1375171D01*
G01X1370971D02*
X1371759Y12245D01*
G01X1375171Y12514D02*
X1375958Y12245D01*
G01X1371759D02*
X1372546Y11442D01*
G01X1375958Y12245D02*
X1376483Y11709D01*
G01X1373333Y12245D02*
X1374121Y12514D01*
G01X1372546Y11442D02*
X1373333Y12245D01*
G01X1383268Y21259D02*
G03I-6299J0D01*
G01X1378817Y27280D02*
X1394685Y43149D01*
G01X1383268Y21259D02*
G03I-6299J0D01*
G01X1370971Y11173D02*
X1370446Y11442D01*
G01X1375171Y11173D02*
X1374646Y11442D01*
G01X1371234Y10905D02*
X1370971Y11173D01*
G01X1375433Y10905D02*
X1375171Y11173D01*
G01X1371496Y10369D02*
X1371234Y10905D01*
G01X1375696Y10369D02*
X1375433Y10905D01*
G01X1376483Y11709D02*
X1377008Y10369D01*
G01X1373858Y11442D02*
X1373333Y11173D01*
G01X1373071Y10905D02*
X1372809Y10369D01*
G01X1373333Y11173D02*
X1373071Y10905D01*
G01X1348661Y15194D02*
X1347349Y14926D01*
G01X1348661Y16534D02*
X1347087Y16266D01*
G01X1362835Y11442D02*
X1362047D01*
G01X1358635D02*
X1358110D01*
G01X1355486Y12514D02*
X1356798D01*
G01X1358110D02*
X1359160D01*
G01X1362310D02*
X1363360D01*
G01X1367297D02*
X1368609D01*
G01X1350236Y16266D02*
X1348661Y16534D01*
G01X1349974Y14926D02*
X1348661Y15194D01*
G01X1359160Y12514D02*
X1359948Y12245D01*
G01X1363360Y12514D02*
X1364147Y12245D01*
G01X1351549Y15462D02*
X1350236Y16266D01*
G01X1350761Y14390D02*
X1349974Y14926D01*
G01X1352336Y14658D02*
X1351549Y15462D01*
G01X1359948Y12245D02*
X1360735Y11442D01*
G01X1364147Y12245D02*
X1364672Y11709D01*
G01X1351811Y12782D02*
X1350761Y14390D01*
G01X1352861Y13586D02*
X1352336Y14658D01*
G01X1353124Y12782D02*
X1352861Y13586D01*
G01X1353386Y11442D02*
X1353124Y12782D01*
G01X1357323Y12245D02*
X1358110Y12514D01*
G01X1361522Y12245D02*
X1362310Y12514D01*
G01X1369134Y12245D02*
X1369921Y12514D01*
G01X1356798D02*
Y11709D01*
G01X1368609Y12514D02*
Y11709D01*
G01X1347349Y14926D02*
X1346562Y14390D01*
G01X1347087Y16266D02*
X1345774Y15462D01*
G01X1356798Y11709D02*
X1357323Y12245D01*
G01X1360735Y11442D02*
X1361522Y12245D01*
G01X1368609Y11709D02*
X1369134Y12245D01*
G01X1359160Y11173D02*
X1358635Y11442D01*
G01X1363360Y11173D02*
X1362835Y11442D01*
G01X1359423Y10905D02*
X1359160Y11173D01*
G01X1363622Y10905D02*
X1363360Y11173D01*
G01X1359685Y10369D02*
X1359423Y10905D01*
G01X1363885Y10369D02*
X1363622Y10905D01*
G01X1364672Y11709D02*
X1365197Y10369D01*
G01X1352074Y11173D02*
X1351811Y12782D01*
G01X1358110Y11442D02*
X1357323Y11173D01*
G01X1369921Y11442D02*
X1369134Y11173D01*
G01X1352074Y9297D02*
Y11173D01*
G01X1353386Y9029D02*
Y11442D01*
G01X1362047D02*
X1361522Y11173D01*
G01X1351811Y7689D02*
X1352074Y9297D01*
G01X1353124Y7689D02*
X1353386Y9029D01*
G01X1352861Y6884D02*
X1353124Y7689D01*
G01X1357323Y11173D02*
X1356798Y10637D01*
G01X1361522Y11173D02*
X1361260Y10905D01*
G01D02*
X1360998Y10369D01*
G01X1369134Y11173D02*
X1368609Y10637D01*
G01X1383268Y90550D02*
G03I-6299J0D01*
G01D02*
G03I-6299J0D01*
G01X1367218Y139369D02*
X1464787Y191839D01*
G01X1368110Y135826D02*
G03I-7480J0D01*
G01D02*
G03I-7480J0D01*
G01X1369382Y148918D02*
X1435798Y248267D01*
G01X1371422Y789711D02*
X1423783Y734066D01*
G01X1367870Y799298D02*
X1455172Y776601D01*
G01X1368110Y801180D02*
G03I-7480J0D01*
G01D02*
G03I-7480J0D01*
G01X1368504Y840550D02*
X1396063D01*
G01X1363386Y845668D02*
Y871653D01*
G01Y845668D02*
Y871653D01*
G01Y845668D02*
G03X1368504Y840550I5118J0D01*
G01X1363386Y845668D02*
G03X1368504Y840550I5118J0D01*
G01X1352431Y881279D02*
X1352677Y881572D01*
G01Y881237D02*
X1352431Y880944D01*
G01X1361417Y873621D02*
X1358268D01*
G01X1361417D02*
X1358268D01*
G01X1353990Y880944D02*
X1353661D01*
G01X1352431D02*
X1352185D01*
G01X1353457Y882242D02*
X1354195D01*
G01X1353415Y882410D02*
X1354236D01*
G01X1354400Y882912D02*
X1354646D01*
G01X1353006D02*
X1353252D01*
G01X1352185D02*
X1352431D01*
G01X1354232Y883464D02*
X1352067D01*
G01X1351083D02*
X1348917D01*
G01X1347933D02*
X1345768D01*
G01X1354236Y882410D02*
X1354400Y882912D01*
G01X1354195Y882242D02*
X1353826Y881111D01*
G01X1354646Y882912D02*
X1353990Y880944D01*
G01X1345768Y883464D02*
Y892519D01*
G01X1347933D02*
Y883464D01*
G01X1348917D02*
Y892519D01*
G01X1351083D02*
Y883464D01*
G01X1352067D02*
Y892519D01*
G01X1352185Y880944D02*
Y882912D01*
G01X1352431D02*
Y881279D01*
G01X1352677Y881572D02*
Y881237D01*
G01X1354232Y892519D02*
Y883464D01*
G01X1356299Y892519D02*
Y875590D01*
G01D02*
Y892519D01*
G01X1353661Y880944D02*
X1353006Y882912D01*
G01X1353826Y881111D02*
X1353457Y882242D01*
G01X1353252Y882912D02*
X1353415Y882410D01*
G01X1363386Y871653D02*
G03X1361417Y873621I-1969J-1D01*
G01X1356299Y875590D02*
G03X1358268Y873621I1969J0D01*
G01X1363386Y871653D02*
G03X1361417Y873621I-1969J-1D01*
G01X1356299Y875590D02*
G03X1358268Y873621I1969J0D01*
G01X1345768Y892519D02*
X1347933D01*
G01X1348917D02*
X1351083D01*
G01X1352067D02*
X1354232D01*
G01X1352362Y897637D02*
X1356299Y892519D01*
G01X1352362Y897637D02*
X1356299Y892519D01*
G01X1398311Y-1128215D02*
X1397599Y-1130117D01*
X1395460Y-1131067D01*
X1393321Y-1130117D01*
X1392608Y-1128215D01*
X1393321Y-1126314D01*
X1394034Y-1125364D01*
X1395460Y-1124413D01*
X1396886Y-1125364D01*
X1397599Y-1126314D01*
X1398311Y-1128215D01*
Y-1132018D01*
X1397599Y-1133919D01*
X1396886Y-1134870D01*
X1395460Y-1135820D01*
X1394034Y-1134870D01*
X1393321Y-1133919D01*
G01X1389174Y-105325D02*
Y-108249D01*
X1392782Y-108736D01*
X1392061Y-107762D01*
Y-106787D01*
X1392782Y-105812D01*
X1393504Y-105325D01*
X1394948Y-104838D01*
X1396391Y-105325D01*
X1397113Y-105812D01*
X1397835Y-106787D01*
Y-107762D01*
X1397113Y-108736D01*
X1396391Y-109223D01*
G01X1389174Y-113121D02*
Y-116044D01*
X1392782Y-116531D01*
X1392061Y-115557D01*
Y-114582D01*
X1392782Y-113608D01*
X1393504Y-113121D01*
X1394948Y-112634D01*
X1396391Y-113121D01*
X1397113Y-113608D01*
X1397835Y-114582D01*
Y-115557D01*
X1397113Y-116531D01*
X1396391Y-117018D01*
G01X1392782Y-123352D02*
Y-122378D01*
G01X1397835Y-99479D02*
Y-99966D01*
X1397113D01*
X1397835Y-99479D01*
G01X1389895Y-124327D02*
X1389174Y-123352D01*
Y-122378D01*
X1389895Y-121403D01*
X1390617Y-120916D01*
X1391339D01*
X1392061Y-121403D01*
X1392782Y-122378D01*
X1393504Y-121403D01*
X1394226Y-120916D01*
X1394948Y-120429D01*
X1395669D01*
X1396391Y-120916D01*
X1397113Y-121403D01*
X1397835Y-122378D01*
Y-123352D01*
X1397113Y-124327D01*
X1396391Y-124814D01*
G01X1400000Y-15749D02*
Y-75660D01*
G01X1397835Y-83888D02*
X1397113Y-84863D01*
X1396391Y-85350D01*
X1394948Y-85837D01*
X1392061D01*
X1390617Y-85350D01*
X1389895Y-84863D01*
X1389174Y-83888D01*
X1389895Y-82914D01*
X1390617Y-82427D01*
X1392061Y-81940D01*
X1394948D01*
X1396391Y-82427D01*
X1397113Y-82914D01*
X1397835Y-83888D01*
G01X1394948Y-93632D02*
X1393504Y-93145D01*
X1392782Y-91684D01*
X1393504Y-90222D01*
X1394948Y-89735D01*
X1396391Y-90222D01*
X1397113Y-90709D01*
X1397835Y-91684D01*
X1397113Y-92658D01*
X1396391Y-93145D01*
X1394948Y-93632D01*
X1392061D01*
X1390617Y-93145D01*
X1389895Y-92658D01*
X1389174Y-91684D01*
X1389895Y-90709D01*
X1390617Y-90222D01*
G01X1390693Y4743D02*
X1470650Y-52236D01*
G01X1400000Y3936D02*
Y36219D01*
G01Y3936D02*
Y36219D01*
G01X1396063Y-1D02*
G03X1400000Y3936I0J3937D01*
G01X1396063Y-1D02*
G03X1400000Y3936I0J3937D01*
G01D02*
Y36219D01*
G01X1396063Y-1D02*
G03X1400000Y3936I0J3937D01*
G01X1380906Y21259D02*
X1462241D01*
G01X1401969Y38188D02*
X1462241D01*
G01X1398031D02*
X1396654D01*
G01X1398031D02*
X1396654D01*
G01X1394685Y71653D02*
Y40156D01*
G01Y71653D02*
Y40156D01*
G01X1400000Y36219D02*
G03X1398031Y38188I-1968J1D01*
G01X1394685Y40156D02*
G03X1396654Y38188I1969J1D01*
G01X1400000Y36219D02*
G03X1398031Y38188I-1968J1D01*
G01X1394685Y40156D02*
G03X1396654Y38188I1969J1D01*
G01X1398031D02*
X1396654D01*
G01X1394685Y71653D02*
Y40156D01*
G01X1400000Y36219D02*
G03X1398031Y38188I-1968J1D01*
G01X1394685Y40156D02*
G03X1396654Y38188I1969J1D01*
G01X1401969Y73621D02*
X1462241D01*
G01X1398031D02*
X1396654D01*
G01X1398031D02*
X1396654D01*
G01X1398031D02*
G03X1400000Y75590I1J1968D01*
G01X1396654Y73621D02*
G03X1394685Y71653I0J-1969D01*
G01X1396654Y73621D02*
G03X1394685Y71653I0J-1969D01*
G01X1398031Y73621D02*
G03X1400000Y75590I1J1968D01*
G01X1398031Y73621D02*
X1396654D01*
G01X1398031D02*
G03X1400000Y75590I1J1968D01*
G01X1396654Y73621D02*
G03X1394685Y71653I0J-1969D01*
G01X1387205Y90550D02*
X1462241D01*
G01X1400000Y75590D02*
Y836613D01*
G01Y75590D02*
Y836613D01*
G01Y110235D02*
Y75590D01*
G01X1380315Y137794D02*
X1400000D01*
G01X1380315Y118109D02*
Y137794D01*
G01X1384252Y840550D02*
Y303149D01*
G01X1397677Y495786D02*
X1385866D01*
G01Y497263D02*
X1390641D01*
G01X1392149D02*
X1397677D01*
G01Y504153D02*
X1392149D01*
G01X1390641D02*
X1385866D01*
G01Y505629D02*
X1397677D01*
G01X1390641Y507597D02*
X1389636D01*
G01X1393657D02*
X1392651D01*
G01X1389636Y511534D02*
X1390641D01*
G01X1392651D02*
X1393657D01*
G01X1385866Y495786D02*
Y497263D01*
G01Y504153D02*
Y505629D01*
G01X1389636Y507597D02*
Y511534D01*
G01X1390641D02*
Y507597D01*
G01Y497263D02*
Y504153D01*
G01X1392149D02*
Y497263D01*
G01X1392651Y507597D02*
Y511534D01*
G01X1393657D02*
Y507597D01*
G01X1397677Y505629D02*
Y504153D01*
G01Y497263D02*
Y495786D01*
G01X1390641Y522361D02*
X1389385Y522115D01*
G01X1390892Y521131D02*
X1389385Y520885D01*
G01X1392651Y521131D02*
X1390892D01*
G01X1392903Y522361D02*
X1390641D01*
G01X1397677Y524330D02*
X1389636D01*
G01Y525560D02*
X1390390D01*
G01X1391395D02*
X1397677D01*
G01Y528267D02*
X1391646D01*
G01Y529497D02*
X1397677D01*
G01Y532204D02*
X1391646D01*
G01Y533434D02*
X1397677D01*
G01Y535403D02*
X1389636D01*
G01Y536633D02*
X1390390D01*
G01X1391395D02*
X1397677D01*
G01Y539340D02*
X1391646D01*
G01Y540570D02*
X1397677D01*
G01Y543277D02*
X1391646D01*
G01Y544507D02*
X1397677D01*
G01X1390390Y544015D02*
X1391646Y544507D01*
G01X1390390Y532942D02*
X1391646Y533434D01*
G01X1389385Y522115D02*
X1388631Y521869D01*
G01X1391646Y543277D02*
X1391144Y543030D01*
G01X1391646Y539340D02*
X1391144Y539093D01*
G01X1391646Y532204D02*
X1391144Y531958D01*
G01X1391646Y528267D02*
X1391144Y528021D01*
G01X1388631Y521869D02*
X1387626Y521377D01*
G01X1394159Y520885D02*
X1392651Y521131D01*
G01X1394159Y522115D02*
X1392903Y522361D01*
G01X1389385Y520885D02*
X1387877Y519901D01*
G01X1394913Y521869D02*
X1394159Y522115D01*
G01X1389887Y543523D02*
X1390390Y544015D01*
G01X1391144Y543030D02*
X1390892Y542784D01*
G01X1389887Y539586D02*
X1390641Y540324D01*
G01X1391144Y539093D02*
X1390892Y538847D01*
G01X1389887Y532450D02*
X1390390Y532942D01*
G01X1391144Y531958D02*
X1390892Y531712D01*
G01X1389887Y528513D02*
X1390641Y529251D01*
G01X1391144Y528021D02*
X1390892Y527775D01*
G01X1387626Y521377D02*
X1386872Y520639D01*
G01X1395918Y521377D02*
X1394913Y521869D01*
G01X1391144Y529743D02*
X1391646Y529497D01*
G01X1391144Y540816D02*
X1391646Y540570D01*
G01X1395667Y519901D02*
X1394159Y520885D01*
G01X1387877Y519901D02*
X1387374Y519162D01*
G01X1390892Y542784D02*
X1390641Y542292D01*
G01X1390892Y538847D02*
X1390641Y538355D01*
G01X1390892Y531712D02*
X1390641Y531219D01*
G01X1390892Y527775D02*
X1390641Y527282D01*
G01X1386872Y520639D02*
X1386118Y519408D01*
G01X1390390Y525560D02*
X1389887Y526052D01*
G01X1390892D02*
X1391395Y525560D01*
G01X1396672Y520639D02*
X1395918Y521377D01*
G01X1390641Y529251D02*
X1389887Y529989D01*
G01X1390892D02*
X1391144Y529743D01*
G01X1390390Y536633D02*
X1389887Y537125D01*
G01X1390892D02*
X1391395Y536633D01*
G01X1390641Y540324D02*
X1389887Y541062D01*
G01X1390892D02*
X1391144Y540816D01*
G01X1389636Y542784D02*
X1389887Y543523D01*
G01X1389636Y538847D02*
X1389887Y539586D01*
G01X1389636Y531712D02*
X1389887Y532450D01*
G01X1389636Y527775D02*
X1389887Y528513D01*
G01X1396170Y519162D02*
X1395667Y519901D01*
G01X1397426Y519408D02*
X1396672Y520639D01*
G01X1389636Y524330D02*
Y525560D01*
G01Y526790D02*
Y527775D01*
G01Y530727D02*
Y531712D01*
G01Y535403D02*
Y536633D01*
G01Y537863D02*
Y538847D01*
G01Y541800D02*
Y542784D01*
G01X1390641Y542292D02*
Y541554D01*
G01Y538355D02*
Y537863D01*
G01Y531219D02*
Y530481D01*
G01Y527282D02*
Y526790D01*
G01X1397677Y544507D02*
Y543277D01*
G01Y540570D02*
Y539340D01*
G01Y536633D02*
Y535403D01*
G01Y533434D02*
Y532204D01*
G01Y529497D02*
Y528267D01*
G01Y525560D02*
Y524330D01*
G01X1386118Y519408D02*
X1385866Y517932D01*
G01X1387374Y519162D02*
X1387123Y517932D01*
G01X1390641Y530481D02*
X1390892Y529989D01*
G01X1390641Y541554D02*
X1390892Y541062D01*
G01X1389887Y526052D02*
X1389636Y526790D01*
G01X1390641D02*
X1390892Y526052D01*
G01X1389887Y529989D02*
X1389636Y530727D01*
G01X1389887Y537125D02*
X1389636Y537863D01*
G01X1390641D02*
X1390892Y537125D01*
G01X1389887Y541062D02*
X1389636Y541800D01*
G01X1396421Y517932D02*
X1396170Y519162D01*
G01X1397677Y517932D02*
X1397426Y519408D01*
G01X1392903Y513503D02*
X1394159Y513749D01*
G01X1392651Y514733D02*
X1394159Y514979D01*
G01X1390641Y513503D02*
X1392903D01*
G01X1390892Y514733D02*
X1392651D01*
G01X1394159Y513749D02*
X1394913Y513995D01*
G01D02*
X1395918Y514487D01*
G01X1389385Y514979D02*
X1390892Y514733D01*
G01X1389385Y513749D02*
X1390641Y513503D01*
G01X1388631Y513995D02*
X1389385Y513749D01*
G01X1394159Y514979D02*
X1395667Y515964D01*
G01X1387626Y514487D02*
X1388631Y513995D01*
G01X1395918Y514487D02*
X1396672Y515225D01*
G01X1387877Y515964D02*
X1389385Y514979D01*
G01X1395667Y515964D02*
X1396170Y516702D01*
G01X1396672Y515225D02*
X1397426Y516456D01*
G01X1386872Y515225D02*
X1387626Y514487D01*
G01X1387374Y516702D02*
X1387877Y515964D01*
G01X1386118Y516456D02*
X1386872Y515225D01*
G01X1397426Y516456D02*
X1397677Y517932D01*
G01X1396170Y516702D02*
X1396421Y517932D01*
G01X1387123D02*
X1387374Y516702D01*
G01X1385866Y517932D02*
X1386118Y516456D01*
G01X1400000Y836613D02*
G03X1396063Y840550I-3937J0D01*
G01X1400000Y836613D02*
G03X1396063Y840550I-3937J0D01*
G01X1398311Y2163497D02*
X1397599Y2161596D01*
X1395460Y2160645D01*
X1393321Y2161596D01*
X1392608Y2163497D01*
X1393321Y2165399D01*
X1394034Y2166349D01*
X1395460Y2167300D01*
X1396886Y2166349D01*
X1397599Y2165399D01*
X1398311Y2163497D01*
Y2159695D01*
X1397599Y2157793D01*
X1396886Y2156843D01*
X1395460Y2155892D01*
X1394034Y2156843D01*
X1393321Y2157793D01*
G01X1424617Y-120429D02*
X1425339D01*
X1426783Y-121403D01*
G01X1424617Y-104838D02*
X1425339D01*
X1426783Y-105812D01*
G01X1424617Y-117018D02*
X1423174Y-116531D01*
X1422452Y-115070D01*
X1423174Y-113608D01*
X1424617Y-113121D01*
X1426061Y-113608D01*
X1426783Y-114095D01*
X1427504Y-115070D01*
X1426783Y-116044D01*
X1426061Y-116531D01*
X1424617Y-117018D01*
X1421730D01*
X1420287Y-116531D01*
X1419565Y-116044D01*
X1418843Y-115070D01*
X1419565Y-114095D01*
X1420287Y-113608D01*
G01X1419565Y-108736D02*
X1418843Y-107762D01*
Y-106787D01*
X1419565Y-105812D01*
X1420287Y-105325D01*
X1421009D01*
X1421730Y-105812D01*
X1422452Y-106787D01*
X1423174Y-105812D01*
X1424617Y-104838D01*
G01X1426783Y-105812D02*
X1427504Y-106787D01*
Y-107762D01*
X1426783Y-108736D01*
X1426061Y-109223D01*
G01X1422452Y-123352D02*
Y-122378D01*
G01Y-107762D02*
Y-106787D01*
G01X1427504Y-99479D02*
Y-99966D01*
X1426783D01*
X1427504Y-99479D01*
G01X1419565Y-124327D02*
X1418843Y-123352D01*
Y-122378D01*
X1419565Y-121403D01*
X1420287Y-120916D01*
X1421009D01*
X1421730Y-121403D01*
X1422452Y-122378D01*
X1423174Y-121403D01*
X1424617Y-120429D01*
G01X1426783Y-121403D02*
X1427504Y-122378D01*
Y-123352D01*
X1426783Y-124327D01*
X1426061Y-124814D01*
G01X1429670Y-51182D02*
Y-75660D01*
G01X1427504Y-82427D02*
X1418843D01*
X1425339Y-85837D01*
Y-81453D01*
G01X1418843Y-91684D02*
X1427504D01*
G01X1413150Y-4063D02*
X1531526Y-25973D01*
G01X1420824Y108327D02*
X1507893Y178248D01*
G01X1438947Y248267D02*
X1623724D01*
G01X1435798D02*
X1438947D01*
G01X1439979Y731901D02*
X1439004Y730457D01*
X1438517Y728292D01*
Y726848D01*
X1439004Y724683D01*
X1439979Y723239D01*
G01X1445338D02*
Y731901D01*
X1449236Y723239D01*
Y731901D01*
G01X1423783Y734066D02*
X1426933D01*
G01D02*
X1611709D01*
G01X1436316D02*
X1443533Y747058D01*
G01X1435594Y740562D02*
X1436316Y742727D01*
X1437759Y744171D01*
X1439924Y744893D01*
X1442090Y744171D01*
X1443533Y742727D01*
X1444256Y740562D01*
X1443533Y738397D01*
X1442090Y736953D01*
X1439924Y736231D01*
X1437759Y736953D01*
X1436316Y738397D01*
X1435594Y740562D01*
G01X1429670Y897637D02*
X1477748D01*
G01X1470650Y-52236D02*
X1482461D01*
G01X1478265Y23424D02*
X1477778D01*
Y24146D01*
X1478265Y23424D01*
G01X1472419Y32086D02*
X1469495D01*
X1469008Y28477D01*
X1469982Y29198D01*
X1470957D01*
X1471931Y28477D01*
X1472419Y27755D01*
X1472906Y26311D01*
X1472419Y24868D01*
X1471931Y24146D01*
X1470957Y23424D01*
X1469982D01*
X1469008Y24146D01*
X1468520Y24868D01*
G01X1479726Y58070D02*
Y66731D01*
X1476316Y60235D01*
X1480701D01*
G01X1478265Y40353D02*
X1477778D01*
Y41075D01*
X1478265Y40353D01*
G01X1470469Y66731D02*
Y58070D01*
G01X1472419Y46127D02*
X1471931Y44684D01*
X1470469Y43962D01*
X1469008Y44684D01*
X1468520Y46127D01*
X1469008Y47571D01*
X1469495Y48293D01*
X1470469Y49015D01*
X1471444Y48293D01*
X1471931Y47571D01*
X1472419Y46127D01*
Y43240D01*
X1471931Y41797D01*
X1471444Y41075D01*
X1470469Y40353D01*
X1469495Y41075D01*
X1469008Y41797D01*
G01X1477778Y97768D02*
X1478752D01*
G01X1477778Y80839D02*
X1476803Y81561D01*
X1476316Y82282D01*
Y83004D01*
X1476803Y83726D01*
X1477778Y84448D01*
X1478752D01*
X1479726Y83726D01*
X1480214Y83004D01*
Y82282D01*
X1479726Y81561D01*
X1478752Y80839D01*
G01X1479726Y97046D02*
X1480701Y95603D01*
Y94881D01*
G01X1476803Y100655D02*
X1477778Y101377D01*
X1478752D01*
X1479726Y100655D01*
X1480214Y99933D01*
Y99212D01*
X1479726Y98490D01*
X1478752Y97768D01*
X1479726Y97046D01*
G01X1480701Y94881D02*
X1479726Y93437D01*
X1478752Y92716D01*
X1477778D01*
X1476803Y93437D01*
X1476316Y94159D01*
G01X1477778Y75786D02*
X1476803Y76508D01*
X1475829Y77952D01*
G01X1476803Y80117D02*
X1477778Y80839D01*
X1478752D01*
X1479726Y80117D01*
X1480214Y79395D01*
X1480701Y78673D01*
Y77952D01*
X1480214Y77230D01*
X1479726Y76508D01*
X1478752Y75786D01*
X1477778D01*
G01X1475829Y77952D02*
Y78673D01*
X1476803Y80117D01*
G01X1471931Y97768D02*
X1469982Y96324D01*
X1469008Y94881D01*
X1468520Y92716D01*
X1472419D01*
G01X1468520Y99933D02*
X1469008Y100655D01*
X1469982Y101377D01*
X1470957D01*
X1471931Y100655D01*
X1472419Y99933D01*
Y98490D01*
X1471931Y97768D01*
G01X1470469Y84448D02*
Y75786D01*
G01X1476598Y198335D02*
X1477320Y200500D01*
X1478763Y201944D01*
X1480929Y202666D01*
X1483094Y201944D01*
X1484538Y200500D01*
X1485259Y198335D01*
X1484538Y196169D01*
X1483094Y194726D01*
X1480929Y194004D01*
X1478763Y194726D01*
X1477320Y196169D01*
X1476598Y198335D01*
G01X1477320Y191839D02*
X1484538Y204831D01*
G01X1464787Y191839D02*
X1467937D01*
G01D02*
X1574761D01*
G01X1457353Y237440D02*
Y246102D01*
X1461250Y237440D01*
Y246102D01*
G01X1451993D02*
X1451019Y244658D01*
X1450532Y242493D01*
Y241049D01*
X1451019Y238884D01*
X1451993Y237440D01*
G01X1469046Y239606D02*
X1468071Y238162D01*
X1467097Y237440D01*
X1466122Y238162D01*
X1465148Y239606D01*
Y241049D01*
X1466122Y242493D01*
X1467097Y243215D01*
X1468071Y242493D01*
X1469046Y241049D01*
Y239606D01*
G01X1478645Y250432D02*
X1477671Y251154D01*
X1477184Y251876D01*
X1476696Y253319D01*
Y256207D01*
X1477184Y257651D01*
X1477671Y258372D01*
X1478645Y259094D01*
X1479620Y258372D01*
X1480107Y257651D01*
X1480594Y256207D01*
Y253319D01*
X1480107Y251876D01*
X1479620Y251154D01*
X1478645Y250432D01*
G01X1480251Y246102D02*
X1485123D01*
G01X1470850Y250432D02*
X1470363D01*
Y251154D01*
X1470850Y250432D01*
G01X1462568D02*
X1461593Y251154D01*
X1461106Y251876D01*
X1460619Y252598D01*
Y253319D01*
X1461106Y254042D01*
X1461593Y254763D01*
X1462568Y255485D01*
X1463542D01*
X1464517Y254763D01*
X1465004Y254042D01*
X1465491Y253319D01*
Y252598D01*
X1465004Y251876D01*
X1464517Y251154D01*
X1463542Y250432D01*
X1462568D01*
G01Y255485D02*
X1461593Y256207D01*
X1461106Y256929D01*
Y257651D01*
X1461593Y258372D01*
X1462568Y259094D01*
X1463542D01*
X1464517Y258372D01*
X1465004Y257651D01*
Y256929D01*
X1464517Y256207D01*
X1463542Y255485D01*
G01X1448330Y248267D02*
X1455548Y261259D01*
G01X1447609Y254763D02*
X1448330Y256929D01*
X1449774Y258372D01*
X1451939Y259094D01*
X1454105Y258372D01*
X1455548Y256929D01*
X1456270Y254763D01*
X1455548Y252598D01*
X1454105Y251154D01*
X1451939Y250432D01*
X1449774Y251154D01*
X1448330Y252598D01*
X1447609Y254763D01*
G01X1477006Y727570D02*
X1477981Y729014D01*
X1478955D01*
X1479443Y728292D01*
G01X1474426Y736231D02*
X1473452Y736953D01*
X1472964Y737675D01*
X1472477Y739119D01*
Y742006D01*
X1472964Y743449D01*
X1473452Y744171D01*
X1474426Y744893D01*
X1475400Y744171D01*
X1475887Y743449D01*
X1476375Y742006D01*
Y739119D01*
X1475887Y737675D01*
X1475400Y736953D01*
X1474426Y736231D01*
G01X1477006Y723239D02*
Y729014D01*
G01X1449578Y740562D02*
X1450553Y741284D01*
X1451527D01*
X1452502Y740562D01*
X1453476Y739119D01*
G01X1468237Y731901D02*
X1473109D01*
G01X1458835Y736231D02*
X1458348D01*
Y736953D01*
X1458835Y736231D01*
G01X1457031Y725405D02*
X1456057Y723961D01*
X1455082Y723239D01*
X1454108Y723961D01*
X1453133Y725405D01*
Y726848D01*
X1454108Y728292D01*
X1455082Y729014D01*
X1456057Y728292D01*
X1457031Y726848D01*
Y725405D01*
G01X1450553Y736231D02*
X1449578Y736953D01*
X1449091Y737675D01*
X1448604Y738397D01*
Y739119D01*
X1449578Y740562D01*
G01X1450553Y741284D02*
X1449578Y742006D01*
X1449091Y742727D01*
Y743449D01*
X1449578Y744171D01*
X1450553Y744893D01*
X1451527D01*
X1452502Y744171D01*
X1452989Y743449D01*
Y742727D01*
X1452502Y742006D01*
X1451527Y741284D01*
G01X1466631Y736231D02*
X1465656Y736953D01*
X1465169Y737675D01*
X1464682Y739119D01*
Y742006D01*
X1465169Y743449D01*
X1465656Y744171D01*
X1466631Y744893D01*
X1467605Y744171D01*
X1468093Y743449D01*
X1468580Y742006D01*
Y739119D01*
X1468093Y737675D01*
X1467605Y736953D01*
X1466631Y736231D01*
G01X1453476Y739119D02*
Y738397D01*
X1452989Y737675D01*
X1452502Y736953D01*
X1451527Y736231D01*
X1450553D01*
G01X1470673Y731901D02*
Y723239D01*
G01X1480967Y786706D02*
X1481942Y787427D01*
X1482916D01*
X1483891Y786706D01*
X1484378Y785984D01*
Y785262D01*
X1483891Y784540D01*
X1482916Y783818D01*
X1483891Y783097D01*
X1484378Y782375D01*
X1484865Y781653D01*
Y780931D01*
X1484378Y780210D01*
X1483891Y779488D01*
X1482916Y778766D01*
X1481942D01*
X1480967Y779488D01*
X1480480Y780210D01*
G01X1455172Y776601D02*
X1458321D01*
G01D02*
X1565145D01*
G01X1467704D02*
X1474922Y789593D01*
G01X1466983Y783097D02*
X1467704Y785262D01*
X1469148Y786706D01*
X1471313Y787427D01*
X1473479Y786706D01*
X1474922Y785262D01*
X1475644Y783097D01*
X1474922Y780931D01*
X1473479Y779488D01*
X1471313Y778766D01*
X1469148Y779488D01*
X1467704Y780931D01*
X1466983Y783097D01*
G01X1503829Y-1120610D02*
Y-1139623D01*
G01X1492693Y-53680D02*
X1495616D01*
G01X1500001Y-47906D02*
X1501950D01*
X1502924Y-48627D01*
X1503411Y-49349D01*
X1503898Y-50071D01*
X1504385Y-52236D01*
X1503898Y-54402D01*
X1503411Y-55123D01*
X1502924Y-55845D01*
X1501950Y-56567D01*
X1500001D01*
Y-47906D01*
G01X1484410Y-56567D02*
Y-47906D01*
X1486846D01*
X1487820Y-48627D01*
X1488308Y-49349D01*
Y-50793D01*
X1487820Y-51515D01*
X1486846Y-52236D01*
X1484410D01*
G01X1491718Y-56567D02*
X1494154Y-47906D01*
X1496590Y-56567D01*
G01X1493855Y23424D02*
X1492881Y24146D01*
X1492394Y24868D01*
X1491907Y26311D01*
Y29198D01*
X1492394Y30642D01*
X1492881Y31364D01*
X1493855Y32086D01*
X1494830Y31364D01*
X1495317Y30642D01*
X1495804Y29198D01*
Y26311D01*
X1495317Y24868D01*
X1494830Y24146D01*
X1493855Y23424D01*
G01X1487522D02*
Y32086D01*
X1484111Y25590D01*
X1488496D01*
G01X1486060Y58070D02*
X1485573D01*
Y58792D01*
X1486060Y58070D01*
G01X1501651D02*
X1500676Y58792D01*
X1500189Y59513D01*
X1499702Y60957D01*
Y63844D01*
X1500189Y65288D01*
X1500676Y66009D01*
X1501651Y66731D01*
X1502625Y66009D01*
X1503112Y65288D01*
X1503600Y63844D01*
Y60957D01*
X1503112Y59513D01*
X1502625Y58792D01*
X1501651Y58070D01*
G01X1491907Y65288D02*
X1492394Y66009D01*
X1493368Y66731D01*
X1494343D01*
X1495317Y66009D01*
X1495804Y65288D01*
Y63844D01*
X1495317Y63122D01*
X1493368Y61679D01*
G01D02*
X1492394Y60235D01*
X1491907Y58070D01*
X1495804D01*
G01X1493855Y40353D02*
X1492881Y41075D01*
X1492394Y41797D01*
X1491907Y43240D01*
Y46127D01*
X1492394Y47571D01*
X1492881Y48293D01*
X1493855Y49015D01*
X1494830Y48293D01*
X1495317Y47571D01*
X1495804Y46127D01*
Y43240D01*
X1495317Y41797D01*
X1494830Y41075D01*
X1493855Y40353D01*
G01X1486060D02*
X1486547Y43962D01*
X1487035Y46127D01*
X1487522Y47571D01*
X1488009Y49015D01*
X1484111D01*
G01X1486060Y92716D02*
X1485573D01*
Y93437D01*
X1486060Y92716D01*
G01X1501651D02*
X1500676Y93437D01*
X1500189Y94159D01*
X1499702Y95603D01*
Y98490D01*
X1500189Y99933D01*
X1500676Y100655D01*
X1501651Y101377D01*
X1502625Y100655D01*
X1503112Y99933D01*
X1503600Y98490D01*
Y95603D01*
X1503112Y94159D01*
X1502625Y93437D01*
X1501651Y92716D01*
G01X1493855D02*
X1492881Y93437D01*
X1492394Y94159D01*
X1491907Y95603D01*
Y98490D01*
X1492394Y99933D01*
X1492881Y100655D01*
X1493855Y101377D01*
X1494830Y100655D01*
X1495317Y99933D01*
X1495804Y98490D01*
Y95603D01*
X1495317Y94159D01*
X1494830Y93437D01*
X1493855Y92716D01*
G01X1486060Y75786D02*
X1485573D01*
Y76508D01*
X1486060Y75786D01*
G01X1501651D02*
X1500676Y76508D01*
X1500189Y77230D01*
X1499702Y78673D01*
Y81561D01*
X1500189Y83004D01*
X1500676Y83726D01*
X1501651Y84448D01*
X1502625Y83726D01*
X1503112Y83004D01*
X1503600Y81561D01*
Y78673D01*
X1503112Y77230D01*
X1502625Y76508D01*
X1501651Y75786D01*
G01X1493855D02*
X1494343Y79395D01*
X1494830Y81561D01*
X1495317Y83004D01*
X1495804Y84448D01*
X1491907D01*
G01X1507148Y194004D02*
X1506173Y194726D01*
X1505686Y195448D01*
X1505198Y196169D01*
Y196892D01*
X1505686Y197613D01*
X1506173Y198335D01*
X1507148Y199057D01*
X1508122D01*
X1509096Y198335D01*
G01X1507148Y199057D02*
X1506173Y199779D01*
X1505686Y200500D01*
Y201222D01*
X1506173Y201944D01*
X1507148Y202666D01*
X1508122D01*
X1509096Y201944D01*
X1509583Y201222D01*
Y200500D01*
X1509096Y199779D01*
X1508122Y199057D01*
G01X1515430Y194004D02*
X1514456Y194726D01*
X1513969Y195448D01*
X1513481Y196892D01*
Y199779D01*
X1513969Y201222D01*
X1514456Y201944D01*
X1515430Y202666D01*
X1516404Y201944D01*
X1516892Y201222D01*
X1517379Y199779D01*
Y196892D01*
X1516892Y195448D01*
X1516404Y194726D01*
X1515430Y194004D01*
G01X1509096Y198335D02*
X1510071Y196892D01*
Y196169D01*
G01D02*
X1509096Y194726D01*
X1508122Y194004D01*
X1507148D01*
G01X1507893Y178248D02*
X1519704D01*
G01X1499839Y194004D02*
X1499352D01*
Y194726D01*
X1499839Y194004D01*
G01X1491557Y199057D02*
X1492531D01*
G01X1493506Y198335D02*
X1494480Y196892D01*
Y196169D01*
G01X1490583Y201944D02*
X1491557Y202666D01*
X1492531D01*
X1493506Y201944D01*
X1493993Y201222D01*
Y200500D01*
X1493506Y199779D01*
X1492531Y199057D01*
X1493506Y198335D01*
G01X1494480Y196169D02*
X1493506Y194726D01*
X1492531Y194004D01*
X1491557D01*
X1490583Y194726D01*
X1490095Y195448D01*
G01X1515330Y238884D02*
X1514843Y238162D01*
X1513869Y237440D01*
X1512894Y238162D01*
X1511920Y239606D01*
Y241049D01*
X1512894Y242493D01*
X1513869Y243215D01*
X1514843Y242493D01*
X1515330Y241049D01*
X1511920D01*
G01X1507048Y238162D02*
X1506073Y237440D01*
X1505099Y238162D01*
X1504124Y239606D01*
Y241049D01*
X1505099Y242493D01*
X1506073Y243215D01*
X1507048Y242493D01*
G01X1489021Y241771D02*
X1489995Y243215D01*
X1490970D01*
X1491457Y242493D01*
G01X1482687Y246102D02*
Y237440D01*
G01X1489021D02*
Y243215D01*
G01X1500227D02*
Y237440D01*
G01Y239606D02*
X1499252Y238162D01*
X1498278Y237440D01*
X1497304Y238162D01*
X1496329Y239606D01*
Y241049D01*
X1497304Y242493D01*
X1498278Y243215D01*
X1499252Y242493D01*
X1500227Y241049D01*
G01X1511775Y252598D02*
X1510801Y251154D01*
X1509826Y250432D01*
X1508852Y251154D01*
X1507878Y252598D01*
Y254042D01*
X1508852Y255485D01*
X1509826Y256207D01*
X1510801Y255485D01*
X1511775Y254042D01*
Y252598D01*
G01X1499595Y255485D02*
X1503006D01*
G01X1486441Y250432D02*
X1485466Y251154D01*
X1484979Y251876D01*
X1484492Y253319D01*
Y256207D01*
X1484979Y257651D01*
X1485466Y258372D01*
X1486441Y259094D01*
X1487415Y258372D01*
X1487902Y257651D01*
X1488389Y256207D01*
Y253319D01*
X1487902Y251876D01*
X1487415Y251154D01*
X1486441Y250432D01*
G01X1494723Y259094D02*
X1493749Y257651D01*
X1493261Y255485D01*
Y254042D01*
X1493749Y251876D01*
X1494723Y250432D01*
G01X1499595Y259094D02*
Y250432D01*
X1503006D01*
X1503493Y251154D01*
X1503980Y251876D01*
Y254042D01*
X1503493Y254763D01*
X1503006Y255485D01*
X1503493Y256207D01*
Y258372D01*
X1503006Y259094D01*
X1499595D01*
G01X1511941Y741284D02*
X1512915Y742006D01*
G01D02*
X1513889D01*
X1514864Y740562D01*
Y736231D01*
G01X1505607D02*
Y744893D01*
G01X1511941Y736231D02*
Y744893D01*
G01X1495033Y723961D02*
X1494059Y723239D01*
X1493084Y723961D01*
X1492110Y725405D01*
Y726848D01*
X1493084Y728292D01*
X1494059Y729014D01*
X1495033Y728292D01*
G01X1487580Y741284D02*
X1490991D01*
G01X1504146D02*
X1507069D01*
G01X1482709Y744893D02*
X1481734Y743449D01*
X1481247Y741284D01*
Y739840D01*
X1481734Y737675D01*
X1482709Y736231D01*
G01X1490991Y741284D02*
X1491478Y742006D01*
Y744171D01*
X1490991Y744893D01*
X1487580D01*
G01X1488212Y725405D02*
X1487238Y723961D01*
X1486263Y723239D01*
X1485289Y723961D01*
X1484315Y725405D01*
Y726848D01*
X1485289Y728292D01*
X1486263Y729014D01*
X1487238Y728292D01*
X1488212Y726848D01*
G01X1499761Y738397D02*
X1498786Y736953D01*
X1497812Y736231D01*
X1496837Y736953D01*
X1495863Y738397D01*
Y739840D01*
X1496837Y741284D01*
X1497812Y742006D01*
X1498786Y741284D01*
X1499761Y739840D01*
Y738397D01*
G01X1503315Y724683D02*
X1502828Y723961D01*
X1501854Y723239D01*
X1500880Y723961D01*
X1499905Y725405D01*
Y726848D01*
X1500880Y728292D01*
X1501854Y729014D01*
X1502828Y728292D01*
X1503315Y726848D01*
X1499905D01*
G01X1487580Y744893D02*
Y736231D01*
X1490991D01*
X1491478Y736953D01*
X1491965Y737675D01*
Y739840D01*
X1490991Y741284D01*
G01X1488212Y729014D02*
Y723239D01*
G01X1514097Y787427D02*
X1513123Y785984D01*
X1512635Y783818D01*
Y782375D01*
X1513123Y780210D01*
X1514097Y778766D01*
G01X1490224D02*
X1489737D01*
Y779488D01*
X1490224Y778766D01*
G01X1497532D02*
X1496558Y779488D01*
X1496071Y780210D01*
X1495583Y780931D01*
Y781653D01*
X1496071Y782375D01*
X1496558Y783097D01*
X1497532Y783818D01*
X1498507D01*
X1499481Y783097D01*
X1499968Y782375D01*
X1500456Y781653D01*
Y780931D01*
X1499968Y780210D01*
X1499481Y779488D01*
X1498507Y778766D01*
X1497532D01*
G01X1505815D02*
X1504840Y779488D01*
X1504353Y780210D01*
X1503866Y781653D01*
Y784540D01*
X1504353Y785984D01*
X1504840Y786706D01*
X1505815Y787427D01*
X1506789Y786706D01*
X1507276Y785984D01*
X1507764Y784540D01*
Y781653D01*
X1507276Y780210D01*
X1506789Y779488D01*
X1505815Y778766D01*
G01X1481942Y783818D02*
X1482916D01*
G01X1497532D02*
X1496558Y784540D01*
X1496071Y785262D01*
Y785984D01*
X1496558Y786706D01*
X1497532Y787427D01*
X1498507D01*
X1499481Y786706D01*
X1499968Y785984D01*
Y785262D01*
X1499481Y784540D01*
X1498507Y783818D01*
G01X1509362Y899802D02*
X1508874D01*
Y900524D01*
X1509362Y899802D01*
G01X1484027Y907020D02*
X1484514Y907742D01*
X1485489Y908464D01*
X1486463D01*
X1487438Y907742D01*
X1487925Y907020D01*
Y905576D01*
X1487438Y904855D01*
X1485489Y903411D01*
G01D02*
X1484514Y901968D01*
X1484027Y899802D01*
X1487925D01*
G01X1493284Y903411D02*
X1492310Y901968D01*
X1491822Y899802D01*
X1495720D01*
G01X1491822Y907020D02*
X1492310Y907742D01*
X1493284Y908464D01*
X1494258D01*
X1495233Y907742D01*
X1495720Y907020D01*
Y905576D01*
X1495233Y904855D01*
X1493284Y903411D01*
G01X1504003Y902689D02*
Y901968D01*
X1503515Y901245D01*
X1503028Y900524D01*
X1502054Y899802D01*
X1501080D01*
G01D02*
X1500105Y900524D01*
G01X1501080Y904855D02*
X1500105Y905576D01*
X1499618Y906298D01*
Y907020D01*
X1500105Y907742D01*
X1501080Y908464D01*
X1502054D01*
X1503028Y907742D01*
X1503515Y907020D01*
Y906298D01*
X1503028Y905576D01*
X1502054Y904855D01*
G01X1500105Y900524D02*
X1499131Y901968D01*
Y902689D01*
X1499618Y903411D01*
X1500105Y904133D01*
X1501080Y904855D01*
X1502054D01*
X1503028Y904133D01*
X1504003Y902689D01*
G01X1503829Y2171102D02*
Y2152090D01*
G01X1546706Y-570682D02*
X1545985Y-569708D01*
Y-568733D01*
X1546706Y-567759D01*
X1547428Y-567272D01*
X1548150D01*
X1548872Y-567759D01*
X1549594Y-568733D01*
X1550315Y-567759D01*
G01X1547428Y-578965D02*
X1546706Y-578478D01*
X1545985Y-577503D01*
Y-576529D01*
X1546706Y-575554D01*
X1547428Y-575067D01*
X1548872D01*
X1549594Y-575554D01*
G01X1554646Y-553630D02*
X1553924Y-554605D01*
X1553202Y-555092D01*
X1551759Y-555579D01*
X1548872D01*
X1547428Y-555092D01*
X1546706Y-554605D01*
X1545985Y-553630D01*
X1546706Y-552656D01*
X1547428Y-552169D01*
X1548872Y-551681D01*
X1551759D01*
X1553202Y-552169D01*
X1553924Y-552656D01*
X1554646Y-553630D01*
G01Y-545835D02*
X1553924Y-546809D01*
X1553202Y-547296D01*
X1551759Y-547784D01*
X1548872D01*
X1547428Y-547296D01*
X1546706Y-546809D01*
X1545985Y-545835D01*
X1546706Y-544860D01*
X1547428Y-544373D01*
X1548872Y-543886D01*
X1551759D01*
X1553202Y-544373D01*
X1553924Y-544860D01*
X1554646Y-545835D01*
G01X1543051Y-415011D02*
X1543773Y-412845D01*
X1545216Y-411402D01*
X1547381Y-410680D01*
X1549547Y-411402D01*
X1550991Y-412845D01*
X1551712Y-415011D01*
X1550991Y-417176D01*
X1549547Y-418620D01*
X1547381Y-419342D01*
X1545216Y-418620D01*
X1543773Y-417176D01*
X1543051Y-415011D01*
G01X1543773Y-421507D02*
X1550991Y-408515D01*
G01X1633419Y-421507D02*
X1518799D01*
G01X1537692Y-419342D02*
X1540615Y-413567D01*
G01X1533794Y-417176D02*
X1532820Y-418620D01*
X1531845Y-419342D01*
X1530871D01*
X1529896Y-418620D01*
X1529409Y-417898D01*
G01X1529896Y-411402D02*
X1530871Y-410680D01*
X1531845D01*
X1532820Y-411402D01*
X1533307Y-412123D01*
Y-412845D01*
X1532820Y-413567D01*
X1531845Y-414289D01*
X1532820Y-415011D01*
G01X1537692Y-413567D02*
X1540615Y-419342D01*
G01X1532820Y-415011D02*
X1533794Y-416454D01*
Y-417176D01*
G01X1530871Y-414289D02*
X1531845D01*
G01X1544799Y-30304D02*
Y-21643D01*
X1547235Y-28860D01*
X1549671Y-21643D01*
Y-30304D01*
G01X1531526Y-25973D02*
X1543337D01*
G01X1541141Y173917D02*
X1537243D01*
Y182579D01*
X1541141D01*
G01X1533346Y173917D02*
X1529448D01*
Y182579D01*
X1533346D01*
G01X1525550Y181135D02*
X1525063Y181857D01*
X1524089Y182579D01*
X1523115D01*
X1522140Y181857D01*
X1521653Y181135D01*
Y180413D01*
X1522140Y179692D01*
X1523115Y178969D01*
X1525063Y177526D01*
X1525550Y176805D01*
Y175361D01*
X1525063Y174639D01*
X1524089Y173917D01*
X1523115D01*
X1522140Y174639D01*
X1521166Y176082D01*
G01X1544175Y202666D02*
X1549047D01*
G01X1546611D02*
Y194004D01*
G01X1529072D02*
Y202666D01*
X1532969Y194004D01*
Y202666D01*
G01X1536867Y194004D02*
Y202666D01*
X1539303D01*
X1540278Y201944D01*
X1540765Y201222D01*
Y199779D01*
X1540278Y199057D01*
X1539303Y198335D01*
X1536867D01*
G01X1523713Y202666D02*
X1522738Y201222D01*
X1522251Y199057D01*
Y197613D01*
X1522738Y195448D01*
X1523713Y194004D01*
G01X1529448Y178248D02*
X1531884D01*
G01X1537243D02*
X1539680D01*
G01X1527997Y240327D02*
X1530920D01*
G01X1535793Y242493D02*
X1538716D01*
G01X1537254Y237440D02*
Y246102D01*
G01X1527023Y237440D02*
X1529459Y246102D01*
X1531895Y237440D01*
G01X1542956Y257651D02*
X1542469Y258372D01*
X1541495Y259094D01*
X1540520D01*
X1539546Y258372D01*
X1539059Y257651D01*
Y256929D01*
X1539546Y256207D01*
X1540520Y255485D01*
X1542469Y254042D01*
X1542956Y253319D01*
Y251876D01*
X1542469Y251154D01*
X1541495Y250432D01*
X1540520D01*
X1539546Y251154D01*
X1539059Y251876D01*
X1538572Y252598D01*
G01X1516160Y255485D02*
X1519083D01*
G01X1524930Y256207D02*
X1525904D01*
X1526879Y254763D01*
Y250432D01*
G01X1523955Y255485D02*
X1524930Y256207D01*
G01X1517622Y250432D02*
Y259094D01*
G01X1523955Y250432D02*
Y259094D01*
G01X1539369Y726126D02*
X1542292D01*
G01X1546532Y738397D02*
X1545558Y736953D01*
X1544583Y736231D01*
X1543609Y736953D01*
X1542635Y738397D01*
Y739840D01*
X1543609Y741284D01*
X1544583Y742006D01*
X1545558Y741284D01*
X1546532Y739840D01*
G01Y744893D02*
Y736231D01*
G01X1515983Y726126D02*
X1518906D01*
G01X1523778Y728292D02*
X1526701D01*
G01X1515008Y723239D02*
X1517444Y731901D01*
X1519880Y723239D01*
G01X1538394D02*
X1540830Y731901D01*
X1543266Y723239D01*
G01X1525240D02*
Y731901D01*
G01X1536788Y744893D02*
Y744171D01*
G01Y742006D02*
Y736231D01*
G01X1530942Y743449D02*
X1530455Y744171D01*
X1529480Y744893D01*
X1528506D01*
X1527531Y744171D01*
X1527044Y743449D01*
Y742727D01*
X1527531Y742006D01*
X1528506Y741284D01*
X1529480Y740562D01*
X1530455Y739840D01*
X1530942Y739119D01*
Y737675D01*
X1530455Y736953D01*
X1529480Y736231D01*
X1528506D01*
X1527531Y736953D01*
X1527044Y737675D01*
X1526557Y738397D01*
G01X1542842Y787427D02*
Y778766D01*
G01X1546740Y787427D02*
Y778766D01*
G01X1519456D02*
Y787427D01*
X1523354Y778766D01*
Y787427D01*
G01X1527252Y778766D02*
Y787427D01*
X1529688D01*
X1530662Y786706D01*
X1531149Y785984D01*
Y784540D01*
X1530662Y783818D01*
X1529688Y783097D01*
X1527252D01*
G01X1536996Y787427D02*
Y778766D01*
G01X1542842Y783097D02*
X1546740D01*
G01X1534560Y787427D02*
X1539432D01*
G01X1517157Y899802D02*
X1516183Y900524D01*
X1515696Y901245D01*
X1515208Y902689D01*
Y905576D01*
X1515696Y907020D01*
X1516183Y907742D01*
X1517157Y908464D01*
X1518131Y907742D01*
X1518619Y907020D01*
X1519106Y905576D01*
Y902689D01*
X1518619Y901245D01*
X1518131Y900524D01*
X1517157Y899802D01*
G01X1524952D02*
X1523978Y900524D01*
X1523491Y901245D01*
X1523004Y902689D01*
Y905576D01*
X1523491Y907020D01*
X1523978Y907742D01*
X1524952Y908464D01*
X1525927Y907742D01*
X1526414Y907020D01*
X1526901Y905576D01*
Y902689D01*
X1526414Y901245D01*
X1525927Y900524D01*
X1524952Y899802D01*
G01X1705779Y-651977D02*
X1552874D01*
G01X1556811D02*
Y-561425D01*
G01X1549594Y-569708D02*
Y-568733D01*
G01Y-575554D02*
X1551037Y-577503D01*
X1552481Y-578478D01*
X1554646Y-578965D01*
Y-575067D01*
G01X1550315Y-567759D02*
X1551759Y-566784D01*
X1552481D01*
X1553202Y-567272D01*
X1553924Y-567759D01*
X1554646Y-568733D01*
Y-569708D01*
X1553924Y-570682D01*
X1553202Y-571170D01*
G01X1556811Y-470874D02*
Y-561425D01*
G01X1554646D02*
Y-561912D01*
X1553924D01*
X1554646Y-561425D01*
G01X1831763Y-470874D02*
X1552874D01*
G01X1581883Y-419342D02*
X1580909Y-418620D01*
X1580421Y-417898D01*
X1579934Y-416454D01*
Y-413567D01*
X1580421Y-412123D01*
X1580909Y-411402D01*
X1581883Y-410680D01*
X1582857Y-411402D01*
X1583344Y-412123D01*
X1583832Y-413567D01*
Y-416454D01*
X1583344Y-417898D01*
X1582857Y-418620D01*
X1581883Y-419342D01*
G01X1560933Y-416454D02*
Y-417176D01*
X1560446Y-417898D01*
X1559959Y-418620D01*
X1558984Y-419342D01*
X1558010D01*
X1557035Y-418620D01*
X1556548Y-417898D01*
G01X1572139Y-412123D02*
X1572626Y-411402D01*
X1573600Y-410680D01*
X1574575D01*
X1575549Y-411402D01*
X1576037Y-412123D01*
Y-413567D01*
X1575549Y-414289D01*
G01X1557035Y-411402D02*
X1558010Y-410680D01*
X1558984D01*
X1559959Y-411402D01*
X1560446Y-412123D01*
Y-412845D01*
X1559959Y-413567D01*
X1558984Y-414289D01*
X1559959Y-415011D01*
X1560933Y-416454D01*
G01X1575549Y-414289D02*
X1573600Y-415732D01*
X1572626Y-417176D01*
X1572139Y-419342D01*
X1576037D01*
G01X1566293D02*
X1565805D01*
Y-418620D01*
X1566293Y-419342D01*
G01X1558010Y-414289D02*
X1558984D01*
G01X1578416Y-30304D02*
Y-23086D01*
X1579390Y-21643D01*
X1579878D01*
X1580365Y-22364D01*
G01X1564774Y-21643D02*
Y-30304D01*
G01X1570620Y-24530D02*
Y-30304D01*
G01X1556979Y-28138D02*
X1556004Y-29582D01*
X1555030Y-30304D01*
X1554056Y-29582D01*
X1553081Y-28138D01*
Y-26695D01*
X1554056Y-25251D01*
X1555030Y-24530D01*
X1556004Y-25251D01*
X1556979Y-26695D01*
Y-28138D01*
G01X1564774D02*
X1563800Y-29582D01*
X1562826Y-30304D01*
X1561851Y-29582D01*
X1560876Y-28138D01*
Y-26695D01*
X1561851Y-25251D01*
X1562826Y-24530D01*
X1563800Y-25251D01*
X1564774Y-26695D01*
G01X1577442Y-25251D02*
X1579390D01*
G01X1570620Y-21643D02*
Y-22364D01*
G01X1575733Y173917D02*
X1578169Y182579D01*
X1580605Y173917D01*
G01X1564527D02*
X1560629D01*
Y182579D01*
X1564527D01*
G01X1555757Y181857D02*
X1556731Y180413D01*
X1557219Y178248D01*
X1556731Y176082D01*
X1556244Y175361D01*
X1555757Y174639D01*
X1554783Y173917D01*
X1552834D01*
Y182579D01*
G01X1570373D02*
Y173917D01*
G01X1576707Y176805D02*
X1579630D01*
G01X1552834Y182579D02*
X1554783D01*
X1555757Y181857D01*
G01X1567937Y182579D02*
X1572809D01*
G01X1552457Y198335D02*
X1556355D01*
G01X1561715Y202666D02*
X1562689Y201222D01*
X1563176Y199057D01*
Y197613D01*
X1562689Y195448D01*
X1561715Y194004D01*
G01X1552457Y202666D02*
Y194004D01*
G01X1556355Y202666D02*
Y194004D01*
G01X1560629Y178248D02*
X1563065D01*
G01X1551383Y240327D02*
X1554306D01*
G01X1560640Y237440D02*
Y246102D01*
G01X1568435Y237440D02*
Y246102D01*
G01X1550409Y237440D02*
X1552845Y246102D01*
X1555281Y237440D01*
G01X1573163Y255485D02*
X1572676Y256207D01*
X1571702D01*
X1571214Y255485D01*
Y254763D01*
X1572189Y254042D01*
X1573163Y253319D01*
X1573650Y252598D01*
Y251876D01*
X1573163Y251154D01*
X1572676Y250432D01*
X1571702D01*
X1571214Y251154D01*
X1570727Y251876D01*
G01X1548803Y259094D02*
Y258372D01*
G01Y256207D02*
Y250432D01*
G01X1558547Y259094D02*
Y250432D01*
G01Y252598D02*
X1557572Y251154D01*
X1556598Y250432D01*
X1555624Y251154D01*
X1554649Y252598D01*
Y254042D01*
X1555624Y255485D01*
X1556598Y256207D01*
X1557572Y255485D01*
X1558547Y254042D01*
G01X1565855Y251876D02*
X1565368Y251154D01*
X1564393Y250432D01*
X1563419Y251154D01*
X1562444Y252598D01*
Y254042D01*
X1563419Y255485D01*
X1564393Y256207D01*
X1565368Y255485D01*
X1565855Y254042D01*
X1562444D01*
G01X1581756Y725405D02*
X1580781Y723961D01*
X1579807Y723239D01*
X1578832Y723961D01*
X1577858Y725405D01*
Y726848D01*
X1578832Y728292D01*
X1579807Y729014D01*
X1580781Y728292D01*
X1581756Y726848D01*
G01X1573816Y736231D02*
Y744893D01*
X1576252D01*
X1577226Y744171D01*
X1577713Y743449D01*
Y742006D01*
X1577226Y741284D01*
X1576252Y740562D01*
X1573816D01*
G01X1581756Y729014D02*
Y723239D01*
G01X1581124Y736231D02*
X1583560Y744893D01*
X1585996Y736231D01*
G01X1560661D02*
X1559687D01*
X1559200Y736953D01*
X1558713Y737675D01*
G01X1553840D02*
X1553353Y736953D01*
X1552379Y736231D01*
X1551404Y736953D01*
X1550430Y738397D01*
Y739840D01*
X1551404Y741284D01*
X1552379Y742006D01*
X1553353Y741284D01*
X1553840Y739840D01*
X1550430D01*
G01X1548626Y723239D02*
Y731901D01*
G01X1556421Y723239D02*
Y731901D01*
G01X1570063D02*
Y723239D01*
X1573960D01*
G01X1561148Y741284D02*
X1560661Y742006D01*
X1559687D01*
X1559200Y741284D01*
Y740562D01*
X1561148Y739119D01*
X1561636Y738397D01*
Y737675D01*
X1560661Y736231D01*
G01X1552099Y787427D02*
X1553074Y785984D01*
X1553561Y783818D01*
Y782375D01*
X1553074Y780210D01*
X1552099Y778766D01*
G01X1613339Y-1124413D02*
Y-1135820D01*
G01X1705779Y-651977D02*
X1591711D01*
G01X1595648D02*
Y-596071D01*
G01X1584821Y-611662D02*
X1593482D01*
G01Y-602405D02*
X1584821D01*
X1591317Y-605815D01*
Y-601430D01*
G01X1588430Y-586814D02*
X1589874Y-588763D01*
X1591317Y-589738D01*
X1593482Y-590225D01*
Y-586327D01*
G01X1586265Y-590225D02*
X1585543Y-589738D01*
X1584821Y-588763D01*
Y-587788D01*
X1585543Y-586814D01*
X1586265Y-586327D01*
X1587708D01*
X1588430Y-586814D01*
G01X1593482Y-580481D02*
X1592761Y-581455D01*
X1592039Y-581942D01*
X1590595Y-582429D01*
X1587708D01*
X1586265Y-581942D01*
X1585543Y-581455D01*
X1584821Y-580481D01*
X1585543Y-579506D01*
X1586265Y-579019D01*
X1587708Y-578532D01*
X1590595D01*
X1592039Y-579019D01*
X1592761Y-579506D01*
X1593482Y-580481D01*
G01X1595648Y-540166D02*
Y-596071D01*
G01X1593482D02*
Y-596558D01*
X1592761D01*
X1593482Y-596071D01*
G01X1745149Y-540166D02*
X1591711D01*
G01X1611115Y-410680D02*
Y-419342D01*
G01X1615013Y-410680D02*
Y-419342D01*
G01X1611115Y-415011D02*
X1615013D01*
G01X1590165Y-410680D02*
X1589191Y-412123D01*
X1588704Y-414289D01*
Y-415732D01*
X1589191Y-417898D01*
X1590165Y-419342D01*
G01X1595525D02*
Y-410680D01*
X1597961D01*
X1598935Y-411402D01*
X1599422Y-412123D01*
Y-413567D01*
X1598935Y-414289D01*
X1597961Y-415011D01*
X1595525D01*
G01X1605269Y-410680D02*
Y-419342D01*
G01X1602833Y-410680D02*
X1607705D01*
G01X1619341Y-28138D02*
X1618367Y-29582D01*
X1617393Y-30304D01*
X1616418Y-29582D01*
X1615444Y-28138D01*
Y-26695D01*
X1616418Y-25251D01*
X1617393Y-24530D01*
X1618367Y-25251D01*
X1619341Y-26695D01*
Y-28138D01*
G01X1586211Y-24530D02*
Y-30304D01*
G01X1603751Y-21643D02*
Y-30304D01*
G01Y-28138D02*
X1602776Y-29582D01*
X1601802Y-30304D01*
X1600827Y-29582D01*
X1599853Y-28138D01*
Y-26695D01*
X1600827Y-25251D01*
X1601802Y-24530D01*
X1602776Y-25251D01*
X1603751Y-26695D01*
G01X1595468Y-28860D02*
X1594981Y-29582D01*
X1594006Y-30304D01*
X1593032Y-29582D01*
X1592057Y-28138D01*
Y-26695D01*
X1593032Y-25251D01*
X1594006Y-24530D01*
X1594981Y-25251D01*
X1595468Y-26695D01*
X1592057D01*
G01X1586211Y-21643D02*
Y-22364D01*
G01X1619094Y175361D02*
X1618607Y174639D01*
X1617632Y173917D01*
X1616658D01*
X1615683Y174639D01*
X1615196Y175361D01*
X1614709Y176082D01*
X1614222Y178248D01*
X1614709Y180413D01*
X1615196Y181135D01*
X1615683Y181857D01*
X1616658Y182579D01*
X1617632D01*
X1618607Y181857D01*
X1619094Y181135D01*
G01X1585964Y182579D02*
Y173917D01*
G01X1591810Y182579D02*
Y173917D01*
X1595708D01*
G01X1613745Y237440D02*
Y243215D01*
G01Y241771D02*
X1614720Y243215D01*
X1615694D01*
X1616181Y242493D01*
G01X1582077Y246102D02*
Y237440D01*
X1585975D01*
G01X1593770Y243215D02*
Y237440D01*
G01X1599617Y238162D02*
X1601565Y243215D01*
G01X1593770Y239606D02*
X1592796Y238162D01*
X1591821Y237440D01*
X1590847Y238162D01*
X1589872Y239606D01*
Y241049D01*
X1590847Y242493D01*
X1591821Y243215D01*
X1592796Y242493D01*
X1593770Y241049D01*
G01X1608873Y238884D02*
X1608386Y238162D01*
X1607412Y237440D01*
X1606437Y238162D01*
X1605463Y239606D01*
Y241049D01*
X1606437Y242493D01*
X1607412Y243215D01*
X1608386Y242493D01*
X1608873Y241049D01*
X1605463D01*
G01X1597668Y243215D02*
X1599617Y238162D01*
X1599129Y235997D01*
X1598155Y234553D01*
X1597180D01*
G01X1610678Y259094D02*
X1611652Y257651D01*
X1612139Y255485D01*
Y254042D01*
X1611652Y251876D01*
X1610678Y250432D01*
G01X1594113Y253319D02*
X1597036D01*
G01X1601421Y259094D02*
X1603370D01*
X1604344Y258372D01*
G01D02*
X1605319Y256929D01*
X1605806Y254763D01*
X1605319Y252598D01*
X1604831Y251876D01*
X1604344Y251154D01*
X1603370Y250432D01*
X1601421D01*
Y259094D01*
G01X1585830Y250432D02*
Y259094D01*
X1588266D01*
X1589241Y258372D01*
X1589728Y257651D01*
Y256207D01*
X1589241Y255485D01*
X1588266Y254763D01*
X1585830D01*
G01X1593139Y250432D02*
X1595574Y259094D01*
X1598011Y250432D01*
G01X1610500Y731901D02*
X1611475Y730457D01*
X1611962Y728292D01*
Y726848D01*
X1611475Y724683D01*
X1610500Y723239D01*
G01X1582098Y739119D02*
X1585022D01*
G01X1589406Y744893D02*
X1591355D01*
X1592330Y744171D01*
X1592817Y743449D01*
X1593304Y742727D01*
X1593791Y740562D01*
X1593304Y738397D01*
X1592817Y737675D01*
X1592330Y736953D01*
X1591355Y736231D01*
X1589406D01*
Y744893D01*
G01X1596859Y724683D02*
X1596372Y723961D01*
X1595397Y723239D01*
X1594423Y723961D01*
X1593448Y725405D01*
Y726848D01*
X1594423Y728292D01*
X1595397Y729014D01*
X1596372Y728292D01*
X1596859Y726848D01*
X1593448D01*
G01X1601731Y727570D02*
X1602705Y729014D01*
X1603680D01*
X1604167Y728292D01*
G01X1587602Y723961D02*
X1589551Y729014D01*
G01X1601731Y723239D02*
Y729014D01*
G01X1598663Y744893D02*
X1599638Y743449D01*
X1600125Y741284D01*
Y739840D01*
X1599638Y737675D01*
X1598663Y736231D01*
G01X1585653Y729014D02*
X1587602Y723961D01*
X1587115Y721796D01*
X1586140Y720352D01*
X1585166D01*
G01X1613339Y2167300D02*
Y2155892D01*
G01X1624746Y-1135820D02*
X1623320Y-1134870D01*
X1622607Y-1133919D01*
X1621894Y-1132018D01*
Y-1128215D01*
X1622607Y-1126314D01*
X1623320Y-1125364D01*
X1624746Y-1124413D01*
X1626172Y-1125364D01*
X1626885Y-1126314D01*
X1627598Y-1128215D01*
Y-1132018D01*
X1626885Y-1133919D01*
X1626172Y-1134870D01*
X1624746Y-1135820D01*
G01X1643546Y-651977D02*
Y-630717D01*
G01X1705779Y-651977D02*
X1639609D01*
G01X1643546Y-609457D02*
Y-630717D01*
G01D02*
Y-569614D01*
G01X1831763Y-609457D02*
X1639609D01*
G01X1641381Y-589102D02*
Y-589589D01*
X1640659D01*
X1641381Y-589102D01*
G01Y-573512D02*
X1640659Y-574486D01*
X1639937Y-574973D01*
X1638494Y-575460D01*
X1635606D01*
X1634163Y-574973D01*
X1633441Y-574486D01*
X1632719Y-573512D01*
X1633441Y-572537D01*
X1634163Y-572050D01*
X1635606Y-571563D01*
X1638494D01*
X1639937Y-572050D01*
X1640659Y-572537D01*
X1641381Y-573512D01*
G01Y-579845D02*
X1632719D01*
X1639215Y-583256D01*
Y-578871D01*
G01X1632719Y-594949D02*
Y-597872D01*
X1636328Y-598359D01*
X1635606Y-597384D01*
Y-596410D01*
X1636328Y-595436D01*
X1637050Y-594949D01*
X1638494Y-594461D01*
X1639937Y-594949D01*
X1640659Y-595436D01*
X1641381Y-596410D01*
Y-597384D01*
X1640659Y-598359D01*
X1639937Y-598846D01*
G01X1740418Y-531024D02*
X1636568Y-421507D01*
G01D02*
X1633419D01*
G01X1620372Y-410680D02*
X1621346Y-412123D01*
X1621834Y-414289D01*
Y-415732D01*
X1621346Y-417898D01*
X1620372Y-419342D01*
G01X1648573Y-30304D02*
X1647599Y-29582D01*
X1647112Y-28860D01*
X1646624Y-27417D01*
Y-24530D01*
X1647112Y-23086D01*
X1647599Y-22364D01*
X1648573Y-21643D01*
X1649548Y-22364D01*
X1650035Y-23086D01*
X1650522Y-24530D01*
Y-27417D01*
X1650035Y-28860D01*
X1649548Y-29582D01*
X1648573Y-30304D01*
G01X1623726D02*
Y-24530D01*
G01Y-25973D02*
X1624700Y-24530D01*
X1625675D01*
X1626649Y-25973D01*
Y-30304D01*
G01X1642240Y-25251D02*
X1640291Y-26695D01*
X1639317Y-28138D01*
X1638829Y-30304D01*
X1642727D01*
G01X1638829Y-23086D02*
X1639317Y-22364D01*
X1640291Y-21643D01*
X1641265D01*
X1642240Y-22364D01*
X1642727Y-23086D01*
Y-24530D01*
X1642240Y-25251D01*
G01X1622515Y246102D02*
X1623489Y244658D01*
X1623977Y242493D01*
Y241049D01*
X1623489Y238884D01*
X1622515Y237440D01*
G01X1624746Y2155892D02*
X1623320Y2156843D01*
X1622607Y2157793D01*
X1621894Y2159695D01*
Y2163497D01*
X1622607Y2165399D01*
X1623320Y2166349D01*
X1624746Y2167300D01*
X1626172Y2166349D01*
X1626885Y2165399D01*
X1627598Y2163497D01*
Y2159695D01*
X1626885Y2157793D01*
X1626172Y2156843D01*
X1624746Y2155892D01*
G01X1679839Y-635776D02*
X1679820Y-635761D01*
G01X1682900Y-635892D02*
X1682910Y-635902D01*
G01Y-635801D02*
X1682900Y-635791D01*
G01X1679824Y-635796D02*
X1679815Y-635786D01*
G01X1680223Y-635977D02*
X1680204Y-635957D01*
G01X1680356Y-635771D02*
X1680376Y-635791D01*
G01X1681694Y-635771D02*
X1681714Y-635791D01*
G01X1682009Y-635977D02*
X1681990Y-635957D01*
G01X1682143Y-635771D02*
X1682162Y-635791D01*
G01X1682354Y-635892D02*
X1682344Y-635882D01*
G01X1682457Y-635977D02*
X1682438Y-635957D01*
G01X1682374Y-635877D02*
X1682359Y-635862D01*
G01X1682590Y-635771D02*
X1682610Y-635791D01*
G01X1679854Y-635796D02*
X1679839Y-635776D01*
G01X1681232Y-635952D02*
X1681247Y-635972D01*
G01X1681227Y-635867D02*
X1681242Y-635887D01*
G01X1681380Y-635796D02*
X1681365Y-635776D01*
G01X1682221Y-635952D02*
X1682236Y-635972D01*
G01X1682369Y-635796D02*
X1682354Y-635776D01*
G01X1682925Y-635877D02*
X1682940Y-635897D01*
G01X1682925Y-635776D02*
X1682940Y-635796D01*
G01X1680223Y-635932D02*
X1680233Y-635947D01*
G01X1681261Y-635952D02*
X1681252Y-635937D01*
G01X1681247Y-635852D02*
X1681257Y-635867D01*
G01X1681360Y-635811D02*
X1681350Y-635796D01*
G01X1681690Y-635811D02*
X1681680Y-635796D01*
G01X1682009Y-635932D02*
X1682019Y-635947D01*
G01X1682241Y-635937D02*
X1682251Y-635952D01*
G01X1682339Y-635796D02*
X1682349Y-635811D01*
G01X1682457Y-635932D02*
X1682467Y-635947D01*
G01X1680243Y-635987D02*
X1680223Y-635977D01*
G01X1680336Y-635761D02*
X1680356Y-635771D01*
G01X1682029Y-635987D02*
X1682009Y-635977D01*
G01X1681675Y-635761D02*
X1681694Y-635771D01*
G01X1682477Y-635987D02*
X1682457Y-635977D01*
G01X1682123Y-635761D02*
X1682143Y-635771D01*
G01X1682570Y-635761D02*
X1682590Y-635771D01*
G01X1682915Y-635872D02*
X1682925Y-635877D01*
G01X1681247Y-635972D02*
X1681271Y-635987D01*
G01X1681242Y-635887D02*
X1681267Y-635902D01*
G01X1681365Y-635776D02*
X1681340Y-635761D01*
G01X1682236Y-635972D02*
X1682261Y-635987D01*
G01X1682359Y-635862D02*
X1682334Y-635847D01*
G01X1682354Y-635776D02*
X1682330Y-635761D01*
G01X1680233Y-635947D02*
X1680248Y-635957D01*
G01X1680346Y-635801D02*
X1680331Y-635791D01*
G01X1681276Y-635962D02*
X1681261Y-635952D01*
G01X1681257Y-635867D02*
X1681271Y-635877D01*
G01X1681350Y-635796D02*
X1681335Y-635786D01*
G01X1681872Y-635942D02*
X1681857Y-635932D01*
G01X1681680Y-635796D02*
X1681665Y-635786D01*
G01X1682019Y-635947D02*
X1682034Y-635957D01*
G01X1681921Y-635807D02*
X1681936Y-635816D01*
G01X1682251Y-635952D02*
X1682265Y-635962D01*
G01X1682133Y-635801D02*
X1682118Y-635791D01*
G01X1682344Y-635882D02*
X1682330Y-635872D01*
G01X1682467Y-635947D02*
X1682482Y-635957D01*
G01X1682324Y-635786D02*
X1682339Y-635796D01*
G01X1682580Y-635801D02*
X1682566Y-635791D01*
G01X1682905Y-635761D02*
X1682925Y-635776D01*
G01X1680204Y-635957D02*
X1680194Y-635937D01*
G01X1681990Y-635957D02*
X1681980Y-635937D01*
G01X1682438Y-635957D02*
X1682428Y-635937D01*
G01X1686780Y-653613D02*
X1675991Y-629005D01*
G01X1681217Y-635842D02*
X1681227Y-635867D01*
G01X1681389Y-635821D02*
X1681380Y-635796D01*
G01X1682211Y-635927D02*
X1682221Y-635952D01*
G01X1682383Y-635902D02*
X1682374Y-635877D01*
G01X1679864Y-635992D02*
X1679820Y-635877D01*
G01X1679790Y-635887D02*
X1679830Y-635992D01*
G01X1679254Y-635756D02*
X1679322Y-635962D01*
G01X1679303Y-635992D02*
X1679224Y-635756D01*
G01X1679830Y-635811D02*
X1679824Y-635796D01*
G01X1679859Y-635811D02*
X1679854Y-635796D01*
G01X1680351Y-635816D02*
X1680346Y-635801D01*
G01X1681227Y-635937D02*
X1681232Y-635952D01*
G01X1681242Y-635836D02*
X1681247Y-635852D01*
G01X1681365Y-635827D02*
X1681360Y-635811D01*
G01X1682137Y-635816D02*
X1682133Y-635801D01*
G01X1682236Y-635922D02*
X1682241Y-635937D01*
G01X1682359Y-635907D02*
X1682354Y-635892D01*
G01X1682374Y-635811D02*
X1682369Y-635796D01*
G01X1682585Y-635816D02*
X1682580Y-635801D01*
G01X1682910Y-635902D02*
X1682915Y-635917D01*
G01X1682940Y-635897D02*
X1682944Y-635912D01*
G01X1682915Y-635816D02*
X1682910Y-635801D01*
G01X1682940Y-635796D02*
X1682944Y-635811D01*
G01X1680218Y-635912D02*
X1680223Y-635932D01*
G01X1681714Y-635791D02*
X1681719Y-635811D01*
G01X1682482Y-635957D02*
X1682502Y-635962D01*
G01X1682118Y-635791D02*
X1682098Y-635786D01*
G01X1680248Y-635957D02*
X1680267Y-635962D01*
G01X1680331Y-635791D02*
X1680312Y-635786D01*
G01X1682034Y-635957D02*
X1682054Y-635962D01*
G01X1682566Y-635791D02*
X1682546Y-635786D01*
G01X1679815D02*
X1679800Y-635781D01*
G01X1681291Y-635967D02*
X1681276Y-635962D01*
G01X1681271Y-635877D02*
X1681286Y-635882D01*
G01X1681335Y-635786D02*
X1681320Y-635781D01*
G01X1682265Y-635962D02*
X1682280Y-635967D01*
G01X1682330Y-635872D02*
X1682315Y-635867D01*
G01X1682310Y-635781D02*
X1682324Y-635786D01*
G01X1682885Y-635887D02*
X1682900Y-635892D01*
G01Y-635791D02*
X1682885Y-635786D01*
G01X1682005Y-635912D02*
X1682009Y-635932D01*
G01X1682452Y-635912D02*
X1682457Y-635932D01*
G01X1680194Y-635937D02*
X1680189Y-635912D01*
G01X1680376Y-635791D02*
X1680381Y-635816D01*
G01X1681980Y-635937D02*
X1681975Y-635912D01*
G01X1682162Y-635791D02*
X1682167Y-635816D01*
G01X1682428Y-635937D02*
X1682423Y-635912D01*
G01X1682610Y-635791D02*
X1682615Y-635816D01*
G01X1681394Y-635857D02*
X1681389Y-635821D01*
G01X1682206Y-635892D02*
X1682211Y-635927D01*
G01X1679007Y-635885D02*
Y-635756D01*
G01X1679037Y-635882D02*
Y-635953D01*
G01Y-635786D02*
Y-635852D01*
G01X1679165D02*
Y-635882D01*
G01X1679185Y-635756D02*
Y-635786D01*
G01Y-635962D02*
Y-635992D01*
G01X1679460D02*
Y-635756D01*
G01X1679490Y-635882D02*
Y-635962D01*
G01Y-635786D02*
Y-635852D01*
G01X1679618D02*
Y-635882D01*
G01X1679637Y-635756D02*
Y-635786D01*
G01Y-635962D02*
Y-635992D01*
G01X1679677Y-635756D02*
Y-635992D01*
G01X1679706Y-635781D02*
Y-635857D01*
G01Y-635992D02*
Y-635887D01*
G01X1679830Y-635827D02*
Y-635811D01*
G01X1679859Y-635831D02*
Y-635811D01*
G01X1679903Y-635992D02*
Y-635756D01*
G01X1679933D02*
Y-635962D01*
G01X1680080D02*
Y-635992D01*
G01X1680120D02*
Y-635756D01*
G01X1680149D02*
Y-635992D01*
G01X1680189Y-635912D02*
Y-635836D01*
G01X1680218D02*
Y-635912D01*
G01X1680307Y-635892D02*
Y-635862D01*
G01X1680351Y-635932D02*
Y-635892D01*
G01X1680381Y-635862D02*
Y-635937D01*
G01X1680420Y-635992D02*
Y-635756D01*
G01X1680450Y-635882D02*
Y-635992D01*
G01Y-635756D02*
Y-635852D01*
G01X1680587Y-635992D02*
Y-635882D01*
G01Y-635852D02*
Y-635756D01*
G01X1680617D02*
Y-635992D01*
G01X1680656Y-635781D02*
Y-635756D01*
G01X1680735Y-635992D02*
Y-635781D01*
G01X1680765D02*
Y-635992D01*
G01X1680843Y-635756D02*
Y-635781D01*
G01X1681119Y-635831D02*
Y-635791D01*
G01X1681148Y-635992D02*
Y-635796D01*
G01X1681178Y-635756D02*
Y-635992D01*
G01X1681217Y-635821D02*
Y-635842D01*
G01X1681242Y-635827D02*
Y-635836D01*
G01X1681365D02*
Y-635827D01*
G01X1681370Y-635882D02*
Y-635892D01*
G01X1681394D02*
Y-635857D01*
G01X1681434Y-635907D02*
Y-635882D01*
G01X1681503D02*
Y-635907D01*
G01X1681542Y-635992D02*
Y-635967D01*
G01X1681690Y-635821D02*
Y-635811D01*
G01X1681719Y-635967D02*
Y-635992D01*
G01Y-635811D02*
Y-635821D01*
G01X1681759Y-635831D02*
Y-635791D01*
G01X1681788Y-635992D02*
Y-635796D01*
G01X1681818Y-635756D02*
Y-635992D01*
G01X1681975Y-635912D02*
Y-635836D01*
G01X1682005D02*
Y-635912D01*
G01X1682093Y-635892D02*
Y-635862D01*
G01X1682137Y-635932D02*
Y-635892D01*
G01X1682167Y-635862D02*
Y-635937D01*
G01X1682206Y-635857D02*
Y-635892D01*
G01X1682231Y-635867D02*
Y-635857D01*
G01X1682236Y-635907D02*
Y-635922D01*
G01X1682359D02*
Y-635907D01*
G01X1682383Y-635927D02*
Y-635902D01*
G01X1682423Y-635912D02*
Y-635836D01*
G01X1682452D02*
Y-635912D01*
G01X1682654Y-635907D02*
Y-635882D01*
G01X1682723D02*
Y-635907D01*
G01X1682763Y-635992D02*
Y-635756D01*
G01X1682792Y-635786D02*
Y-635857D01*
G01Y-635962D02*
Y-635887D01*
G01X1682915Y-635917D02*
Y-635932D01*
G01Y-635827D02*
Y-635816D01*
G01X1682944Y-635811D02*
Y-635831D01*
G01Y-635912D02*
Y-635937D01*
G01X1682984Y-635992D02*
Y-635756D01*
G01X1681645D02*
X1681675Y-635761D01*
G01X1680267Y-635992D02*
X1680243Y-635987D01*
G01X1679820Y-635761D02*
X1679795Y-635756D01*
G01X1681271Y-635987D02*
X1681296Y-635992D01*
G01X1680312Y-635756D02*
X1680336Y-635761D01*
G01X1681267Y-635902D02*
X1681291Y-635907D01*
G01X1682054Y-635992D02*
X1682029Y-635987D01*
G01X1682261D02*
X1682285Y-635992D01*
G01X1681340Y-635761D02*
X1681316Y-635756D01*
G01X1682502Y-635992D02*
X1682477Y-635987D01*
G01X1681665Y-635786D02*
X1681641Y-635781D01*
G01X1682334Y-635847D02*
X1682310Y-635842D01*
G01X1682098Y-635756D02*
X1682123Y-635761D01*
G01X1682330D02*
X1682305Y-635756D01*
G01X1682546D02*
X1682570Y-635761D01*
G01X1682881Y-635756D02*
X1682905Y-635761D01*
G01X1681389Y-635927D02*
X1681394Y-635892D01*
G01X1682211Y-635821D02*
X1682206Y-635857D01*
G01X1681370Y-635892D02*
X1681365Y-635922D01*
G01X1682231Y-635857D02*
X1682236Y-635827D01*
G01X1680189Y-635836D02*
X1680194Y-635811D01*
G01X1681975Y-635836D02*
X1681980Y-635811D01*
G01X1680539Y-639378D02*
X1687275D01*
G01X1679342Y-635992D02*
X1679303D01*
G01X1679637D02*
X1679460D01*
G01X1680080D02*
X1679903D01*
G01X1680149D02*
X1680120D01*
G01X1680312D02*
X1680267D01*
G01X1680617D02*
X1680587D01*
G01X1680450D02*
X1680420D01*
G01X1680765D02*
X1680735D01*
G01X1681178D02*
X1681148D01*
G01X1681719D02*
X1681542D01*
G01X1681818D02*
X1681788D01*
G01X1682098D02*
X1682054D01*
G01X1682546D02*
X1682502D01*
G01X1682881D02*
X1682763D01*
G01X1683013D02*
X1682984D01*
G01X1679185D02*
X1679054D01*
G01X1679830D02*
X1679864D01*
G01X1679677D02*
X1679706D01*
G01X1681296D02*
X1681316D01*
G01X1682285D02*
X1682310D01*
G01X1681320Y-635967D02*
X1681291D01*
G01X1681581D02*
X1681719D01*
G01X1682280D02*
X1682315D01*
G01X1682885Y-635962D02*
X1682792D01*
G01X1679041D02*
X1679185D01*
G01X1679490D02*
X1679637D01*
G01X1679933D02*
X1680080D01*
G01X1680267D02*
X1680312D01*
G01X1682054D02*
X1682098D01*
G01X1682502D02*
X1682546D01*
G01X1681252Y-635937D02*
X1681227D01*
G01X1682585Y-635932D02*
X1682615D01*
G01X1681503Y-635907D02*
X1681434D01*
G01X1682723D02*
X1682654D01*
G01X1681291D02*
X1681316D01*
G01X1680351Y-635892D02*
X1680307D01*
G01X1682137D02*
X1682093D01*
G01X1679706Y-635887D02*
X1679790D01*
G01X1682792D02*
X1682885D01*
G01X1679618Y-635882D02*
X1679490D01*
G01X1680587D02*
X1680450D01*
G01X1679165D02*
X1679037D01*
G01X1681286D02*
X1681320D01*
G01X1681434D02*
X1681503D01*
G01X1682654D02*
X1682723D01*
G01X1682315Y-635867D02*
X1682280D01*
G01X1680307Y-635862D02*
X1680381D01*
G01X1682093D02*
X1682167D01*
G01X1679706Y-635857D02*
X1679800D01*
G01X1682792D02*
X1682885D01*
G01X1679037Y-635852D02*
X1679165D01*
G01X1679490D02*
X1679618D01*
G01X1680450D02*
X1680587D01*
G01X1682310Y-635842D02*
X1682285D01*
G01X1680381Y-635816D02*
X1680351D01*
G01X1682167D02*
X1682137D01*
G01X1682615D02*
X1682585D01*
G01X1681572Y-635811D02*
X1681547D01*
G01X1682349D02*
X1682374D01*
G01X1679637Y-635786D02*
X1679490D01*
G01X1680312D02*
X1680267D01*
G01X1682098D02*
X1682054D01*
G01X1682546D02*
X1682502D01*
G01X1682885D02*
X1682792D01*
G01X1679185D02*
X1679037D01*
G01X1679800Y-635781D02*
X1679706D01*
G01X1680735D02*
X1680656D01*
G01X1680843D02*
X1680765D01*
G01X1681320D02*
X1681286D01*
G01X1681641D02*
X1681621D01*
G01X1682280D02*
X1682310D01*
G01X1679795Y-635756D02*
X1679677D01*
G01X1681316D02*
X1681291D01*
G01X1682305D02*
X1682285D01*
G01X1679007D02*
X1679185D01*
G01X1679391D02*
X1679421D01*
G01X1679224D02*
X1679254D01*
G01X1679460D02*
X1679637D01*
G01X1679903D02*
X1679933D01*
G01X1680120D02*
X1680149D01*
G01X1680267D02*
X1680312D01*
G01X1680587D02*
X1680617D01*
G01X1680420D02*
X1680450D01*
G01X1680656D02*
X1680843D01*
G01X1681148D02*
X1681178D01*
G01X1681626D02*
X1681645D01*
G01X1681788D02*
X1681818D01*
G01X1682054D02*
X1682098D01*
G01X1682502D02*
X1682546D01*
G01X1682763D02*
X1682881D01*
G01X1682984D02*
X1683028D01*
G01X1682423Y-635836D02*
X1682428Y-635811D01*
G01X1682615Y-635932D02*
X1682610Y-635957D01*
G01X1680223Y-635816D02*
X1680218Y-635836D01*
G01X1680381Y-635937D02*
X1680376Y-635957D01*
G01X1681547Y-635811D02*
X1681552Y-635791D01*
G01X1681719Y-635821D02*
X1681714Y-635842D01*
G01X1682009Y-635816D02*
X1682005Y-635836D01*
G01X1682167Y-635937D02*
X1682162Y-635957D01*
G01X1682457Y-635816D02*
X1682452Y-635836D01*
G01X1679824Y-635842D02*
X1679830Y-635827D01*
G01X1679854Y-635847D02*
X1679859Y-635831D01*
G01X1680346Y-635947D02*
X1680351Y-635932D01*
G01X1679421Y-635756D02*
X1679342Y-635992D01*
G01X1679322Y-635962D02*
X1679391Y-635756D01*
G01X1681247Y-635811D02*
X1681242Y-635827D01*
G01X1681360Y-635852D02*
X1681365Y-635836D01*
G01Y-635922D02*
X1681360Y-635937D01*
G01X1682133Y-635947D02*
X1682137Y-635932D01*
G01X1682236Y-635827D02*
X1682241Y-635811D01*
G01Y-635892D02*
X1682236Y-635907D01*
G01X1682354Y-635937D02*
X1682359Y-635922D01*
G01X1682580Y-635947D02*
X1682585Y-635932D01*
G01X1682910Y-635842D02*
X1682915Y-635827D01*
G01X1682944Y-635831D02*
X1682940Y-635847D01*
G01X1682915Y-635932D02*
X1682910Y-635947D01*
G01X1682944Y-635937D02*
X1682940Y-635952D01*
G01X1681227Y-635796D02*
X1681217Y-635821D01*
G01X1681380Y-635952D02*
X1681389Y-635927D01*
G01X1682221Y-635796D02*
X1682211Y-635821D01*
G01X1682374Y-635952D02*
X1682383Y-635927D01*
G01X1682546Y-635962D02*
X1682566Y-635957D01*
G01X1682905Y-635987D02*
X1682881Y-635992D01*
G01X1682570Y-635987D02*
X1682546Y-635992D01*
G01X1682310D02*
X1682334Y-635987D01*
G01X1682123D02*
X1682098Y-635992D01*
G01X1682285Y-635842D02*
X1682261Y-635847D01*
G01X1682477Y-635761D02*
X1682502Y-635756D01*
G01X1681316Y-635992D02*
X1681340Y-635987D01*
G01X1682285Y-635756D02*
X1682261Y-635761D01*
G01X1681316Y-635907D02*
X1681340Y-635902D01*
G01X1682029Y-635761D02*
X1682054Y-635756D01*
G01X1681621Y-635781D02*
X1681596Y-635786D01*
G01X1680336Y-635987D02*
X1680312Y-635992D01*
G01X1681291Y-635756D02*
X1681267Y-635761D01*
G01X1680243D02*
X1680267Y-635756D01*
G01X1681591Y-635761D02*
X1681626Y-635756D01*
G01X1680194Y-635811D02*
X1680204Y-635791D01*
G01X1681680Y-635842D02*
X1681690Y-635821D01*
G01X1681980Y-635811D02*
X1681990Y-635791D01*
G01X1682428Y-635811D02*
X1682438Y-635791D01*
G01X1681857Y-635932D02*
X1681921Y-635807D01*
G01X1681936Y-635816D02*
X1681872Y-635942D01*
G01X1682098Y-635962D02*
X1682118Y-635957D01*
G01X1682502Y-635786D02*
X1682482Y-635791D01*
G01X1682054Y-635786D02*
X1682034Y-635791D01*
G01X1680312Y-635962D02*
X1680331Y-635957D01*
G01X1680267Y-635786D02*
X1680248Y-635791D01*
G01X1680233Y-635801D02*
X1680223Y-635816D01*
G01X1681257Y-635796D02*
X1681247Y-635811D01*
G01X1681350Y-635867D02*
X1681360Y-635852D01*
G01Y-635937D02*
X1681350Y-635952D01*
G01X1681581Y-635796D02*
X1681572Y-635811D01*
G01X1681714Y-635842D02*
X1681704Y-635857D01*
G01X1682019Y-635801D02*
X1682009Y-635816D01*
G01X1682241Y-635811D02*
X1682251Y-635796D01*
G01X1682344Y-635952D02*
X1682354Y-635937D01*
G01X1682467Y-635801D02*
X1682457Y-635816D01*
G01X1679839Y-635867D02*
X1679854Y-635847D01*
G01X1681242Y-635776D02*
X1681227Y-635796D01*
G01X1681365Y-635972D02*
X1681380Y-635952D01*
G01X1682236Y-635776D02*
X1682221Y-635796D01*
G01X1682359Y-635972D02*
X1682374Y-635952D01*
G01X1682940Y-635847D02*
X1682925Y-635867D01*
G01X1682940Y-635952D02*
X1682925Y-635972D01*
G01X1681119Y-635791D02*
X1681148Y-635756D01*
G01Y-635796D02*
X1681119Y-635831D01*
G01X1681759Y-635791D02*
X1681788Y-635756D01*
G01Y-635796D02*
X1681759Y-635831D01*
G01X1679815Y-635852D02*
X1679824Y-635842D01*
G01X1680204Y-635791D02*
X1680223Y-635771D01*
G01X1680376Y-635957D02*
X1680356Y-635977D01*
G01X1681552Y-635791D02*
X1681572Y-635771D01*
G01X1681990Y-635791D02*
X1682009Y-635771D01*
G01X1682162Y-635957D02*
X1682143Y-635977D01*
G01X1682251Y-635882D02*
X1682241Y-635892D01*
G01X1682438Y-635791D02*
X1682457Y-635771D01*
G01X1682610Y-635957D02*
X1682590Y-635977D01*
G01X1682900Y-635852D02*
X1682910Y-635842D01*
G01Y-635947D02*
X1682900Y-635957D01*
G01X1681542Y-635967D02*
X1681680Y-635842D01*
G01X1681704Y-635857D02*
X1681581Y-635967D01*
G01X1682925Y-635972D02*
X1682905Y-635987D01*
G01X1680248Y-635791D02*
X1680233Y-635801D01*
G01X1680331Y-635957D02*
X1680346Y-635947D01*
G01X1681271Y-635786D02*
X1681257Y-635796D01*
G01X1681335Y-635877D02*
X1681350Y-635867D01*
G01X1681340Y-635902D02*
X1681370Y-635882D01*
G01X1681350Y-635952D02*
X1681335Y-635962D01*
G01X1681596Y-635786D02*
X1681581Y-635796D01*
G01X1682034Y-635791D02*
X1682019Y-635801D01*
G01X1682251Y-635796D02*
X1682265Y-635786D01*
G01X1682261Y-635847D02*
X1682231Y-635867D01*
G01X1682118Y-635957D02*
X1682133Y-635947D01*
G01X1682265Y-635872D02*
X1682251Y-635882D01*
G01X1682482Y-635791D02*
X1682467Y-635801D01*
G01X1682330Y-635962D02*
X1682344Y-635952D01*
G01X1682566Y-635957D02*
X1682580Y-635947D01*
G01X1681267Y-635761D02*
X1681242Y-635776D01*
G01X1681340Y-635987D02*
X1681365Y-635972D01*
G01X1682261Y-635761D02*
X1682236Y-635776D01*
G01X1682334Y-635987D02*
X1682359Y-635972D01*
G01X1679820Y-635877D02*
X1679839Y-635867D01*
G01X1680223Y-635771D02*
X1680243Y-635761D01*
G01X1680356Y-635977D02*
X1680336Y-635987D01*
G01X1681572Y-635771D02*
X1681591Y-635761D01*
G01X1682009Y-635771D02*
X1682029Y-635761D01*
G01X1682457Y-635771D02*
X1682477Y-635761D01*
G01X1682143Y-635977D02*
X1682123Y-635987D01*
G01X1682590Y-635977D02*
X1682570Y-635987D01*
G01X1682925Y-635867D02*
X1682915Y-635872D01*
G01X1679800Y-635857D02*
X1679815Y-635852D01*
G01X1681286Y-635781D02*
X1681271Y-635786D01*
G01X1681320Y-635882D02*
X1681335Y-635877D01*
G01Y-635962D02*
X1681320Y-635967D01*
G01X1682265Y-635786D02*
X1682280Y-635781D01*
G01Y-635867D02*
X1682265Y-635872D01*
G01X1682315Y-635967D02*
X1682330Y-635962D01*
G01X1682885Y-635857D02*
X1682900Y-635852D01*
G01Y-635957D02*
X1682885Y-635962D01*
G01X1678220Y-634090D02*
Y-633079D01*
G01Y-634090D02*
Y-633079D01*
G01X1687275D02*
X1677777D01*
G01X1678220D02*
X1677777D01*
G01X1675991Y-629005D02*
X1668896Y-601832D01*
G01D02*
X1662302Y-553358D01*
G01X1674519Y-589496D02*
Y-588315D01*
G01X1674667Y-589094D02*
Y-589496D01*
G01Y-588315D02*
Y-588893D01*
G01X1674677Y-585835D02*
Y-592134D01*
G01X1679854Y-588552D02*
X1679839Y-588532D01*
G01X1681232Y-588708D02*
X1681247Y-588728D01*
G01X1681227Y-588623D02*
X1681242Y-588643D01*
G01X1681380Y-588552D02*
X1681365Y-588532D01*
G01X1682221Y-588708D02*
X1682236Y-588728D01*
G01X1682369Y-588552D02*
X1682354Y-588532D01*
G01X1682925Y-588632D02*
X1682940Y-588653D01*
G01X1682925Y-588532D02*
X1682940Y-588552D01*
G01X1680223Y-588688D02*
X1680233Y-588703D01*
G01X1681261Y-588708D02*
X1681252Y-588693D01*
G01X1681247Y-588608D02*
X1681257Y-588623D01*
G01X1681360Y-588567D02*
X1681350Y-588552D01*
G01X1681690Y-588567D02*
X1681680Y-588552D01*
G01X1682009Y-588688D02*
X1682019Y-588703D01*
G01X1682241Y-588693D02*
X1682251Y-588708D01*
G01X1682339Y-588552D02*
X1682349Y-588567D01*
G01X1682457Y-588688D02*
X1682467Y-588703D01*
G01X1675208Y-589496D02*
X1674839Y-588918D01*
G01X1674962Y-588793D02*
X1675405Y-589496D01*
G01X1680204Y-588713D02*
X1680194Y-588693D01*
G01X1681990Y-588713D02*
X1681980Y-588693D01*
G01X1682438Y-588713D02*
X1682428Y-588693D01*
G01X1681217Y-588597D02*
X1681227Y-588623D01*
G01X1681389Y-588577D02*
X1681380Y-588552D01*
G01X1682211Y-588683D02*
X1682221Y-588708D01*
G01X1682383Y-588658D02*
X1682374Y-588632D01*
G01X1679864Y-588748D02*
X1679820Y-588632D01*
G01X1679790Y-588643D02*
X1679830Y-588748D01*
G01X1679254Y-588512D02*
X1679322Y-588718D01*
G01X1679303Y-588748D02*
X1679224Y-588512D01*
G01X1679830Y-588567D02*
X1679824Y-588552D01*
G01X1679859Y-588567D02*
X1679854Y-588552D01*
G01X1680351Y-588572D02*
X1680346Y-588557D01*
G01X1681227Y-588693D02*
X1681232Y-588708D01*
G01X1681242Y-588592D02*
X1681247Y-588608D01*
G01X1681365Y-588582D02*
X1681360Y-588567D01*
G01X1682137Y-588572D02*
X1682133Y-588557D01*
G01X1682236Y-588678D02*
X1682241Y-588693D01*
G01X1682359Y-588663D02*
X1682354Y-588648D01*
G01X1682374Y-588567D02*
X1682369Y-588552D01*
G01X1682585Y-588572D02*
X1682580Y-588557D01*
G01X1682910Y-588658D02*
X1682915Y-588673D01*
G01X1682940Y-588653D02*
X1682944Y-588668D01*
G01X1682915Y-588572D02*
X1682910Y-588557D01*
G01X1682940Y-588552D02*
X1682944Y-588567D01*
G01X1680218Y-588668D02*
X1680223Y-588688D01*
G01X1681714Y-588547D02*
X1681719Y-588567D01*
G01X1682005Y-588668D02*
X1682009Y-588688D01*
G01X1682452Y-588668D02*
X1682457Y-588688D01*
G01X1680194Y-588693D02*
X1680189Y-588668D01*
G01X1680376Y-588547D02*
X1680381Y-588572D01*
G01X1681980Y-588693D02*
X1681975Y-588668D01*
G01X1682162Y-588547D02*
X1682167Y-588572D01*
G01X1682428Y-588693D02*
X1682423Y-588668D01*
G01X1682610Y-588547D02*
X1682615Y-588572D01*
G01X1681394Y-588612D02*
X1681389Y-588577D01*
G01X1676252Y-592134D02*
Y-585835D01*
G01X1676580D02*
Y-592134D01*
G01X1678220D02*
Y-585835D01*
G01Y-592134D02*
Y-585835D01*
G01X1679007Y-588748D02*
Y-588512D01*
G01X1679037Y-588638D02*
Y-588718D01*
G01Y-588542D02*
Y-588608D01*
G01X1679165D02*
Y-588638D01*
G01X1679185Y-588512D02*
Y-588542D01*
G01Y-588718D02*
Y-588748D01*
G01X1679460D02*
Y-588512D01*
G01X1679490Y-588638D02*
Y-588718D01*
G01Y-588542D02*
Y-588608D01*
G01X1679618D02*
Y-588638D01*
G01X1679637Y-588512D02*
Y-588542D01*
G01Y-588718D02*
Y-588748D01*
G01X1679677Y-588512D02*
Y-588748D01*
G01X1679706Y-588537D02*
Y-588612D01*
G01Y-588748D02*
Y-588643D01*
G01X1679830Y-588582D02*
Y-588567D01*
G01X1679859Y-588587D02*
Y-588567D01*
G01X1679903Y-588748D02*
Y-588512D01*
G01X1679933D02*
Y-588718D01*
G01X1680080D02*
Y-588748D01*
G01X1680120D02*
Y-588512D01*
G01X1680149D02*
Y-588748D01*
G01X1680189Y-588668D02*
Y-588592D01*
G01X1680218D02*
Y-588668D01*
G01X1680307Y-588648D02*
Y-588618D01*
G01X1680351Y-588688D02*
Y-588648D01*
G01X1680381Y-588618D02*
Y-588693D01*
G01X1680420Y-588748D02*
Y-588512D01*
G01X1680450Y-588638D02*
Y-588748D01*
G01Y-588512D02*
Y-588608D01*
G01X1680587Y-588748D02*
Y-588638D01*
G01Y-588608D02*
Y-588512D01*
G01X1680617D02*
Y-588748D01*
G01X1680656Y-588537D02*
Y-588512D01*
G01X1680735Y-588748D02*
Y-588537D01*
G01X1680765D02*
Y-588748D01*
G01X1680843Y-588512D02*
Y-588537D01*
G01X1681119Y-588587D02*
Y-588547D01*
G01X1681148Y-588748D02*
Y-588552D01*
G01X1681178Y-588512D02*
Y-588748D01*
G01X1681217Y-588577D02*
Y-588597D01*
G01X1681242Y-588582D02*
Y-588592D01*
G01X1681365D02*
Y-588582D01*
G01X1681370Y-588638D02*
Y-588648D01*
G01X1681394D02*
Y-588612D01*
G01X1681434Y-588663D02*
Y-588638D01*
G01X1681503D02*
Y-588663D01*
G01X1681542Y-588748D02*
Y-588723D01*
G01X1681690Y-588577D02*
Y-588567D01*
G01X1681719Y-588723D02*
Y-588748D01*
G01Y-588567D02*
Y-588577D01*
G01X1681759Y-588587D02*
Y-588547D01*
G01X1681788Y-588748D02*
Y-588552D01*
G01X1681818Y-588512D02*
Y-588748D01*
G01X1681975Y-588668D02*
Y-588592D01*
G01X1682005D02*
Y-588668D01*
G01X1682093Y-588648D02*
Y-588618D01*
G01X1682137Y-588688D02*
Y-588648D01*
G01X1682167Y-588618D02*
Y-588693D01*
G01X1682206Y-588612D02*
Y-588648D01*
G01X1682231Y-588623D02*
Y-588612D01*
G01X1682236Y-588663D02*
Y-588678D01*
G01X1682359D02*
Y-588663D01*
G01X1682383Y-588683D02*
Y-588658D01*
G01X1682423Y-588668D02*
Y-588592D01*
G01X1682452D02*
Y-588668D01*
G01X1682654Y-588663D02*
Y-588638D01*
G01X1682723D02*
Y-588663D01*
G01X1682763Y-588748D02*
Y-588512D01*
G01X1682792Y-588542D02*
Y-588612D01*
G01Y-588718D02*
Y-588643D01*
G01X1682915Y-588673D02*
Y-588688D01*
G01Y-588582D02*
Y-588572D01*
G01X1682944Y-588567D02*
Y-588587D01*
G01Y-588668D02*
Y-588693D01*
G01X1682984Y-588748D02*
Y-588512D01*
G01X1680233Y-588703D02*
X1680248Y-588713D01*
G01X1680346Y-588557D02*
X1680331Y-588547D01*
G01X1681276Y-588718D02*
X1681261Y-588708D01*
G01X1681257Y-588623D02*
X1681271Y-588632D01*
G01X1679839Y-588532D02*
X1679820Y-588517D01*
G01X1682905D02*
X1682925Y-588532D01*
G01X1682900Y-588648D02*
X1682910Y-588658D01*
G01Y-588557D02*
X1682900Y-588547D01*
G01X1679824Y-588552D02*
X1679815Y-588542D01*
G01X1680223Y-588733D02*
X1680204Y-588713D01*
G01X1680356Y-588527D02*
X1680376Y-588547D01*
G01X1681694Y-588527D02*
X1681714Y-588547D01*
G01X1682009Y-588733D02*
X1681990Y-588713D01*
G01X1682143Y-588527D02*
X1682162Y-588547D01*
G01X1682354Y-588648D02*
X1682344Y-588638D01*
G01X1682457Y-588733D02*
X1682438Y-588713D01*
G01X1682374Y-588632D02*
X1682359Y-588618D01*
G01X1682590Y-588527D02*
X1682610Y-588547D01*
G01X1682206Y-588648D02*
X1682211Y-588683D01*
G01X1681389D02*
X1681394Y-588648D01*
G01X1682211Y-588577D02*
X1682206Y-588612D01*
G01X1681370Y-588648D02*
X1681365Y-588678D01*
G01X1682231Y-588612D02*
X1682236Y-588582D01*
G01X1680189Y-588592D02*
X1680194Y-588567D01*
G01X1681975Y-588592D02*
X1681980Y-588567D01*
G01X1682423Y-588592D02*
X1682428Y-588567D01*
G01X1682615Y-588688D02*
X1682610Y-588713D01*
G01X1680223Y-588572D02*
X1680218Y-588592D01*
G01X1680381Y-588693D02*
X1680376Y-588713D01*
G01X1681547Y-588567D02*
X1681552Y-588547D01*
G01X1681719Y-588577D02*
X1681714Y-588597D01*
G01X1682009Y-588572D02*
X1682005Y-588592D01*
G01X1682167Y-588693D02*
X1682162Y-588713D01*
G01X1682457Y-588572D02*
X1682452Y-588592D01*
G01X1679824Y-588597D02*
X1679830Y-588582D01*
G01X1679854Y-588603D02*
X1679859Y-588587D01*
G01X1680346Y-588703D02*
X1680351Y-588688D01*
G01X1679421Y-588512D02*
X1679342Y-588748D01*
G01X1679322Y-588718D02*
X1679391Y-588512D01*
G01X1680243Y-588743D02*
X1680223Y-588733D01*
G01X1680336Y-588517D02*
X1680356Y-588527D01*
G01X1682029Y-588743D02*
X1682009Y-588733D01*
G01X1681675Y-588517D02*
X1681694Y-588527D01*
G01X1682477Y-588743D02*
X1682457Y-588733D01*
G01X1682123Y-588517D02*
X1682143Y-588527D01*
G01X1682570Y-588517D02*
X1682590Y-588527D01*
G01X1682915Y-588628D02*
X1682925Y-588632D01*
G01X1681247Y-588728D02*
X1681271Y-588743D01*
G01X1681242Y-588643D02*
X1681267Y-588658D01*
G01X1681365Y-588532D02*
X1681340Y-588517D01*
G01X1682236Y-588728D02*
X1682261Y-588743D01*
G01X1682359Y-588618D02*
X1682334Y-588603D01*
G01X1682354Y-588532D02*
X1682330Y-588517D01*
G01X1681350Y-588552D02*
X1681335Y-588542D01*
G01X1681872Y-588698D02*
X1681857Y-588688D01*
G01X1681680Y-588552D02*
X1681665Y-588542D01*
G01X1682019Y-588703D02*
X1682034Y-588713D01*
G01X1681921Y-588562D02*
X1681936Y-588572D01*
G01X1682251Y-588708D02*
X1682265Y-588718D01*
G01X1682133Y-588557D02*
X1682118Y-588547D01*
G01X1682344Y-588638D02*
X1682330Y-588628D01*
G01X1682467Y-588703D02*
X1682482Y-588713D01*
G01X1682324Y-588542D02*
X1682339Y-588552D01*
G01X1682580Y-588557D02*
X1682566Y-588547D01*
G01X1681247Y-588567D02*
X1681242Y-588582D01*
G01X1681360Y-588608D02*
X1681365Y-588592D01*
G01Y-588678D02*
X1681360Y-588693D01*
G01X1682133Y-588703D02*
X1682137Y-588688D01*
G01X1682236Y-588582D02*
X1682241Y-588567D01*
G01Y-588648D02*
X1682236Y-588663D01*
G01X1682354Y-588693D02*
X1682359Y-588678D01*
G01X1682580Y-588703D02*
X1682585Y-588688D01*
G01X1682910Y-588597D02*
X1682915Y-588582D01*
G01X1682944Y-588587D02*
X1682940Y-588603D01*
G01X1682915Y-588688D02*
X1682910Y-588703D01*
G01X1682944Y-588693D02*
X1682940Y-588708D01*
G01X1681227Y-588552D02*
X1681217Y-588577D01*
G01X1681380Y-588708D02*
X1681389Y-588683D01*
G01X1682221Y-588552D02*
X1682211Y-588577D01*
G01X1682374Y-588708D02*
X1682383Y-588683D01*
G01X1680194Y-588567D02*
X1680204Y-588547D01*
G01X1681680Y-588597D02*
X1681690Y-588577D01*
G01X1681980Y-588567D02*
X1681990Y-588547D01*
G01X1679815Y-588542D02*
X1679800Y-588537D01*
G01X1681291Y-588723D02*
X1681276Y-588718D01*
G01X1681271Y-588632D02*
X1681286Y-588638D01*
G01X1681335Y-588542D02*
X1681320Y-588537D01*
G01X1682265Y-588718D02*
X1682280Y-588723D01*
G01X1682330Y-588628D02*
X1682315Y-588623D01*
G01X1682310Y-588537D02*
X1682324Y-588542D01*
G01X1682885Y-588643D02*
X1682900Y-588648D01*
G01Y-588547D02*
X1682885Y-588542D01*
G01X1682428Y-588567D02*
X1682438Y-588547D01*
G01X1681857Y-588688D02*
X1681921Y-588562D01*
G01X1681936Y-588572D02*
X1681872Y-588698D01*
G01X1680233Y-588557D02*
X1680223Y-588572D01*
G01X1681257Y-588552D02*
X1681247Y-588567D01*
G01X1681350Y-588623D02*
X1681360Y-588608D01*
G01Y-588693D02*
X1681350Y-588708D01*
G01X1681581Y-588552D02*
X1681572Y-588567D01*
G01X1681714Y-588597D02*
X1681704Y-588612D01*
G01X1682019Y-588557D02*
X1682009Y-588572D01*
G01X1682241Y-588567D02*
X1682251Y-588552D01*
G01X1682344Y-588708D02*
X1682354Y-588693D01*
G01X1682467Y-588557D02*
X1682457Y-588572D01*
G01X1681645Y-588512D02*
X1681675Y-588517D01*
G01X1680267Y-588748D02*
X1680243Y-588743D01*
G01X1679820Y-588517D02*
X1679795Y-588512D01*
G01X1681271Y-588743D02*
X1681296Y-588748D01*
G01X1680312Y-588512D02*
X1680336Y-588517D01*
G01X1681267Y-588658D02*
X1681291Y-588663D01*
G01X1682054Y-588748D02*
X1682029Y-588743D01*
G01X1682261D02*
X1682285Y-588748D01*
G01X1681340Y-588517D02*
X1681316Y-588512D01*
G01X1682502Y-588748D02*
X1682477Y-588743D01*
G01X1681665Y-588542D02*
X1681641Y-588537D01*
G01X1682334Y-588603D02*
X1682310Y-588597D01*
G01X1682098Y-588512D02*
X1682123Y-588517D01*
G01X1682330D02*
X1682305Y-588512D01*
G01X1682546D02*
X1682570Y-588517D01*
G01X1682881Y-588512D02*
X1682905Y-588517D01*
G01X1682482Y-588713D02*
X1682502Y-588718D01*
G01X1682118Y-588547D02*
X1682098Y-588542D01*
G01X1680248Y-588713D02*
X1680267Y-588718D01*
G01X1680331Y-588547D02*
X1680312Y-588542D01*
G01X1682034Y-588713D02*
X1682054Y-588718D01*
G01X1682566Y-588547D02*
X1682546Y-588542D01*
G01X1679839Y-588623D02*
X1679854Y-588603D01*
G01X1681242Y-588532D02*
X1681227Y-588552D01*
G01X1681365Y-588728D02*
X1681380Y-588708D01*
G01X1682236Y-588532D02*
X1682221Y-588552D01*
G01X1682359Y-588728D02*
X1682374Y-588708D01*
G01X1682940Y-588603D02*
X1682925Y-588623D01*
G01X1682940Y-588708D02*
X1682925Y-588728D01*
G01X1681119Y-588547D02*
X1681148Y-588512D01*
G01Y-588552D02*
X1681119Y-588587D01*
G01X1681759Y-588547D02*
X1681788Y-588512D01*
G01Y-588552D02*
X1681759Y-588587D01*
G01X1675405Y-588315D02*
X1674962Y-588793D01*
G01X1674667Y-588893D02*
X1675208Y-588315D01*
G01X1674677Y-592134D02*
X1687275D01*
G01X1674839Y-588918D02*
X1674667Y-589094D01*
G01X1679815Y-588608D02*
X1679824Y-588597D01*
G01X1680204Y-588547D02*
X1680223Y-588527D01*
G01X1680376Y-588713D02*
X1680356Y-588733D01*
G01X1681552Y-588547D02*
X1681572Y-588527D01*
G01X1681990Y-588547D02*
X1682009Y-588527D01*
G01X1682162Y-588713D02*
X1682143Y-588733D01*
G01X1682251Y-588638D02*
X1682241Y-588648D01*
G01X1682438Y-588547D02*
X1682457Y-588527D01*
G01X1682610Y-588713D02*
X1682590Y-588733D01*
G01X1682900Y-588608D02*
X1682910Y-588597D01*
G01Y-588703D02*
X1682900Y-588713D01*
G01X1681542Y-588723D02*
X1681680Y-588597D01*
G01X1675405Y-589496D02*
X1675208D01*
G01X1674667D02*
X1674519D01*
G01X1679342Y-588748D02*
X1679303D01*
G01X1679637D02*
X1679460D01*
G01X1680080D02*
X1679903D01*
G01X1680149D02*
X1680120D01*
G01X1680312D02*
X1680267D01*
G01X1680617D02*
X1680587D01*
G01X1680450D02*
X1680420D01*
G01X1680765D02*
X1680735D01*
G01X1681178D02*
X1681148D01*
G01X1681719D02*
X1681542D01*
G01X1681818D02*
X1681788D01*
G01X1682098D02*
X1682054D01*
G01X1682546D02*
X1682502D01*
G01X1682881D02*
X1682763D01*
G01X1683013D02*
X1682984D01*
G01X1679185D02*
X1679007D01*
G01X1679830D02*
X1679864D01*
G01X1679677D02*
X1679706D01*
G01X1681296D02*
X1681316D01*
G01X1682285D02*
X1682310D01*
G01X1681320Y-588723D02*
X1681291D01*
G01X1681581D02*
X1681719D01*
G01X1682280D02*
X1682315D01*
G01X1682885Y-588718D02*
X1682792D01*
G01X1679037D02*
X1679185D01*
G01X1679490D02*
X1679637D01*
G01X1679933D02*
X1680080D01*
G01X1680267D02*
X1680312D01*
G01X1682054D02*
X1682098D01*
G01X1682502D02*
X1682546D01*
G01X1681252Y-588693D02*
X1681227D01*
G01X1682585Y-588688D02*
X1682615D01*
G01X1681503Y-588663D02*
X1681434D01*
G01X1682723D02*
X1682654D01*
G01X1681291D02*
X1681316D01*
G01X1680351Y-588648D02*
X1680307D01*
G01X1682137D02*
X1682093D01*
G01X1679706Y-588643D02*
X1679790D01*
G01X1682792D02*
X1682885D01*
G01X1679618Y-588638D02*
X1679490D01*
G01X1680587D02*
X1680450D01*
G01X1679165D02*
X1679037D01*
G01X1681286D02*
X1681320D01*
G01X1681434D02*
X1681503D01*
G01X1682654D02*
X1682723D01*
G01X1682315Y-588623D02*
X1682280D01*
G01X1680307Y-588618D02*
X1680381D01*
G01X1682093D02*
X1682167D01*
G01X1679706Y-588612D02*
X1679800D01*
G01X1682792D02*
X1682885D01*
G01X1679037Y-588608D02*
X1679165D01*
G01X1679490D02*
X1679618D01*
G01X1680450D02*
X1680587D01*
G01X1682310Y-588597D02*
X1682285D01*
G01X1680381Y-588572D02*
X1680351D01*
G01X1682167D02*
X1682137D01*
G01X1682615D02*
X1682585D01*
G01X1681572Y-588567D02*
X1681547D01*
G01X1682349D02*
X1682374D01*
G01X1679637Y-588542D02*
X1679490D01*
G01X1680312D02*
X1680267D01*
G01X1682098D02*
X1682054D01*
G01X1682546D02*
X1682502D01*
G01X1682885D02*
X1682792D01*
G01X1679185D02*
X1679037D01*
G01X1679800Y-588537D02*
X1679706D01*
G01X1680735D02*
X1680656D01*
G01X1680843D02*
X1680765D01*
G01X1681320D02*
X1681286D01*
G01X1681641D02*
X1681621D01*
G01X1682280D02*
X1682310D01*
G01X1679795Y-588512D02*
X1679677D01*
G01X1681316D02*
X1681291D01*
G01X1682305D02*
X1682285D01*
G01X1679007D02*
X1679185D01*
G01X1679391D02*
X1679421D01*
G01X1679224D02*
X1679254D01*
G01X1679460D02*
X1679637D01*
G01X1679903D02*
X1679933D01*
G01X1680120D02*
X1680149D01*
G01X1680267D02*
X1680312D01*
G01X1680587D02*
X1680617D01*
G01X1680420D02*
X1680450D01*
G01X1680656D02*
X1680843D01*
G01X1681148D02*
X1681178D01*
G01X1681626D02*
X1681645D01*
G01X1681788D02*
X1681818D01*
G01X1682054D02*
X1682098D01*
G01X1682502D02*
X1682546D01*
G01X1682763D02*
X1682881D01*
G01X1682984D02*
X1683028D01*
G01X1675208Y-588315D02*
X1675405D01*
G01X1674519D02*
X1674667D01*
G01X1687275Y-585835D02*
X1674677D01*
G01X1681704Y-588612D02*
X1681581Y-588723D01*
G01X1682925Y-588728D02*
X1682905Y-588743D01*
G01D02*
X1682881Y-588748D01*
G01X1682570Y-588743D02*
X1682546Y-588748D01*
G01X1682310D02*
X1682334Y-588743D01*
G01X1682123D02*
X1682098Y-588748D01*
G01X1682285Y-588597D02*
X1682261Y-588603D01*
G01X1682477Y-588517D02*
X1682502Y-588512D01*
G01X1681316Y-588748D02*
X1681340Y-588743D01*
G01X1682285Y-588512D02*
X1682261Y-588517D01*
G01X1681316Y-588663D02*
X1681340Y-588658D01*
G01X1682029Y-588517D02*
X1682054Y-588512D01*
G01X1681621Y-588537D02*
X1681596Y-588542D01*
G01X1680336Y-588743D02*
X1680312Y-588748D01*
G01X1681291Y-588512D02*
X1681267Y-588517D01*
G01X1680243D02*
X1680267Y-588512D01*
G01X1681591Y-588517D02*
X1681626Y-588512D01*
G01X1680248Y-588547D02*
X1680233Y-588557D01*
G01X1680331Y-588713D02*
X1680346Y-588703D01*
G01X1681271Y-588542D02*
X1681257Y-588552D01*
G01X1681335Y-588632D02*
X1681350Y-588623D01*
G01X1681340Y-588658D02*
X1681370Y-588638D01*
G01X1681350Y-588708D02*
X1681335Y-588718D01*
G01X1681596Y-588542D02*
X1681581Y-588552D01*
G01X1682034Y-588547D02*
X1682019Y-588557D01*
G01X1682251Y-588552D02*
X1682265Y-588542D01*
G01X1682261Y-588603D02*
X1682231Y-588623D01*
G01X1682118Y-588713D02*
X1682133Y-588703D01*
G01X1682265Y-588628D02*
X1682251Y-588638D01*
G01X1682482Y-588547D02*
X1682467Y-588557D01*
G01X1682330Y-588718D02*
X1682344Y-588708D01*
G01X1682566Y-588713D02*
X1682580Y-588703D01*
G01X1681267Y-588517D02*
X1681242Y-588532D01*
G01X1681340Y-588743D02*
X1681365Y-588728D01*
G01X1682261Y-588517D02*
X1682236Y-588532D01*
G01X1682334Y-588743D02*
X1682359Y-588728D01*
G01X1682546Y-588718D02*
X1682566Y-588713D01*
G01X1682098Y-588718D02*
X1682118Y-588713D01*
G01X1682502Y-588542D02*
X1682482Y-588547D01*
G01X1682054Y-588542D02*
X1682034Y-588547D01*
G01X1680312Y-588718D02*
X1680331Y-588713D01*
G01X1680267Y-588542D02*
X1680248Y-588547D01*
G01X1679820Y-588632D02*
X1679839Y-588623D01*
G01X1680223Y-588527D02*
X1680243Y-588517D01*
G01X1680356Y-588733D02*
X1680336Y-588743D01*
G01X1681572Y-588527D02*
X1681591Y-588517D01*
G01X1682009Y-588527D02*
X1682029Y-588517D01*
G01X1682457Y-588527D02*
X1682477Y-588517D01*
G01X1682143Y-588733D02*
X1682123Y-588743D01*
G01X1682590Y-588733D02*
X1682570Y-588743D01*
G01X1682925Y-588623D02*
X1682915Y-588628D01*
G01X1679800Y-588612D02*
X1679815Y-588608D01*
G01X1681286Y-588537D02*
X1681271Y-588542D01*
G01X1681320Y-588638D02*
X1681335Y-588632D01*
G01Y-588718D02*
X1681320Y-588723D01*
G01X1682265Y-588542D02*
X1682280Y-588537D01*
G01Y-588623D02*
X1682265Y-588628D01*
G01X1682315Y-588723D02*
X1682330Y-588718D01*
G01X1682885Y-588612D02*
X1682900Y-588608D01*
G01Y-588713D02*
X1682885Y-588718D01*
G01X1671921Y-585835D02*
Y-592134D01*
G01Y-585835D02*
Y-592134D01*
G01D02*
X1674677D01*
G01X1671921D02*
X1678220D01*
G01X1674677Y-585835D02*
X1671921D01*
G01X1678220D02*
X1671921D01*
G01X1674519Y-542252D02*
Y-541071D01*
G01X1674667D02*
Y-541649D01*
G01Y-541850D02*
Y-542252D01*
G01X1674677Y-538591D02*
Y-544890D01*
G01X1676252D02*
Y-538591D01*
G01X1676580D02*
Y-544890D01*
G01X1678220D02*
Y-538591D01*
G01Y-544890D02*
Y-538591D01*
G01X1679007Y-541504D02*
Y-541268D01*
G01X1679037Y-541394D02*
Y-541474D01*
G01Y-541298D02*
Y-541364D01*
G01X1679165D02*
Y-541394D01*
G01X1679185Y-541268D02*
Y-541298D01*
G01Y-541474D02*
Y-541504D01*
G01X1679460D02*
Y-541268D01*
G01X1679490Y-541394D02*
Y-541474D01*
G01Y-541298D02*
Y-541364D01*
G01X1679618D02*
Y-541394D01*
G01X1679637Y-541268D02*
Y-541298D01*
G01Y-541474D02*
Y-541504D01*
G01X1679677Y-541268D02*
Y-541504D01*
G01X1679706Y-541293D02*
Y-541368D01*
G01Y-541504D02*
Y-541399D01*
G01X1679830Y-541338D02*
Y-541323D01*
G01X1679859Y-541343D02*
Y-541323D01*
G01X1679903Y-541504D02*
Y-541268D01*
G01X1679933D02*
Y-541474D01*
G01X1680080D02*
Y-541504D01*
G01X1680120D02*
Y-541268D01*
G01X1680149D02*
Y-541504D01*
G01X1680189Y-541424D02*
Y-541348D01*
G01X1680218D02*
Y-541424D01*
G01X1680307Y-541404D02*
Y-541373D01*
G01X1680351Y-541444D02*
Y-541404D01*
G01X1680381Y-541373D02*
Y-541449D01*
G01X1680420Y-541504D02*
Y-541268D01*
G01X1680450Y-541394D02*
Y-541504D01*
G01Y-541268D02*
Y-541364D01*
G01X1680587Y-541504D02*
Y-541394D01*
G01Y-541364D02*
Y-541268D01*
G01X1680617D02*
Y-541504D01*
G01X1680656Y-541293D02*
Y-541268D01*
G01X1680735Y-541504D02*
Y-541293D01*
G01X1680765D02*
Y-541504D01*
G01X1680843Y-541268D02*
Y-541293D01*
G01X1681119Y-541343D02*
Y-541303D01*
G01X1681148Y-541504D02*
Y-541308D01*
G01X1681178Y-541268D02*
Y-541504D01*
G01X1681217Y-541333D02*
Y-541353D01*
G01X1681242Y-541338D02*
Y-541348D01*
G01X1681365D02*
Y-541338D01*
G01X1681370Y-541394D02*
Y-541404D01*
G01X1681394D02*
Y-541368D01*
G01X1681434Y-541419D02*
Y-541394D01*
G01X1681503D02*
Y-541419D01*
G01X1681542Y-541504D02*
Y-541479D01*
G01X1681690Y-541333D02*
Y-541323D01*
G01X1681719D02*
Y-541333D01*
G01Y-541479D02*
Y-541504D01*
G01X1681759Y-541343D02*
Y-541303D01*
G01X1681788Y-541504D02*
Y-541308D01*
G01X1681818Y-541268D02*
Y-541504D01*
G01X1681975Y-541424D02*
Y-541348D01*
G01X1682005D02*
Y-541424D01*
G01X1682093Y-541404D02*
Y-541373D01*
G01X1682137Y-541444D02*
Y-541404D01*
G01X1682167Y-541373D02*
Y-541449D01*
G01X1682206Y-541368D02*
Y-541404D01*
G01X1682231Y-541379D02*
Y-541368D01*
G01X1682236Y-541419D02*
Y-541434D01*
G01X1682359D02*
Y-541419D01*
G01X1682383Y-541439D02*
Y-541414D01*
G01X1682423Y-541424D02*
Y-541348D01*
G01X1682452D02*
Y-541424D01*
G01X1682654Y-541419D02*
Y-541394D01*
G01X1682723D02*
Y-541419D01*
G01X1682763Y-541504D02*
Y-541268D01*
G01X1682792Y-541298D02*
Y-541368D01*
G01Y-541474D02*
Y-541399D01*
G01X1682915Y-541429D02*
Y-541444D01*
G01Y-541338D02*
Y-541328D01*
G01X1682944Y-541323D02*
Y-541343D01*
G01Y-541424D02*
Y-541449D01*
G01X1682984Y-541504D02*
Y-541268D01*
G01X1681389Y-541439D02*
X1681394Y-541404D01*
G01X1682211Y-541333D02*
X1682206Y-541368D01*
G01X1681370Y-541404D02*
X1681365Y-541434D01*
G01X1682231Y-541368D02*
X1682236Y-541338D01*
G01X1680189Y-541348D02*
X1680194Y-541323D01*
G01X1681975Y-541348D02*
X1681980Y-541323D01*
G01X1682423Y-541348D02*
X1682428Y-541323D01*
G01X1682615Y-541444D02*
X1682610Y-541469D01*
G01X1680223Y-541328D02*
X1680218Y-541348D01*
G01X1680381Y-541449D02*
X1680376Y-541469D01*
G01X1681547Y-541323D02*
X1681552Y-541303D01*
G01X1681719Y-541333D02*
X1681714Y-541353D01*
G01X1682009Y-541328D02*
X1682005Y-541348D01*
G01X1682167Y-541449D02*
X1682162Y-541469D01*
G01X1682457Y-541328D02*
X1682452Y-541348D01*
G01X1679824Y-541353D02*
X1679830Y-541338D01*
G01X1679854Y-541358D02*
X1679859Y-541343D01*
G01X1680346Y-541459D02*
X1680351Y-541444D01*
G01X1681247Y-541323D02*
X1681242Y-541338D01*
G01X1681360Y-541364D02*
X1681365Y-541348D01*
G01Y-541434D02*
X1681360Y-541449D01*
G01X1679421Y-541268D02*
X1679342Y-541504D01*
G01X1679322Y-541474D02*
X1679391Y-541268D01*
G01X1681217Y-541353D02*
X1681227Y-541379D01*
G01X1681389Y-541333D02*
X1681380Y-541308D01*
G01X1682211Y-541439D02*
X1682221Y-541464D01*
G01X1682383Y-541414D02*
X1682374Y-541388D01*
G01X1679864Y-541504D02*
X1679820Y-541388D01*
G01X1679790Y-541399D02*
X1679830Y-541504D01*
G01X1679254Y-541268D02*
X1679322Y-541474D01*
G01X1679303Y-541504D02*
X1679224Y-541268D01*
G01X1679830Y-541323D02*
X1679824Y-541308D01*
G01X1679859Y-541323D02*
X1679854Y-541308D01*
G01X1680351Y-541328D02*
X1680346Y-541313D01*
G01X1681227Y-541449D02*
X1681232Y-541464D01*
G01X1681242Y-541348D02*
X1681247Y-541364D01*
G01X1681365Y-541338D02*
X1681360Y-541323D01*
G01X1682137Y-541328D02*
X1682133Y-541313D01*
G01X1682236Y-541434D02*
X1682241Y-541449D01*
G01X1682359Y-541419D02*
X1682354Y-541404D01*
G01X1682374Y-541323D02*
X1682369Y-541308D01*
G01X1682585Y-541328D02*
X1682580Y-541313D01*
G01X1682910Y-541414D02*
X1682915Y-541429D01*
G01X1682940Y-541408D02*
X1682944Y-541424D01*
G01X1682915Y-541328D02*
X1682910Y-541313D01*
G01X1682940Y-541308D02*
X1682944Y-541323D01*
G01X1680218Y-541424D02*
X1680223Y-541444D01*
G01X1681714Y-541303D02*
X1681719Y-541323D01*
G01X1682005Y-541424D02*
X1682009Y-541444D01*
G01X1682452Y-541424D02*
X1682457Y-541444D01*
G01X1680194Y-541449D02*
X1680189Y-541424D01*
G01X1680376Y-541303D02*
X1680381Y-541328D01*
G01X1681980Y-541449D02*
X1681975Y-541424D01*
G01X1682162Y-541303D02*
X1682167Y-541328D01*
G01X1682428Y-541449D02*
X1682423Y-541424D01*
G01X1682610Y-541303D02*
X1682615Y-541328D01*
G01X1681394Y-541368D02*
X1681389Y-541333D01*
G01X1682206Y-541404D02*
X1682211Y-541439D01*
G01X1682133Y-541459D02*
X1682137Y-541444D01*
G01X1682236Y-541338D02*
X1682241Y-541323D01*
G01Y-541404D02*
X1682236Y-541419D01*
G01X1682354Y-541449D02*
X1682359Y-541434D01*
G01X1682580Y-541459D02*
X1682585Y-541444D01*
G01X1682910Y-541353D02*
X1682915Y-541338D01*
G01X1682944Y-541343D02*
X1682940Y-541358D01*
G01X1682915Y-541444D02*
X1682910Y-541459D01*
G01X1682944Y-541449D02*
X1682940Y-541464D01*
G01X1681227Y-541308D02*
X1681217Y-541333D01*
G01X1681380Y-541464D02*
X1681389Y-541439D01*
G01X1682221Y-541308D02*
X1682211Y-541333D01*
G01X1682374Y-541464D02*
X1682383Y-541439D01*
G01X1680194Y-541323D02*
X1680204Y-541303D01*
G01X1681680Y-541353D02*
X1681690Y-541333D01*
G01X1681980Y-541323D02*
X1681990Y-541303D01*
G01X1682428Y-541323D02*
X1682438Y-541303D01*
G01X1681857Y-541444D02*
X1681921Y-541318D01*
G01X1681936Y-541328D02*
X1681872Y-541454D01*
G01X1680233Y-541313D02*
X1680223Y-541328D01*
G01X1679854Y-541308D02*
X1679839Y-541288D01*
G01X1681232Y-541464D02*
X1681247Y-541484D01*
G01X1681227Y-541379D02*
X1681242Y-541399D01*
G01X1681380Y-541308D02*
X1681365Y-541288D01*
G01X1682221Y-541464D02*
X1682236Y-541484D01*
G01X1682369Y-541308D02*
X1682354Y-541288D01*
G01X1682925Y-541388D02*
X1682940Y-541408D01*
G01X1682925Y-541288D02*
X1682940Y-541308D01*
G01X1680223Y-541444D02*
X1680233Y-541459D01*
G01X1681261Y-541464D02*
X1681252Y-541449D01*
G01X1681247Y-541364D02*
X1681257Y-541379D01*
G01X1681360Y-541323D02*
X1681350Y-541308D01*
G01X1681690Y-541323D02*
X1681680Y-541308D01*
G01X1682009Y-541444D02*
X1682019Y-541459D01*
G01X1682241Y-541449D02*
X1682251Y-541464D01*
G01X1682339Y-541308D02*
X1682349Y-541323D01*
G01X1682457Y-541444D02*
X1682467Y-541459D01*
G01X1675208Y-542252D02*
X1674839Y-541674D01*
G01X1674962Y-541549D02*
X1675405Y-542252D01*
G01X1680204Y-541469D02*
X1680194Y-541449D01*
G01X1681990Y-541469D02*
X1681980Y-541449D01*
G01X1682438Y-541469D02*
X1682428Y-541449D01*
G01X1681257Y-541308D02*
X1681247Y-541323D01*
G01X1681350Y-541379D02*
X1681360Y-541364D01*
G01Y-541449D02*
X1681350Y-541464D01*
G01X1681581Y-541308D02*
X1681572Y-541323D01*
G01X1681714Y-541353D02*
X1681704Y-541368D01*
G01X1682019Y-541313D02*
X1682009Y-541328D01*
G01X1682241Y-541323D02*
X1682251Y-541308D01*
G01X1682344Y-541464D02*
X1682354Y-541449D01*
G01X1682467Y-541313D02*
X1682457Y-541328D01*
G01X1679839Y-541379D02*
X1679854Y-541358D01*
G01X1681242Y-541288D02*
X1681227Y-541308D01*
G01X1681365Y-541484D02*
X1681380Y-541464D01*
G01X1682236Y-541288D02*
X1682221Y-541308D01*
G01X1682359Y-541484D02*
X1682374Y-541464D01*
G01X1682940Y-541358D02*
X1682925Y-541379D01*
G01X1682940Y-541464D02*
X1682925Y-541484D01*
G01X1681119Y-541303D02*
X1681148Y-541268D01*
G01Y-541308D02*
X1681119Y-541343D01*
G01X1681759Y-541303D02*
X1681788Y-541268D01*
G01Y-541308D02*
X1681759Y-541343D01*
G01X1675405Y-541071D02*
X1674962Y-541549D01*
G01X1674667Y-541649D02*
X1675208Y-541071D01*
G01X1674839Y-541674D02*
X1674667Y-541850D01*
G01X1682900Y-541404D02*
X1682910Y-541414D01*
G01Y-541313D02*
X1682900Y-541303D01*
G01X1679824Y-541308D02*
X1679815Y-541298D01*
G01X1680223Y-541489D02*
X1680204Y-541469D01*
G01X1680356Y-541283D02*
X1680376Y-541303D01*
G01X1681694Y-541283D02*
X1681714Y-541303D01*
G01X1682009Y-541489D02*
X1681990Y-541469D01*
G01X1682143Y-541283D02*
X1682162Y-541303D01*
G01X1682354Y-541404D02*
X1682344Y-541394D01*
G01X1682457Y-541489D02*
X1682438Y-541469D01*
G01X1682374Y-541388D02*
X1682359Y-541373D01*
G01X1682590Y-541283D02*
X1682610Y-541303D01*
G01X1679815Y-541364D02*
X1679824Y-541353D01*
G01X1680204Y-541303D02*
X1680223Y-541283D01*
G01X1680376Y-541469D02*
X1680356Y-541489D01*
G01X1681552Y-541303D02*
X1681572Y-541283D01*
G01X1681990Y-541303D02*
X1682009Y-541283D01*
G01X1682162Y-541469D02*
X1682143Y-541489D01*
G01X1682251Y-541394D02*
X1682241Y-541404D01*
G01X1682438Y-541303D02*
X1682457Y-541283D01*
G01X1682610Y-541469D02*
X1682590Y-541489D01*
G01X1682900Y-541364D02*
X1682910Y-541353D01*
G01Y-541459D02*
X1682900Y-541469D01*
G01X1681542Y-541479D02*
X1681680Y-541353D01*
G01X1681704Y-541368D02*
X1681581Y-541479D01*
G01X1680233Y-541459D02*
X1680248Y-541469D01*
G01X1680346Y-541313D02*
X1680331Y-541303D01*
G01X1681276Y-541474D02*
X1681261Y-541464D01*
G01X1681257Y-541379D02*
X1681271Y-541388D01*
G01X1681350Y-541308D02*
X1681335Y-541298D01*
G01X1681872Y-541454D02*
X1681857Y-541444D01*
G01X1681680Y-541308D02*
X1681665Y-541298D01*
G01X1682019Y-541459D02*
X1682034Y-541469D01*
G01X1681921Y-541318D02*
X1681936Y-541328D01*
G01X1682251Y-541464D02*
X1682265Y-541474D01*
G01X1682133Y-541313D02*
X1682118Y-541303D01*
G01X1682344Y-541394D02*
X1682330Y-541384D01*
G01X1682467Y-541459D02*
X1682482Y-541469D01*
G01X1682324Y-541298D02*
X1682339Y-541308D01*
G01X1682580Y-541313D02*
X1682566Y-541303D01*
G01X1679839Y-541288D02*
X1679820Y-541273D01*
G01X1682905D02*
X1682925Y-541288D01*
G01Y-541484D02*
X1682905Y-541499D01*
G01X1680248Y-541303D02*
X1680233Y-541313D01*
G01X1680331Y-541469D02*
X1680346Y-541459D01*
G01X1681271Y-541298D02*
X1681257Y-541308D01*
G01X1681335Y-541388D02*
X1681350Y-541379D01*
G01X1681340Y-541414D02*
X1681370Y-541394D01*
G01X1681350Y-541464D02*
X1681335Y-541474D01*
G01X1681596Y-541298D02*
X1681581Y-541308D01*
G01X1682034Y-541303D02*
X1682019Y-541313D01*
G01X1682251Y-541308D02*
X1682265Y-541298D01*
G01X1682261Y-541358D02*
X1682231Y-541379D01*
G01X1682118Y-541469D02*
X1682133Y-541459D01*
G01X1682265Y-541384D02*
X1682251Y-541394D01*
G01X1682482Y-541303D02*
X1682467Y-541313D01*
G01X1682330Y-541474D02*
X1682344Y-541464D01*
G01X1682566Y-541469D02*
X1682580Y-541459D01*
G01X1681267Y-541273D02*
X1681242Y-541288D01*
G01X1681340Y-541499D02*
X1681365Y-541484D01*
G01X1682261Y-541273D02*
X1682236Y-541288D01*
G01X1682334Y-541499D02*
X1682359Y-541484D01*
G01X1680243Y-541499D02*
X1680223Y-541489D01*
G01X1680336Y-541273D02*
X1680356Y-541283D01*
G01X1682029Y-541499D02*
X1682009Y-541489D01*
G01X1681675Y-541273D02*
X1681694Y-541283D01*
G01X1682477Y-541499D02*
X1682457Y-541489D01*
G01X1682123Y-541273D02*
X1682143Y-541283D01*
G01X1682570Y-541273D02*
X1682590Y-541283D01*
G01X1682915Y-541384D02*
X1682925Y-541388D01*
G01X1681247Y-541484D02*
X1681271Y-541499D01*
G01X1681242Y-541399D02*
X1681267Y-541414D01*
G01X1681365Y-541288D02*
X1681340Y-541273D01*
G01X1682236Y-541484D02*
X1682261Y-541499D01*
G01X1682359Y-541373D02*
X1682334Y-541358D01*
G01X1682354Y-541288D02*
X1682330Y-541273D01*
G01X1679820Y-541388D02*
X1679839Y-541379D01*
G01X1680223Y-541283D02*
X1680243Y-541273D01*
G01X1680356Y-541489D02*
X1680336Y-541499D01*
G01X1681572Y-541283D02*
X1681591Y-541273D01*
G01X1682009Y-541283D02*
X1682029Y-541273D01*
G01X1682457Y-541283D02*
X1682477Y-541273D01*
G01X1682143Y-541489D02*
X1682123Y-541499D01*
G01X1682590Y-541489D02*
X1682570Y-541499D01*
G01X1682925Y-541379D02*
X1682915Y-541384D01*
G01X1679815Y-541298D02*
X1679800Y-541293D01*
G01X1681291Y-541479D02*
X1681276Y-541474D01*
G01X1681271Y-541388D02*
X1681286Y-541394D01*
G01X1681335Y-541298D02*
X1681320Y-541293D01*
G01X1682265Y-541474D02*
X1682280Y-541479D01*
G01X1682330Y-541384D02*
X1682315Y-541379D01*
G01X1682310Y-541293D02*
X1682324Y-541298D01*
G01X1682885Y-541399D02*
X1682900Y-541404D01*
G01Y-541303D02*
X1682885Y-541298D01*
G01X1679800Y-541368D02*
X1679815Y-541364D01*
G01X1681286Y-541293D02*
X1681271Y-541298D01*
G01X1681320Y-541394D02*
X1681335Y-541388D01*
G01Y-541474D02*
X1681320Y-541479D01*
G01X1682265Y-541298D02*
X1682280Y-541293D01*
G01Y-541379D02*
X1682265Y-541384D01*
G01X1682315Y-541479D02*
X1682330Y-541474D01*
G01X1682885Y-541368D02*
X1682900Y-541364D01*
G01Y-541469D02*
X1682885Y-541474D01*
G01X1680267Y-541504D02*
X1680243Y-541499D01*
G01X1679820Y-541273D02*
X1679795Y-541268D01*
G01X1681271Y-541499D02*
X1681296Y-541504D01*
G01X1680312Y-541268D02*
X1680336Y-541273D01*
G01X1681267Y-541414D02*
X1681291Y-541419D01*
G01X1682054Y-541504D02*
X1682029Y-541499D01*
G01X1682261D02*
X1682285Y-541504D01*
G01X1681340Y-541273D02*
X1681316Y-541268D01*
G01X1682502Y-541504D02*
X1682477Y-541499D01*
G01X1681665Y-541298D02*
X1681641Y-541293D01*
G01X1682334Y-541358D02*
X1682310Y-541353D01*
G01X1682098Y-541268D02*
X1682123Y-541273D01*
G01X1682330D02*
X1682305Y-541268D01*
G01X1682546D02*
X1682570Y-541273D01*
G01X1682881Y-541268D02*
X1682905Y-541273D01*
G01X1682482Y-541469D02*
X1682502Y-541474D01*
G01X1682118Y-541303D02*
X1682098Y-541298D01*
G01X1680248Y-541469D02*
X1680267Y-541474D01*
G01X1680331Y-541303D02*
X1680312Y-541298D01*
G01X1682034Y-541469D02*
X1682054Y-541474D01*
G01X1682566Y-541303D02*
X1682546Y-541298D01*
G01X1681645Y-541268D02*
X1681675Y-541273D01*
G01X1674677Y-544890D02*
X1687275D01*
G01X1675405Y-542252D02*
X1675208D01*
G01X1674667D02*
X1674519D01*
G01X1679342Y-541504D02*
X1679303D01*
G01X1679637D02*
X1679460D01*
G01X1680080D02*
X1679903D01*
G01X1680149D02*
X1680120D01*
G01X1680312D02*
X1680267D01*
G01X1680617D02*
X1680587D01*
G01X1680450D02*
X1680420D01*
G01X1680765D02*
X1680735D01*
G01X1681178D02*
X1681148D01*
G01X1681719D02*
X1681542D01*
G01X1681818D02*
X1681788D01*
G01X1682098D02*
X1682054D01*
G01X1682546D02*
X1682502D01*
G01X1682881D02*
X1682763D01*
G01X1683013D02*
X1682984D01*
G01X1679185D02*
X1679007D01*
G01X1679830D02*
X1679864D01*
G01X1679677D02*
X1679706D01*
G01X1681296D02*
X1681316D01*
G01X1682285D02*
X1682310D01*
G01X1681320Y-541479D02*
X1681291D01*
G01X1681581D02*
X1681719D01*
G01X1682280D02*
X1682315D01*
G01X1682885Y-541474D02*
X1682792D01*
G01X1679037D02*
X1679185D01*
G01X1679490D02*
X1679637D01*
G01X1679933D02*
X1680080D01*
G01X1680267D02*
X1680312D01*
G01X1682054D02*
X1682098D01*
G01X1682502D02*
X1682546D01*
G01X1681252Y-541449D02*
X1681227D01*
G01X1682585Y-541444D02*
X1682615D01*
G01X1681503Y-541419D02*
X1681434D01*
G01X1682723D02*
X1682654D01*
G01X1681291D02*
X1681316D01*
G01X1680351Y-541404D02*
X1680307D01*
G01X1682137D02*
X1682093D01*
G01X1679706Y-541399D02*
X1679790D01*
G01X1682792D02*
X1682885D01*
G01X1679618Y-541394D02*
X1679490D01*
G01X1680587D02*
X1680450D01*
G01X1679165D02*
X1679037D01*
G01X1681286D02*
X1681320D01*
G01X1681434D02*
X1681503D01*
G01X1682654D02*
X1682723D01*
G01X1682315Y-541379D02*
X1682280D01*
G01X1680307Y-541373D02*
X1680381D01*
G01X1682093D02*
X1682167D01*
G01X1679706Y-541368D02*
X1679800D01*
G01X1682792D02*
X1682885D01*
G01X1679037Y-541364D02*
X1679165D01*
G01X1679490D02*
X1679618D01*
G01X1680450D02*
X1680587D01*
G01X1682310Y-541353D02*
X1682285D01*
G01X1680381Y-541328D02*
X1680351D01*
G01X1682167D02*
X1682137D01*
G01X1682615D02*
X1682585D01*
G01X1681572Y-541323D02*
X1681547D01*
G01X1682349D02*
X1682374D01*
G01X1679637Y-541298D02*
X1679490D01*
G01X1680312D02*
X1680267D01*
G01X1682098D02*
X1682054D01*
G01X1682546D02*
X1682502D01*
G01X1682885D02*
X1682792D01*
G01X1679185D02*
X1679037D01*
G01X1679800Y-541293D02*
X1679706D01*
G01X1680735D02*
X1680656D01*
G01X1680843D02*
X1680765D01*
G01X1681320D02*
X1681286D01*
G01X1681641D02*
X1681621D01*
G01X1682280D02*
X1682310D01*
G01X1679795Y-541268D02*
X1679677D01*
G01X1681316D02*
X1681291D01*
G01X1682305D02*
X1682285D01*
G01X1679007D02*
X1679185D01*
G01X1679391D02*
X1679421D01*
G01X1679224D02*
X1679254D01*
G01X1679460D02*
X1679637D01*
G01X1679903D02*
X1679933D01*
G01X1680120D02*
X1680149D01*
G01X1680267D02*
X1680312D01*
G01X1680587D02*
X1680617D01*
G01X1680420D02*
X1680450D01*
G01X1680656D02*
X1680843D01*
G01X1681148D02*
X1681178D01*
G01X1681626D02*
X1681645D01*
G01X1681788D02*
X1681818D01*
G01X1682054D02*
X1682098D01*
G01X1682502D02*
X1682546D01*
G01X1682763D02*
X1682881D01*
G01X1682984D02*
X1683028D01*
G01X1675208Y-541071D02*
X1675405D01*
G01X1674519D02*
X1674667D01*
G01X1687275Y-538591D02*
X1674677D01*
G01X1681591Y-541273D02*
X1681626Y-541268D01*
G01X1682546Y-541474D02*
X1682566Y-541469D01*
G01X1682098Y-541474D02*
X1682118Y-541469D01*
G01X1682502Y-541298D02*
X1682482Y-541303D01*
G01X1682054Y-541298D02*
X1682034Y-541303D01*
G01X1680312Y-541474D02*
X1680331Y-541469D01*
G01X1680267Y-541298D02*
X1680248Y-541303D01*
G01X1682905Y-541499D02*
X1682881Y-541504D01*
G01X1682570Y-541499D02*
X1682546Y-541504D01*
G01X1682310D02*
X1682334Y-541499D01*
G01X1682123D02*
X1682098Y-541504D01*
G01X1682285Y-541353D02*
X1682261Y-541358D01*
G01X1682477Y-541273D02*
X1682502Y-541268D01*
G01X1681316Y-541504D02*
X1681340Y-541499D01*
G01X1682285Y-541268D02*
X1682261Y-541273D01*
G01X1681316Y-541419D02*
X1681340Y-541414D01*
G01X1682029Y-541273D02*
X1682054Y-541268D01*
G01X1681621Y-541293D02*
X1681596Y-541298D01*
G01X1680336Y-541499D02*
X1680312Y-541504D01*
G01X1681291Y-541268D02*
X1681267Y-541273D01*
G01X1680243D02*
X1680267Y-541268D01*
G01X1662586Y-546873D02*
Y-555447D01*
G01X1671921Y-538591D02*
Y-544890D01*
G01Y-538591D02*
Y-544890D01*
G01X1662302Y-553358D02*
X1664357Y-506451D01*
G01X1662410Y-550892D02*
X1662586D01*
G01X1662419Y-550697D02*
X1662586D01*
G01X1662463Y-549691D02*
X1662586D01*
G01X1662465Y-549632D02*
X1662586D01*
G01Y-548808D02*
X1662502D01*
G01X1671921Y-544890D02*
X1674677D01*
G01X1671921D02*
X1678220D01*
G01X1674677Y-538591D02*
X1671921D01*
G01X1678220D02*
X1671921D01*
G01X1665342Y-507971D02*
Y-503087D01*
G01X1664357Y-506451D02*
X1677181Y-462643D01*
G01X1664263Y-508594D02*
X1665342Y-507971D01*
G01X1665065Y-504034D02*
X1665342D01*
G01X1674667Y-493827D02*
Y-494405D01*
G01X1680189Y-494104D02*
X1680194Y-494079D01*
G01X1680223Y-494084D02*
X1680218Y-494104D01*
G01X1680381Y-494205D02*
X1680376Y-494225D01*
G01X1681547Y-494079D02*
X1681552Y-494059D01*
G01X1681719Y-494089D02*
X1681714Y-494109D01*
G01X1679824D02*
X1679830Y-494094D01*
G01X1679854Y-494114D02*
X1679859Y-494099D01*
G01X1680346Y-494215D02*
X1680351Y-494200D01*
G01X1681247Y-494079D02*
X1681242Y-494094D01*
G01X1681360Y-494120D02*
X1681365Y-494104D01*
G01Y-494190D02*
X1681360Y-494205D01*
G01X1682133Y-494215D02*
X1682137Y-494200D01*
G01X1682236Y-494094D02*
X1682241Y-494079D01*
G01Y-494160D02*
X1682236Y-494175D01*
G01X1682354Y-494205D02*
X1682359Y-494190D01*
G01X1682580Y-494215D02*
X1682585Y-494200D01*
G01X1679421Y-494024D02*
X1679342Y-494260D01*
G01X1679322Y-494230D02*
X1679391Y-494024D01*
G01X1681227Y-494064D02*
X1681217Y-494089D01*
G01X1681380Y-494220D02*
X1681389Y-494195D01*
G01X1682221Y-494064D02*
X1682211Y-494089D01*
G01X1682374Y-494220D02*
X1682383Y-494195D01*
G01X1680194Y-494079D02*
X1680204Y-494059D01*
G01X1681680Y-494109D02*
X1681690Y-494089D01*
G01X1679007Y-494260D02*
Y-494024D01*
G01X1679037Y-494149D02*
Y-494230D01*
G01Y-494054D02*
Y-494120D01*
G01X1679165D02*
Y-494149D01*
G01X1679185Y-494024D02*
Y-494054D01*
G01Y-494230D02*
Y-494260D01*
G01X1679460D02*
Y-494024D01*
G01X1679490Y-494149D02*
Y-494230D01*
G01Y-494054D02*
Y-494120D01*
G01X1679618D02*
Y-494149D01*
G01X1679637Y-494024D02*
Y-494054D01*
G01Y-494230D02*
Y-494260D01*
G01X1679677Y-494024D02*
Y-494260D01*
G01X1679706Y-494049D02*
Y-494124D01*
G01Y-494260D02*
Y-494155D01*
G01X1679830Y-494094D02*
Y-494079D01*
G01X1679859Y-494099D02*
Y-494079D01*
G01X1679903Y-494260D02*
Y-494024D01*
G01X1679933D02*
Y-494230D01*
G01X1680080D02*
Y-494260D01*
G01X1680120D02*
Y-494024D01*
G01X1680149D02*
Y-494260D01*
G01X1680189Y-494180D02*
Y-494104D01*
G01X1680218D02*
Y-494180D01*
G01X1680307Y-494160D02*
Y-494129D01*
G01X1680351Y-494200D02*
Y-494160D01*
G01X1680381Y-494129D02*
Y-494205D01*
G01X1680420Y-494260D02*
Y-494024D01*
G01X1680450Y-494149D02*
Y-494260D01*
G01Y-494024D02*
Y-494120D01*
G01X1680587Y-494260D02*
Y-494149D01*
G01Y-494120D02*
Y-494024D01*
G01X1680617D02*
Y-494260D01*
G01X1680656Y-494049D02*
Y-494024D01*
G01X1680735Y-494260D02*
Y-494049D01*
G01X1680765D02*
Y-494260D01*
G01X1680843Y-494024D02*
Y-494049D01*
G01X1681119Y-494099D02*
Y-494059D01*
G01X1681148Y-494260D02*
Y-494064D01*
G01X1681178Y-494024D02*
Y-494260D01*
G01X1681217Y-494089D02*
Y-494109D01*
G01X1681242Y-494094D02*
Y-494104D01*
G01X1681365D02*
Y-494094D01*
G01X1681370Y-494149D02*
Y-494160D01*
G01X1681394D02*
Y-494124D01*
G01X1681434Y-494175D02*
Y-494149D01*
G01X1681503D02*
Y-494175D01*
G01X1681542Y-494260D02*
Y-494235D01*
G01X1681690Y-494089D02*
Y-494079D01*
G01X1681719Y-494235D02*
Y-494260D01*
G01Y-494079D02*
Y-494089D01*
G01X1681759Y-494099D02*
Y-494059D01*
G01X1681788Y-494260D02*
Y-494064D01*
G01X1681818Y-494024D02*
Y-494260D01*
G01X1681975Y-494180D02*
Y-494104D01*
G01X1682005D02*
Y-494180D01*
G01X1682093Y-494160D02*
Y-494129D01*
G01X1682137Y-494200D02*
Y-494160D01*
G01X1682167Y-494129D02*
Y-494205D01*
G01X1682206Y-494124D02*
Y-494160D01*
G01X1682231Y-494134D02*
Y-494124D01*
G01X1682236Y-494175D02*
Y-494190D01*
G01X1682359D02*
Y-494175D01*
G01X1682383Y-494195D02*
Y-494170D01*
G01X1682423Y-494180D02*
Y-494104D01*
G01X1682452D02*
Y-494180D01*
G01X1682654Y-494175D02*
Y-494149D01*
G01X1682723D02*
Y-494175D01*
G01X1682763Y-494260D02*
Y-494024D01*
G01X1682792Y-494054D02*
Y-494124D01*
G01Y-494230D02*
Y-494155D01*
G01X1682915Y-494184D02*
Y-494200D01*
G01Y-494094D02*
Y-494084D01*
G01X1682944Y-494079D02*
Y-494099D01*
G01Y-494180D02*
Y-494205D01*
G01X1682984Y-494260D02*
Y-494024D01*
G01X1681389Y-494195D02*
X1681394Y-494160D01*
G01X1682211Y-494089D02*
X1682206Y-494124D01*
G01X1681370Y-494160D02*
X1681365Y-494190D01*
G01X1682231Y-494124D02*
X1682236Y-494094D01*
G01X1681975Y-494104D02*
X1681980Y-494079D01*
G01X1682423Y-494104D02*
X1682428Y-494079D01*
G01X1682615Y-494200D02*
X1682610Y-494225D01*
G01X1682009Y-494084D02*
X1682005Y-494104D01*
G01X1682167Y-494205D02*
X1682162Y-494225D01*
G01X1682457Y-494084D02*
X1682452Y-494104D01*
G01X1682910Y-494109D02*
X1682915Y-494094D01*
G01X1682944Y-494099D02*
X1682940Y-494114D01*
G01X1682915Y-494200D02*
X1682910Y-494215D01*
G01X1682944Y-494205D02*
X1682940Y-494220D01*
G01X1681980Y-494079D02*
X1681990Y-494059D01*
G01X1682428Y-494079D02*
X1682438Y-494059D01*
G01X1681857Y-494200D02*
X1681921Y-494074D01*
G01X1681936Y-494084D02*
X1681872Y-494210D01*
G01X1680233Y-494069D02*
X1680223Y-494084D01*
G01X1681257Y-494064D02*
X1681247Y-494079D01*
G01X1681350Y-494134D02*
X1681360Y-494120D01*
G01Y-494205D02*
X1681350Y-494220D01*
G01X1681581Y-494064D02*
X1681572Y-494079D01*
G01X1681714Y-494109D02*
X1681704Y-494124D01*
G01X1682019Y-494069D02*
X1682009Y-494084D01*
G01X1682241Y-494079D02*
X1682251Y-494064D01*
G01X1682344Y-494220D02*
X1682354Y-494205D01*
G01X1682467Y-494069D02*
X1682457Y-494084D01*
G01X1679839Y-494134D02*
X1679854Y-494114D01*
G01X1681242Y-494044D02*
X1681227Y-494064D01*
G01X1681365Y-494240D02*
X1681380Y-494220D01*
G01X1682236Y-494044D02*
X1682221Y-494064D01*
G01X1682359Y-494240D02*
X1682374Y-494220D01*
G01X1682940Y-494114D02*
X1682925Y-494134D01*
G01X1682940Y-494220D02*
X1682925Y-494240D01*
G01X1681119Y-494059D02*
X1681148Y-494024D01*
G01Y-494064D02*
X1681119Y-494099D01*
G01X1681759Y-494059D02*
X1681788Y-494024D01*
G01Y-494064D02*
X1681759Y-494099D01*
G01X1675405Y-493827D02*
X1674962Y-494305D01*
G01X1674667Y-494405D02*
X1675208Y-493827D01*
G01X1674839Y-494430D02*
X1674667Y-494606D01*
G01X1679815Y-494120D02*
X1679824Y-494109D01*
G01X1680204Y-494059D02*
X1680223Y-494039D01*
G01X1680376Y-494225D02*
X1680356Y-494245D01*
G01X1681552Y-494059D02*
X1681572Y-494039D01*
G01X1681990Y-494059D02*
X1682009Y-494039D01*
G01X1682162Y-494225D02*
X1682143Y-494245D01*
G01X1682251Y-494149D02*
X1682241Y-494160D01*
G01X1682438Y-494059D02*
X1682457Y-494039D01*
G01X1682610Y-494225D02*
X1682590Y-494245D01*
G01X1682900Y-494120D02*
X1682910Y-494109D01*
G01Y-494215D02*
X1682900Y-494225D01*
G01X1681542Y-494235D02*
X1681680Y-494109D01*
G01X1681394Y-494124D02*
X1681389Y-494089D01*
G01X1682206Y-494160D02*
X1682211Y-494195D01*
G01X1681704Y-494124D02*
X1681581Y-494235D01*
G01X1682925Y-494240D02*
X1682905Y-494255D01*
G01X1680248Y-494059D02*
X1680233Y-494069D01*
G01X1680331Y-494225D02*
X1680346Y-494215D01*
G01X1681271Y-494054D02*
X1681257Y-494064D01*
G01X1681335Y-494144D02*
X1681350Y-494134D01*
G01X1681340Y-494170D02*
X1681370Y-494149D01*
G01X1681350Y-494220D02*
X1681335Y-494230D01*
G01X1681596Y-494054D02*
X1681581Y-494064D01*
G01X1682034Y-494059D02*
X1682019Y-494069D01*
G01X1682251Y-494064D02*
X1682265Y-494054D01*
G01X1682261Y-494114D02*
X1682231Y-494134D01*
G01X1682118Y-494225D02*
X1682133Y-494215D01*
G01X1682265Y-494140D02*
X1682251Y-494149D01*
G01X1682482Y-494059D02*
X1682467Y-494069D01*
G01X1682330Y-494230D02*
X1682344Y-494220D01*
G01X1682566Y-494225D02*
X1682580Y-494215D01*
G01X1681267Y-494029D02*
X1681242Y-494044D01*
G01X1681340Y-494255D02*
X1681365Y-494240D01*
G01X1682261Y-494029D02*
X1682236Y-494044D01*
G01X1682334Y-494255D02*
X1682359Y-494240D01*
G01X1679864Y-494260D02*
X1679820Y-494144D01*
G01X1679790Y-494155D02*
X1679830Y-494260D01*
G01X1679254Y-494024D02*
X1679322Y-494230D01*
G01X1679303Y-494260D02*
X1679224Y-494024D01*
G01X1679830Y-494079D02*
X1679824Y-494064D01*
G01X1679859Y-494079D02*
X1679854Y-494064D01*
G01X1680351Y-494084D02*
X1680346Y-494069D01*
G01X1681227Y-494205D02*
X1681232Y-494220D01*
G01X1681242Y-494104D02*
X1681247Y-494120D01*
G01X1681365Y-494094D02*
X1681360Y-494079D01*
G01X1682137Y-494084D02*
X1682133Y-494069D01*
G01X1682236Y-494190D02*
X1682241Y-494205D01*
G01X1682359Y-494175D02*
X1682354Y-494160D01*
G01X1682374Y-494079D02*
X1682369Y-494064D01*
G01X1682585Y-494084D02*
X1682580Y-494069D01*
G01X1682910Y-494170D02*
X1682915Y-494184D01*
G01X1682940Y-494164D02*
X1682944Y-494180D01*
G01X1682915Y-494084D02*
X1682910Y-494069D01*
G01X1682940Y-494064D02*
X1682944Y-494079D01*
G01X1680218Y-494180D02*
X1680223Y-494200D01*
G01X1681714Y-494059D02*
X1681719Y-494079D01*
G01X1682005Y-494180D02*
X1682009Y-494200D01*
G01X1682452Y-494180D02*
X1682457Y-494200D01*
G01X1680194Y-494205D02*
X1680189Y-494180D01*
G01X1680376Y-494059D02*
X1680381Y-494084D01*
G01X1681980Y-494205D02*
X1681975Y-494180D01*
G01X1682162Y-494059D02*
X1682167Y-494084D01*
G01X1682428Y-494205D02*
X1682423Y-494180D01*
G01X1682610Y-494059D02*
X1682615Y-494084D01*
G01X1679820Y-494144D02*
X1679839Y-494134D01*
G01X1680223Y-494039D02*
X1680243Y-494029D01*
G01X1680356Y-494245D02*
X1680336Y-494255D01*
G01X1681572Y-494039D02*
X1681591Y-494029D01*
G01X1682009Y-494039D02*
X1682029Y-494029D01*
G01X1682457Y-494039D02*
X1682477Y-494029D01*
G01X1682143Y-494245D02*
X1682123Y-494255D01*
G01X1682590Y-494245D02*
X1682570Y-494255D01*
G01X1682925Y-494134D02*
X1682915Y-494140D01*
G01X1680204Y-494225D02*
X1680194Y-494205D01*
G01X1681990Y-494225D02*
X1681980Y-494205D01*
G01X1682438Y-494225D02*
X1682428Y-494205D01*
G01X1681217Y-494109D02*
X1681227Y-494134D01*
G01X1681389Y-494089D02*
X1681380Y-494064D01*
G01X1682211Y-494195D02*
X1682221Y-494220D01*
G01X1682383Y-494170D02*
X1682374Y-494144D01*
G01X1679800Y-494124D02*
X1679815Y-494120D01*
G01X1681286Y-494049D02*
X1681271Y-494054D01*
G01X1681320Y-494149D02*
X1681335Y-494144D01*
G01Y-494230D02*
X1681320Y-494235D01*
G01X1682265Y-494054D02*
X1682280Y-494049D01*
G01Y-494134D02*
X1682265Y-494140D01*
G01X1682315Y-494235D02*
X1682330Y-494230D01*
G01X1682885Y-494124D02*
X1682900Y-494120D01*
G01Y-494225D02*
X1682885Y-494230D01*
G01X1679854Y-494064D02*
X1679839Y-494044D01*
G01X1681232Y-494220D02*
X1681247Y-494240D01*
G01X1681227Y-494134D02*
X1681242Y-494155D01*
G01X1681380Y-494064D02*
X1681365Y-494044D01*
G01X1682221Y-494220D02*
X1682236Y-494240D01*
G01X1682369Y-494064D02*
X1682354Y-494044D01*
G01X1682925Y-494144D02*
X1682940Y-494164D01*
G01X1682925Y-494044D02*
X1682940Y-494064D01*
G01X1680223Y-494200D02*
X1680233Y-494215D01*
G01X1681261Y-494220D02*
X1681252Y-494205D01*
G01X1681247Y-494120D02*
X1681257Y-494134D01*
G01X1681360Y-494079D02*
X1681350Y-494064D01*
G01X1681690Y-494079D02*
X1681680Y-494064D01*
G01X1682009Y-494200D02*
X1682019Y-494215D01*
G01X1682241Y-494205D02*
X1682251Y-494220D01*
G01X1682339Y-494064D02*
X1682349Y-494079D01*
G01X1682457Y-494200D02*
X1682467Y-494215D01*
G01X1679824Y-494064D02*
X1679815Y-494054D01*
G01X1680223Y-494245D02*
X1680204Y-494225D01*
G01X1680356Y-494039D02*
X1680376Y-494059D01*
G01X1681694Y-494039D02*
X1681714Y-494059D01*
G01X1682009Y-494245D02*
X1681990Y-494225D01*
G01X1682143Y-494039D02*
X1682162Y-494059D01*
G01X1682354Y-494160D02*
X1682344Y-494149D01*
G01X1682457Y-494245D02*
X1682438Y-494225D01*
G01X1682374Y-494144D02*
X1682359Y-494129D01*
G01X1682590Y-494039D02*
X1682610Y-494059D01*
G01X1682900Y-494160D02*
X1682910Y-494170D01*
G01Y-494069D02*
X1682900Y-494059D01*
G01X1681247Y-494240D02*
X1681271Y-494255D01*
G01X1681242Y-494155D02*
X1681267Y-494170D01*
G01X1680233Y-494215D02*
X1680248Y-494225D01*
G01X1680346Y-494069D02*
X1680331Y-494059D01*
G01X1681276Y-494230D02*
X1681261Y-494220D01*
G01X1681257Y-494134D02*
X1681271Y-494144D01*
G01X1681350Y-494064D02*
X1681335Y-494054D01*
G01X1681872Y-494210D02*
X1681857Y-494200D01*
G01X1681680Y-494064D02*
X1681665Y-494054D01*
G01X1682019Y-494215D02*
X1682034Y-494225D01*
G01X1681921Y-494074D02*
X1681936Y-494084D01*
G01X1682251Y-494220D02*
X1682265Y-494230D01*
G01X1682133Y-494069D02*
X1682118Y-494059D01*
G01X1682344Y-494149D02*
X1682330Y-494140D01*
G01X1682467Y-494215D02*
X1682482Y-494225D01*
G01X1682324Y-494054D02*
X1682339Y-494064D01*
G01X1682580Y-494069D02*
X1682566Y-494059D01*
G01X1679839Y-494044D02*
X1679820Y-494029D01*
G01X1682905D02*
X1682925Y-494044D01*
G01X1680243Y-494255D02*
X1680223Y-494245D01*
G01X1680336Y-494029D02*
X1680356Y-494039D01*
G01X1682029Y-494255D02*
X1682009Y-494245D01*
G01X1681675Y-494029D02*
X1681694Y-494039D01*
G01X1682477Y-494255D02*
X1682457Y-494245D01*
G01X1682123Y-494029D02*
X1682143Y-494039D01*
G01X1682570Y-494029D02*
X1682590Y-494039D01*
G01X1682915Y-494140D02*
X1682925Y-494144D01*
G01X1681365Y-494044D02*
X1681340Y-494029D01*
G01X1682236Y-494240D02*
X1682261Y-494255D01*
G01X1682359Y-494129D02*
X1682334Y-494114D01*
G01X1682354Y-494044D02*
X1682330Y-494029D01*
G01X1679815Y-494054D02*
X1679800Y-494049D01*
G01X1681291Y-494235D02*
X1681276Y-494230D01*
G01X1681271Y-494144D02*
X1681286Y-494149D01*
G01X1681335Y-494054D02*
X1681320Y-494049D01*
G01X1682265Y-494230D02*
X1682280Y-494235D01*
G01X1682330Y-494140D02*
X1682315Y-494134D01*
G01X1682482Y-494225D02*
X1682502Y-494230D01*
G01X1682118Y-494059D02*
X1682098Y-494054D01*
G01X1680248Y-494225D02*
X1680267Y-494230D01*
G01X1680331Y-494059D02*
X1680312Y-494054D01*
G01X1682034Y-494225D02*
X1682054Y-494230D01*
G01X1682566Y-494059D02*
X1682546Y-494054D01*
G01X1682310Y-494049D02*
X1682324Y-494054D01*
G01X1682885Y-494155D02*
X1682900Y-494160D01*
G01Y-494059D02*
X1682885Y-494054D01*
G01X1681645Y-494024D02*
X1681675Y-494029D01*
G01X1680267Y-494260D02*
X1680243Y-494255D01*
G01X1679820Y-494029D02*
X1679795Y-494024D01*
G01X1681271Y-494255D02*
X1681296Y-494260D01*
G01X1680312Y-494024D02*
X1680336Y-494029D01*
G01X1681267Y-494170D02*
X1681291Y-494175D01*
G01X1682054Y-494260D02*
X1682029Y-494255D01*
G01X1682261D02*
X1682285Y-494260D01*
G01X1681340Y-494029D02*
X1681316Y-494024D01*
G01X1682502Y-494260D02*
X1682477Y-494255D01*
G01X1681665Y-494054D02*
X1681641Y-494049D01*
G01X1682334Y-494114D02*
X1682310Y-494109D01*
G01X1682098Y-494024D02*
X1682123Y-494029D01*
G01X1682330D02*
X1682305Y-494024D01*
G01X1682546D02*
X1682570Y-494029D01*
G01X1682881Y-494024D02*
X1682905Y-494029D01*
G01X1679342Y-494260D02*
X1679303D01*
G01X1679637D02*
X1679460D01*
G01X1680080D02*
X1679903D01*
G01X1680149D02*
X1680120D01*
G01X1680312D02*
X1680267D01*
G01X1680617D02*
X1680587D01*
G01X1680450D02*
X1680420D01*
G01X1680765D02*
X1680735D01*
G01X1681178D02*
X1681148D01*
G01X1681719D02*
X1681542D01*
G01X1681818D02*
X1681788D01*
G01X1682098D02*
X1682054D01*
G01X1682546D02*
X1682502D01*
G01X1682881D02*
X1682763D01*
G01X1683013D02*
X1682984D01*
G01X1679185D02*
X1679007D01*
G01X1679830D02*
X1679864D01*
G01X1679677D02*
X1679706D01*
G01X1681296D02*
X1681316D01*
G01X1682285D02*
X1682310D01*
G01X1681320Y-494235D02*
X1681291D01*
G01X1681581D02*
X1681719D01*
G01X1682280D02*
X1682315D01*
G01X1682885Y-494230D02*
X1682792D01*
G01X1679037D02*
X1679185D01*
G01X1679490D02*
X1679637D01*
G01X1679933D02*
X1680080D01*
G01X1680267D02*
X1680312D01*
G01X1682054D02*
X1682098D01*
G01X1682502D02*
X1682546D01*
G01X1681252Y-494205D02*
X1681227D01*
G01X1682585Y-494200D02*
X1682615D01*
G01X1681503Y-494175D02*
X1681434D01*
G01X1682723D02*
X1682654D01*
G01X1681291D02*
X1681316D01*
G01X1680351Y-494160D02*
X1680307D01*
G01X1682137D02*
X1682093D01*
G01X1679706Y-494155D02*
X1679790D01*
G01X1682792D02*
X1682885D01*
G01X1679618Y-494149D02*
X1679490D01*
G01X1680587D02*
X1680450D01*
G01X1679165D02*
X1679037D01*
G01X1681286D02*
X1681320D01*
G01X1681434D02*
X1681503D01*
G01X1682654D02*
X1682723D01*
G01X1682315Y-494134D02*
X1682280D01*
G01X1680307Y-494129D02*
X1680381D01*
G01X1682093D02*
X1682167D01*
G01X1679706Y-494124D02*
X1679800D01*
G01X1682792D02*
X1682885D01*
G01X1679037Y-494120D02*
X1679165D01*
G01X1679490D02*
X1679618D01*
G01X1680450D02*
X1680587D01*
G01X1682310Y-494109D02*
X1682285D01*
G01X1680381Y-494084D02*
X1680351D01*
G01X1682167D02*
X1682137D01*
G01X1682615D02*
X1682585D01*
G01X1681572Y-494079D02*
X1681547D01*
G01X1682349D02*
X1682374D01*
G01X1679637Y-494054D02*
X1679490D01*
G01X1680312D02*
X1680267D01*
G01X1682098D02*
X1682054D01*
G01X1682546D02*
X1682502D01*
G01X1682885D02*
X1682792D01*
G01X1679185D02*
X1679037D01*
G01X1679800Y-494049D02*
X1679706D01*
G01X1680735D02*
X1680656D01*
G01X1680843D02*
X1680765D01*
G01X1681320D02*
X1681286D01*
G01X1681641D02*
X1681621D01*
G01X1682280D02*
X1682310D01*
G01X1679795Y-494024D02*
X1679677D01*
G01X1681316D02*
X1681291D01*
G01X1682305D02*
X1682285D01*
G01X1679007D02*
X1679185D01*
G01X1679391D02*
X1679421D01*
G01X1679224D02*
X1679254D01*
G01X1679460D02*
X1679637D01*
G01X1679903D02*
X1679933D01*
G01X1680120D02*
X1680149D01*
G01X1680267D02*
X1680312D01*
G01X1680587D02*
X1680617D01*
G01X1680420D02*
X1680450D01*
G01X1680656D02*
X1680843D01*
G01X1681148D02*
X1681178D01*
G01X1681626D02*
X1681645D01*
G01X1681788D02*
X1681818D01*
G01X1682054D02*
X1682098D01*
G01X1682502D02*
X1682546D01*
G01X1682763D02*
X1682881D01*
G01X1682984D02*
X1683028D01*
G01X1675208Y-493827D02*
X1675405D01*
G01X1674519D02*
X1674667D01*
G01X1687275Y-491347D02*
X1674677D01*
G01X1682546Y-494230D02*
X1682566Y-494225D01*
G01X1682098Y-494230D02*
X1682118Y-494225D01*
G01X1682502Y-494054D02*
X1682482Y-494059D01*
G01X1682054Y-494054D02*
X1682034Y-494059D01*
G01X1680312Y-494230D02*
X1680331Y-494225D01*
G01X1680267Y-494054D02*
X1680248Y-494059D01*
G01X1682905Y-494255D02*
X1682881Y-494260D01*
G01X1682570Y-494255D02*
X1682546Y-494260D01*
G01X1682310D02*
X1682334Y-494255D01*
G01X1682123D02*
X1682098Y-494260D01*
G01X1682285Y-494109D02*
X1682261Y-494114D01*
G01X1682477Y-494029D02*
X1682502Y-494024D01*
G01X1681316Y-494260D02*
X1681340Y-494255D01*
G01X1682285Y-494024D02*
X1682261Y-494029D01*
G01X1681316Y-494175D02*
X1681340Y-494170D01*
G01X1682029Y-494029D02*
X1682054Y-494024D01*
G01X1681621Y-494049D02*
X1681596Y-494054D01*
G01X1680336Y-494255D02*
X1680312Y-494260D01*
G01X1681291Y-494024D02*
X1681267Y-494029D01*
G01X1680243D02*
X1680267Y-494024D01*
G01X1681591Y-494029D02*
X1681626Y-494024D01*
G01X1674519Y-495008D02*
Y-493827D01*
G01X1674667Y-494606D02*
Y-495008D01*
G01X1674677Y-491347D02*
Y-497646D01*
G01X1676252D02*
Y-491347D01*
G01X1676580D02*
Y-497646D01*
G01X1678220D02*
Y-491347D01*
G01Y-497646D02*
Y-491347D01*
G01X1675208Y-495008D02*
X1674839Y-494430D01*
G01X1674962Y-494305D02*
X1675405Y-495008D01*
G01X1674677Y-497646D02*
X1687275D01*
G01X1675405Y-495008D02*
X1675208D01*
G01X1674667D02*
X1674519D01*
G01X1674677Y-491347D02*
X1671921D01*
G01X1678220D02*
X1671921D01*
G01D02*
Y-497646D01*
G01Y-491347D02*
Y-497646D01*
G01D02*
X1674677D01*
G01X1671921D02*
X1678220D01*
G01X1677181Y-462643D02*
X1690799Y-438668D01*
G01X1677806Y-27417D02*
X1678293Y-25973D01*
X1679755Y-25251D01*
X1681216Y-25973D01*
X1681704Y-27417D01*
X1681216Y-28860D01*
X1680729Y-29582D01*
X1679755Y-30304D01*
X1678780Y-29582D01*
X1678293Y-28860D01*
X1677806Y-27417D01*
Y-24530D01*
X1678293Y-23086D01*
X1678780Y-22364D01*
X1679755Y-21643D01*
X1680729Y-22364D01*
X1681216Y-23086D01*
G01X1671959Y-30304D02*
X1670985Y-29582D01*
X1670498Y-28860D01*
X1670011Y-27417D01*
Y-24530D01*
X1670498Y-23086D01*
X1670985Y-22364D01*
X1671959Y-21643D01*
X1672933Y-22364D01*
X1673421Y-23086D01*
X1673908Y-24530D01*
Y-27417D01*
X1673421Y-28860D01*
X1672933Y-29582D01*
X1671959Y-30304D01*
G01X1656369Y-21643D02*
Y-30304D01*
G01X1662215Y-27417D02*
X1662702Y-25973D01*
X1664164Y-25251D01*
X1665626Y-25973D01*
X1666113Y-27417D01*
X1665626Y-28860D01*
X1665138Y-29582D01*
X1664164Y-30304D01*
X1663189Y-29582D01*
X1662702Y-28860D01*
X1662215Y-27417D01*
Y-24530D01*
X1662702Y-23086D01*
X1663189Y-22364D01*
X1664164Y-21643D01*
X1665138Y-22364D01*
X1665626Y-23086D01*
G01X1708263Y-738241D02*
X1711186Y-740407D01*
X1711673Y-741128D01*
Y-742572D01*
X1711186Y-743294D01*
X1710212Y-744016D01*
X1709237D01*
X1708263Y-743294D01*
X1707289Y-741850D01*
G01X1711673Y-736797D02*
X1711186Y-736076D01*
X1710212Y-735354D01*
X1709237D01*
X1708263Y-736076D01*
X1707776Y-736797D01*
Y-737520D01*
X1708263Y-738241D01*
G01X1716058Y-743294D02*
X1715084Y-741850D01*
X1714596Y-739685D01*
X1715084Y-737520D01*
G01D02*
X1716058Y-736076D01*
X1717033Y-735354D01*
X1718007D01*
X1718981Y-736076D01*
X1719469Y-736797D01*
G01Y-742572D02*
X1718981Y-743294D01*
X1718007Y-744016D01*
X1717033D01*
X1716058Y-743294D01*
G01X1873889Y-651977D02*
X1709716D01*
G01D02*
Y-431504D01*
G01X1683934Y-635892D02*
X1683944Y-635902D01*
G01Y-635801D02*
X1683934Y-635791D01*
G01X1683412Y-635771D02*
X1683432Y-635791D01*
G01X1683624Y-635796D02*
X1683614Y-635786D01*
G01X1684165Y-635947D02*
X1684175Y-635957D01*
G01X1684283Y-635771D02*
X1684303Y-635791D01*
G01X1693968Y-662315D02*
X1686780Y-653613D01*
G01X1683639Y-635776D02*
X1683653Y-635796D01*
G01X1683958Y-635877D02*
X1683973Y-635897D01*
G01X1683958Y-635776D02*
X1683973Y-635796D01*
G01X1683393Y-635761D02*
X1683412Y-635771D01*
G01X1683948Y-635872D02*
X1683958Y-635877D01*
G01X1684185Y-635987D02*
X1684165Y-635977D01*
G01X1684175Y-635957D02*
X1684185Y-635962D01*
G01X1684263Y-635761D02*
X1684283Y-635771D01*
G01X1683397Y-635796D02*
X1683383Y-635786D01*
G01X1684032Y-635942D02*
X1684017Y-635932D01*
G01X1684165Y-635977D02*
X1684150Y-635967D01*
G01X1684081Y-635807D02*
X1684096Y-635816D01*
G01X1684278Y-635897D02*
X1684263Y-635887D01*
G01X1684273Y-635796D02*
X1684259Y-635786D01*
G01X1683619Y-635761D02*
X1683639Y-635776D01*
G01X1683939Y-635761D02*
X1683958Y-635776D01*
G01X1683407Y-635811D02*
X1683397Y-635796D01*
G01X1684150Y-635967D02*
X1684141Y-635952D01*
G01X1684298Y-635882D02*
X1684308Y-635897D01*
G01X1684283Y-635811D02*
X1684273Y-635796D01*
G01X1684160Y-635937D02*
X1684165Y-635947D01*
G01X1684288Y-635917D02*
X1684278Y-635897D01*
G01X1683082Y-635992D02*
X1683013Y-635807D01*
G01X1683028Y-635756D02*
X1683102Y-635967D01*
G01X1687157Y-635559D02*
X1687551Y-636740D01*
G01X1683629Y-635811D02*
X1683624Y-635796D01*
G01X1683653D02*
X1683658Y-635811D01*
G01X1683944Y-635902D02*
X1683948Y-635917D01*
G01X1683973Y-635897D02*
X1683978Y-635912D01*
G01X1683948Y-635816D02*
X1683944Y-635801D01*
G01X1683973Y-635796D02*
X1683978Y-635811D01*
G01X1684141Y-635952D02*
X1684135Y-635937D01*
G01X1684204Y-635992D02*
X1684185Y-635987D01*
G01X1683614Y-635786D02*
X1683599Y-635781D01*
G01X1683919Y-635887D02*
X1683934Y-635892D01*
G01Y-635791D02*
X1683919Y-635786D01*
G01X1684273Y-635872D02*
X1684298Y-635882D01*
G01X1687403Y-636740D02*
X1687305Y-636439D01*
G01X1687059Y-635660D02*
X1687280Y-636338D01*
G01X1683432Y-635791D02*
X1683437Y-635811D01*
G01X1684308Y-635897D02*
X1684313Y-635917D01*
G01X1684303Y-635791D02*
X1684308Y-635811D01*
G01X1683013Y-635807D02*
Y-635992D01*
G01X1683191D02*
Y-635807D01*
G01X1683220Y-635756D02*
Y-635992D01*
G01X1683259D02*
Y-635967D01*
G01X1683407Y-635821D02*
Y-635811D01*
G01X1683437Y-635967D02*
Y-635992D01*
G01Y-635811D02*
Y-635821D01*
G01X1683476Y-635992D02*
Y-635756D01*
G01X1683506Y-635887D02*
Y-635992D01*
G01Y-635781D02*
Y-635857D01*
G01X1683629Y-635827D02*
Y-635811D01*
G01X1683658D02*
Y-635831D01*
G01X1683698D02*
Y-635791D01*
G01X1683727Y-635992D02*
Y-635796D01*
G01X1683732Y-639378D02*
Y-633079D01*
G01Y-639378D02*
Y-633079D01*
G01X1683757Y-635756D02*
Y-635992D01*
G01X1683796D02*
Y-635756D01*
G01X1683826Y-635786D02*
Y-635857D01*
G01Y-635962D02*
Y-635887D01*
G01X1683948Y-635917D02*
Y-635932D01*
G01Y-635827D02*
Y-635816D01*
G01X1683978Y-635811D02*
Y-635831D01*
G01Y-635912D02*
Y-635937D01*
G01X1684214Y-635882D02*
Y-635862D01*
G01X1684283Y-635821D02*
Y-635811D01*
G01X1684288Y-635937D02*
Y-635917D01*
G01X1684308Y-635811D02*
Y-635821D01*
G01X1684313Y-635917D02*
Y-635937D01*
G01X1684352Y-635781D02*
Y-635756D01*
G01X1684431Y-635992D02*
Y-635781D01*
G01X1684460D02*
Y-635992D01*
G01X1684539Y-635756D02*
Y-635781D01*
G01X1685372Y-639378D02*
Y-633079D01*
G01X1685700Y-639378D02*
Y-633079D01*
G01X1687275Y-639378D02*
Y-633079D01*
G01X1873889Y-651977D02*
X1701842D01*
G01X1873889D02*
X1701842D01*
G01X1684229Y-635756D02*
X1684263Y-635761D01*
G01X1683363Y-635756D02*
X1683393Y-635761D01*
G01X1684263Y-635887D02*
X1684234Y-635882D01*
G01X1684185Y-635962D02*
X1684209Y-635967D01*
G01X1683383Y-635786D02*
X1683358Y-635781D01*
G01X1683594Y-635756D02*
X1683619Y-635761D01*
G01X1683914Y-635756D02*
X1683939Y-635761D01*
G01X1684259Y-635786D02*
X1684234Y-635781D01*
G01X1690031Y-633079D02*
Y-639378D01*
G01Y-633079D02*
Y-639378D01*
G01X1693968Y-662315D02*
Y-434961D01*
G01Y-662315D02*
Y-434961D01*
G01X1690031Y-639378D02*
X1687275D01*
G01X1690031D02*
X1683732D01*
G01X1686714Y-636740D02*
X1686567D01*
G01X1687551D02*
X1687403D01*
G01X1687305Y-636439D02*
X1686813D01*
G01X1687280Y-636338D02*
X1686837D01*
G01X1684244Y-635992D02*
X1684204D01*
G01X1684460D02*
X1684431D01*
G01X1683220D02*
X1683191D01*
G01X1683122D02*
X1683082D01*
G01X1683437D02*
X1683259D01*
G01X1683506D02*
X1683476D01*
G01X1683757D02*
X1683727D01*
G01X1683914D02*
X1683796D01*
G01X1683299Y-635967D02*
X1683437D01*
G01X1684209D02*
X1684239D01*
G01X1683919Y-635962D02*
X1683826D01*
G01X1684135Y-635937D02*
X1684160D01*
G01X1683594Y-635887D02*
X1683506D01*
G01X1683826D02*
X1683919D01*
G01X1684234Y-635882D02*
X1684214D01*
G01Y-635862D02*
X1684234D01*
G01X1683506Y-635857D02*
X1683599D01*
G01X1683826D02*
X1683919D01*
G01X1684165Y-635811D02*
X1684141D01*
G01X1683289D02*
X1683265D01*
G01X1683919Y-635786D02*
X1683826D01*
G01X1684234Y-635781D02*
X1684214D01*
G01X1684431D02*
X1684352D01*
G01X1684539D02*
X1684460D01*
G01X1683358D02*
X1683338D01*
G01X1683599D02*
X1683506D01*
G01X1683176Y-635756D02*
X1683220D01*
G01X1683343D02*
X1683363D01*
G01X1683476D02*
X1683594D01*
G01X1683727D02*
X1683757D01*
G01X1683796D02*
X1683914D01*
G01X1684219D02*
X1684229D01*
G01X1684352D02*
X1684539D01*
G01X1686960Y-635559D02*
X1687157D01*
G01X1683265Y-635811D02*
X1683269Y-635791D01*
G01X1683437Y-635821D02*
X1683432Y-635842D01*
G01X1684141Y-635811D02*
X1684145Y-635791D01*
G01X1684308Y-635821D02*
X1684303Y-635842D01*
G01X1684185Y-635761D02*
X1684219Y-635756D01*
G01X1683309Y-635761D02*
X1683343Y-635756D01*
G01X1683624Y-635842D02*
X1683629Y-635827D01*
G01X1683658Y-635831D02*
X1683653Y-635847D01*
G01X1683944Y-635842D02*
X1683948Y-635827D01*
G01X1683978Y-635831D02*
X1683973Y-635847D01*
G01X1683948Y-635932D02*
X1683944Y-635947D01*
G01X1683978Y-635937D02*
X1683973Y-635952D01*
G01X1684313Y-635937D02*
X1684308Y-635952D01*
G01X1686837Y-636338D02*
X1687059Y-635660D01*
G01X1686813Y-636439D02*
X1686714Y-636740D01*
G01X1686567D02*
X1686960Y-635559D01*
G01X1683102Y-635967D02*
X1683176Y-635756D01*
G01X1683191Y-635807D02*
X1683122Y-635992D01*
G01X1684263Y-635987D02*
X1684244Y-635992D01*
G01X1684239Y-635967D02*
X1684263Y-635962D01*
G01X1683939Y-635987D02*
X1683914Y-635992D01*
G01X1684214Y-635781D02*
X1684190Y-635786D01*
G01X1683619Y-635882D02*
X1683594Y-635887D01*
G01X1683338Y-635781D02*
X1683314Y-635786D01*
G01X1683397Y-635842D02*
X1683407Y-635821D01*
G01X1684273Y-635842D02*
X1684283Y-635821D01*
G01Y-635947D02*
X1684288Y-635937D01*
G01X1684017Y-635932D02*
X1684081Y-635807D01*
G01X1684096Y-635816D02*
X1684032Y-635942D01*
G01X1683299Y-635796D02*
X1683289Y-635811D01*
G01X1683432Y-635842D02*
X1683422Y-635857D01*
G01X1684175Y-635796D02*
X1684165Y-635811D01*
G01X1684303Y-635842D02*
X1684293Y-635857D01*
G01X1684308Y-635952D02*
X1684298Y-635967D01*
G01X1683653Y-635847D02*
X1683639Y-635867D01*
G01X1683973Y-635847D02*
X1683958Y-635867D01*
G01X1683973Y-635952D02*
X1683958Y-635972D01*
G01X1683698Y-635791D02*
X1683727Y-635756D01*
G01Y-635796D02*
X1683698Y-635831D01*
G01X1683269Y-635791D02*
X1683289Y-635771D01*
G01X1683614Y-635852D02*
X1683624Y-635842D01*
G01X1683934Y-635852D02*
X1683944Y-635842D01*
G01Y-635947D02*
X1683934Y-635957D01*
G01X1684145Y-635791D02*
X1684165Y-635771D01*
G01X1684263Y-635852D02*
X1684273Y-635842D01*
G01Y-635957D02*
X1684283Y-635947D01*
G01X1683259Y-635967D02*
X1683397Y-635842D01*
G01X1683422Y-635857D02*
X1683299Y-635967D01*
G01X1683639Y-635867D02*
X1683619Y-635882D01*
G01X1683958Y-635972D02*
X1683939Y-635987D01*
G01X1684293Y-635857D02*
X1684273Y-635872D01*
G01X1683314Y-635786D02*
X1683299Y-635796D01*
G01X1684190Y-635786D02*
X1684175Y-635796D01*
G01X1684298Y-635967D02*
X1684283Y-635977D01*
G01X1683289Y-635771D02*
X1683309Y-635761D01*
G01X1683958Y-635867D02*
X1683948Y-635872D01*
G01X1684165Y-635771D02*
X1684185Y-635761D01*
G01X1684263Y-635962D02*
X1684273Y-635957D01*
G01X1684283Y-635977D02*
X1684263Y-635987D01*
G01X1683599Y-635857D02*
X1683614Y-635852D01*
G01X1683919Y-635857D02*
X1683934Y-635852D01*
G01Y-635957D02*
X1683919Y-635962D01*
G01X1684234Y-635862D02*
X1684263Y-635852D01*
G01X1701842Y-651977D02*
G03X1693968Y-659851I0J-7874D01*
G01X1701842Y-651977D02*
G03X1693968Y-659851I0J-7874D01*
G01X1687275Y-633079D02*
X1690031D01*
G01X1683732D02*
X1690031D01*
G01X1683639Y-588532D02*
X1683653Y-588552D01*
G01X1683958Y-588632D02*
X1683973Y-588653D01*
G01X1683958Y-588532D02*
X1683973Y-588552D01*
G01X1683407Y-588567D02*
X1683397Y-588552D01*
G01X1684150Y-588723D02*
X1684141Y-588708D01*
G01X1684298Y-588638D02*
X1684308Y-588653D01*
G01X1684283Y-588567D02*
X1684273Y-588552D01*
G01X1684160Y-588693D02*
X1684165Y-588703D01*
G01X1684288Y-588673D02*
X1684278Y-588653D01*
G01X1683082Y-588748D02*
X1683013Y-588562D01*
G01X1683028Y-588512D02*
X1683102Y-588723D01*
G01X1683629Y-588567D02*
X1683624Y-588552D01*
G01X1683653D02*
X1683658Y-588567D01*
G01X1683944Y-588658D02*
X1683948Y-588673D01*
G01X1683973Y-588653D02*
X1683978Y-588668D01*
G01X1683948Y-588572D02*
X1683944Y-588557D01*
G01X1683973Y-588552D02*
X1683978Y-588567D01*
G01X1684141Y-588708D02*
X1684135Y-588693D01*
G01X1683432Y-588547D02*
X1683437Y-588567D01*
G01X1684308Y-588653D02*
X1684313Y-588673D01*
G01X1684303Y-588547D02*
X1684308Y-588567D01*
G01X1683013Y-588562D02*
Y-588748D01*
G01X1683191D02*
Y-588562D01*
G01X1683220Y-588512D02*
Y-588748D01*
G01X1683259D02*
Y-588723D01*
G01X1683407Y-588577D02*
Y-588567D01*
G01X1683437Y-588723D02*
Y-588748D01*
G01Y-588567D02*
Y-588577D01*
G01X1683476Y-588748D02*
Y-588512D01*
G01X1683506Y-588643D02*
Y-588748D01*
G01Y-588537D02*
Y-588612D01*
G01X1683629Y-588582D02*
Y-588567D01*
G01X1683658D02*
Y-588587D01*
G01X1683698D02*
Y-588547D01*
G01X1683727Y-588748D02*
Y-588552D01*
G01X1683732Y-592134D02*
Y-585835D01*
G01Y-592134D02*
Y-585835D01*
G01X1683757Y-588512D02*
Y-588748D01*
G01X1683796D02*
Y-588512D01*
G01X1683826Y-588542D02*
Y-588612D01*
G01Y-588718D02*
Y-588643D01*
G01X1683948Y-588673D02*
Y-588688D01*
G01Y-588582D02*
Y-588572D01*
G01X1683978Y-588567D02*
Y-588587D01*
G01Y-588668D02*
Y-588693D01*
G01X1684214Y-588638D02*
Y-588618D01*
G01X1684283Y-588577D02*
Y-588567D01*
G01X1684288Y-588693D02*
Y-588673D01*
G01X1684308Y-588567D02*
Y-588577D01*
G01X1684313Y-588673D02*
Y-588693D01*
G01X1684352Y-588537D02*
Y-588512D01*
G01X1684431Y-588748D02*
Y-588537D01*
G01X1684460D02*
Y-588748D01*
G01X1684539Y-588512D02*
Y-588537D01*
G01X1685372Y-592134D02*
Y-585835D01*
G01X1685700Y-592134D02*
Y-585835D01*
G01X1687275Y-592134D02*
Y-585835D01*
G01X1683619Y-588517D02*
X1683639Y-588532D01*
G01X1683939Y-588517D02*
X1683958Y-588532D01*
G01X1683934Y-588648D02*
X1683944Y-588658D01*
G01Y-588557D02*
X1683934Y-588547D01*
G01X1683412Y-588527D02*
X1683432Y-588547D01*
G01X1683624Y-588552D02*
X1683614Y-588542D01*
G01X1684165Y-588703D02*
X1684175Y-588713D01*
G01X1684283Y-588527D02*
X1684303Y-588547D01*
G01X1687157Y-588315D02*
X1687551Y-589496D01*
G01X1687403D02*
X1687305Y-589195D01*
G01X1687059Y-588416D02*
X1687280Y-589094D01*
G01X1690031Y-585835D02*
Y-592134D01*
G01Y-585835D02*
Y-592134D01*
G01X1683265Y-588567D02*
X1683269Y-588547D01*
G01X1683437Y-588577D02*
X1683432Y-588597D01*
G01X1684141Y-588567D02*
X1684145Y-588547D01*
G01X1684308Y-588577D02*
X1684303Y-588597D01*
G01X1683393Y-588517D02*
X1683412Y-588527D01*
G01X1683948Y-588628D02*
X1683958Y-588632D01*
G01X1684185Y-588743D02*
X1684165Y-588733D01*
G01X1684175Y-588713D02*
X1684185Y-588718D01*
G01X1684263Y-588517D02*
X1684283Y-588527D01*
G01X1683397Y-588552D02*
X1683383Y-588542D01*
G01X1684032Y-588698D02*
X1684017Y-588688D01*
G01X1684165Y-588733D02*
X1684150Y-588723D01*
G01X1684081Y-588562D02*
X1684096Y-588572D01*
G01X1684278Y-588653D02*
X1684263Y-588643D01*
G01X1684273Y-588552D02*
X1684259Y-588542D01*
G01X1683624Y-588597D02*
X1683629Y-588582D01*
G01X1683658Y-588587D02*
X1683653Y-588603D01*
G01X1683944Y-588597D02*
X1683948Y-588582D01*
G01X1683978Y-588587D02*
X1683973Y-588603D01*
G01X1683948Y-588688D02*
X1683944Y-588703D01*
G01X1683978Y-588693D02*
X1683973Y-588708D01*
G01X1684313Y-588693D02*
X1684308Y-588708D01*
G01X1686837Y-589094D02*
X1687059Y-588416D01*
G01X1686813Y-589195D02*
X1686714Y-589496D01*
G01X1686567D02*
X1686960Y-588315D01*
G01X1683102Y-588723D02*
X1683176Y-588512D01*
G01X1683191Y-588562D02*
X1683122Y-588748D01*
G01X1683614Y-588542D02*
X1683599Y-588537D01*
G01X1683919Y-588643D02*
X1683934Y-588648D01*
G01Y-588547D02*
X1683919Y-588542D01*
G01X1684273Y-588628D02*
X1684298Y-588638D01*
G01X1683397Y-588597D02*
X1683407Y-588577D01*
G01X1684273Y-588597D02*
X1684283Y-588577D01*
G01Y-588703D02*
X1684288Y-588693D01*
G01X1684017Y-588688D02*
X1684081Y-588562D01*
G01X1684096Y-588572D02*
X1684032Y-588698D01*
G01X1683299Y-588552D02*
X1683289Y-588567D01*
G01X1683432Y-588597D02*
X1683422Y-588612D01*
G01X1684229Y-588512D02*
X1684263Y-588517D01*
G01X1683363Y-588512D02*
X1683393Y-588517D01*
G01X1684263Y-588643D02*
X1684234Y-588638D01*
G01X1684185Y-588718D02*
X1684209Y-588723D01*
G01X1683383Y-588542D02*
X1683358Y-588537D01*
G01X1683594Y-588512D02*
X1683619Y-588517D01*
G01X1683914Y-588512D02*
X1683939Y-588517D01*
G01X1684259Y-588542D02*
X1684234Y-588537D01*
G01X1684204Y-588748D02*
X1684185Y-588743D01*
G01X1684175Y-588552D02*
X1684165Y-588567D01*
G01X1684303Y-588597D02*
X1684293Y-588612D01*
G01X1684308Y-588708D02*
X1684298Y-588723D01*
G01X1683653Y-588603D02*
X1683639Y-588623D01*
G01X1683973Y-588603D02*
X1683958Y-588623D01*
G01X1683973Y-588708D02*
X1683958Y-588728D01*
G01X1683698Y-588547D02*
X1683727Y-588512D01*
G01Y-588552D02*
X1683698Y-588587D01*
G01X1690031Y-592134D02*
X1687275D01*
G01X1690031D02*
X1683732D01*
G01X1683269Y-588547D02*
X1683289Y-588527D01*
G01X1683614Y-588608D02*
X1683624Y-588597D01*
G01X1683934Y-588608D02*
X1683944Y-588597D01*
G01Y-588703D02*
X1683934Y-588713D01*
G01X1684145Y-588547D02*
X1684165Y-588527D01*
G01X1684263Y-588608D02*
X1684273Y-588597D01*
G01Y-588713D02*
X1684283Y-588703D01*
G01X1686714Y-589496D02*
X1686567D01*
G01X1687551D02*
X1687403D01*
G01X1687305Y-589195D02*
X1686813D01*
G01X1687280Y-589094D02*
X1686837D01*
G01X1684244Y-588748D02*
X1684204D01*
G01X1684460D02*
X1684431D01*
G01X1683220D02*
X1683191D01*
G01X1683122D02*
X1683082D01*
G01X1683437D02*
X1683259D01*
G01X1683506D02*
X1683476D01*
G01X1683757D02*
X1683727D01*
G01X1683914D02*
X1683796D01*
G01X1683299Y-588723D02*
X1683437D01*
G01X1684209D02*
X1684239D01*
G01X1683919Y-588718D02*
X1683826D01*
G01X1684135Y-588693D02*
X1684160D01*
G01X1683594Y-588643D02*
X1683506D01*
G01X1683826D02*
X1683919D01*
G01X1684234Y-588638D02*
X1684214D01*
G01Y-588618D02*
X1684234D01*
G01X1683506Y-588612D02*
X1683599D01*
G01X1683826D02*
X1683919D01*
G01X1684165Y-588567D02*
X1684141D01*
G01X1683289D02*
X1683265D01*
G01X1683919Y-588542D02*
X1683826D01*
G01X1684234Y-588537D02*
X1684214D01*
G01X1684431D02*
X1684352D01*
G01X1684539D02*
X1684460D01*
G01X1683358D02*
X1683338D01*
G01X1683599D02*
X1683506D01*
G01X1683176Y-588512D02*
X1683220D01*
G01X1683343D02*
X1683363D01*
G01X1683476D02*
X1683594D01*
G01X1683727D02*
X1683757D01*
G01X1683796D02*
X1683914D01*
G01X1684219D02*
X1684229D01*
G01X1684352D02*
X1684539D01*
G01X1686960Y-588315D02*
X1687157D01*
G01X1687275Y-585835D02*
X1690031D01*
G01X1683732D02*
X1690031D01*
G01X1683259Y-588723D02*
X1683397Y-588597D01*
G01X1683422Y-588612D02*
X1683299Y-588723D01*
G01X1683639Y-588623D02*
X1683619Y-588638D01*
G01X1683958Y-588728D02*
X1683939Y-588743D01*
G01X1684293Y-588612D02*
X1684273Y-588628D01*
G01X1684239Y-588723D02*
X1684263Y-588718D01*
G01X1683939Y-588743D02*
X1683914Y-588748D01*
G01X1684214Y-588537D02*
X1684190Y-588542D01*
G01X1683619Y-588638D02*
X1683594Y-588643D01*
G01X1683338Y-588537D02*
X1683314Y-588542D01*
G01X1684185Y-588517D02*
X1684219Y-588512D01*
G01X1683309Y-588517D02*
X1683343Y-588512D01*
G01X1683314Y-588542D02*
X1683299Y-588552D01*
G01X1684190Y-588542D02*
X1684175Y-588552D01*
G01X1684298Y-588723D02*
X1684283Y-588733D01*
G01X1684263Y-588743D02*
X1684244Y-588748D01*
G01X1683289Y-588527D02*
X1683309Y-588517D01*
G01X1683958Y-588623D02*
X1683948Y-588628D01*
G01X1684165Y-588527D02*
X1684185Y-588517D01*
G01X1684263Y-588718D02*
X1684273Y-588713D01*
G01X1684283Y-588733D02*
X1684263Y-588743D01*
G01X1683599Y-588612D02*
X1683614Y-588608D01*
G01X1683919Y-588612D02*
X1683934Y-588608D01*
G01Y-588713D02*
X1683919Y-588718D01*
G01X1684234Y-588618D02*
X1684263Y-588608D01*
G01X1683013Y-541318D02*
Y-541504D01*
G01X1683191D02*
Y-541318D01*
G01X1683220Y-541268D02*
Y-541504D01*
G01X1683259D02*
Y-541479D01*
G01X1683407Y-541333D02*
Y-541323D01*
G01X1683437D02*
Y-541333D01*
G01Y-541479D02*
Y-541504D01*
G01X1683476D02*
Y-541268D01*
G01X1683506Y-541399D02*
Y-541504D01*
G01Y-541293D02*
Y-541368D01*
G01X1683629Y-541338D02*
Y-541323D01*
G01X1683658D02*
Y-541343D01*
G01X1683698D02*
Y-541303D01*
G01X1683727Y-541504D02*
Y-541308D01*
G01X1683732Y-544890D02*
Y-538591D01*
G01Y-544890D02*
Y-538591D01*
G01X1683757Y-541268D02*
Y-541504D01*
G01X1683796D02*
Y-541268D01*
G01X1683826Y-541298D02*
Y-541368D01*
G01Y-541474D02*
Y-541399D01*
G01X1683948Y-541429D02*
Y-541444D01*
G01Y-541338D02*
Y-541328D01*
G01X1683978Y-541323D02*
Y-541343D01*
G01Y-541424D02*
Y-541449D01*
G01X1684214Y-541394D02*
Y-541373D01*
G01X1684283Y-541333D02*
Y-541323D01*
G01X1684288Y-541449D02*
Y-541429D01*
G01X1684308Y-541323D02*
Y-541333D01*
G01X1684313Y-541429D02*
Y-541449D01*
G01X1684352Y-541293D02*
Y-541268D01*
G01X1684431Y-541504D02*
Y-541293D01*
G01X1684460D02*
Y-541504D01*
G01X1684539Y-541268D02*
Y-541293D01*
G01X1685372Y-544890D02*
Y-538591D01*
G01X1685700Y-544890D02*
Y-538591D01*
G01X1687275Y-544890D02*
Y-538591D01*
G01X1683265Y-541323D02*
X1683269Y-541303D01*
G01X1683437Y-541333D02*
X1683432Y-541353D01*
G01X1684141Y-541323D02*
X1684145Y-541303D01*
G01X1684308Y-541333D02*
X1684303Y-541353D01*
G01X1683082Y-541504D02*
X1683013Y-541318D01*
G01X1683028Y-541268D02*
X1683102Y-541479D01*
G01X1683629Y-541323D02*
X1683624Y-541308D01*
G01X1683653D02*
X1683658Y-541323D01*
G01X1683944Y-541414D02*
X1683948Y-541429D01*
G01X1683973Y-541408D02*
X1683978Y-541424D01*
G01X1683948Y-541328D02*
X1683944Y-541313D01*
G01X1683973Y-541308D02*
X1683978Y-541323D01*
G01X1684141Y-541464D02*
X1684135Y-541449D01*
G01X1683432Y-541303D02*
X1683437Y-541323D01*
G01X1684308Y-541408D02*
X1684313Y-541429D01*
G01X1684303Y-541303D02*
X1684308Y-541323D01*
G01X1690031Y-538591D02*
Y-544890D01*
G01Y-538591D02*
Y-544890D01*
G01X1683624Y-541353D02*
X1683629Y-541338D01*
G01X1683658Y-541343D02*
X1683653Y-541358D01*
G01X1683944Y-541353D02*
X1683948Y-541338D01*
G01X1683978Y-541343D02*
X1683973Y-541358D01*
G01X1683948Y-541444D02*
X1683944Y-541459D01*
G01X1683978Y-541449D02*
X1683973Y-541464D01*
G01X1684313Y-541449D02*
X1684308Y-541464D01*
G01X1686837Y-541850D02*
X1687059Y-541171D01*
G01X1686813Y-541951D02*
X1686714Y-542252D01*
G01X1686567D02*
X1686960Y-541071D01*
G01X1683102Y-541479D02*
X1683176Y-541268D01*
G01X1683191Y-541318D02*
X1683122Y-541504D01*
G01X1683397Y-541353D02*
X1683407Y-541333D01*
G01X1684273Y-541353D02*
X1684283Y-541333D01*
G01Y-541459D02*
X1684288Y-541449D01*
G01X1684017Y-541444D02*
X1684081Y-541318D01*
G01X1684096Y-541328D02*
X1684032Y-541454D01*
G01X1683639Y-541288D02*
X1683653Y-541308D01*
G01X1683958Y-541388D02*
X1683973Y-541408D01*
G01X1683958Y-541288D02*
X1683973Y-541308D01*
G01X1683407Y-541323D02*
X1683397Y-541308D01*
G01X1684150Y-541479D02*
X1684141Y-541464D01*
G01X1684298Y-541394D02*
X1684308Y-541408D01*
G01X1684283Y-541323D02*
X1684273Y-541308D01*
G01X1684160Y-541449D02*
X1684165Y-541459D01*
G01X1684288Y-541429D02*
X1684278Y-541408D01*
G01X1687157Y-541071D02*
X1687551Y-542252D01*
G01X1687403D02*
X1687305Y-541951D01*
G01X1687059Y-541171D02*
X1687280Y-541850D01*
G01X1683299Y-541308D02*
X1683289Y-541323D01*
G01X1683432Y-541353D02*
X1683422Y-541368D01*
G01X1684175Y-541308D02*
X1684165Y-541323D01*
G01X1684303Y-541353D02*
X1684293Y-541368D01*
G01X1684308Y-541464D02*
X1684298Y-541479D01*
G01X1683653Y-541358D02*
X1683639Y-541379D01*
G01X1683973Y-541358D02*
X1683958Y-541379D01*
G01X1683973Y-541464D02*
X1683958Y-541484D01*
G01X1683698Y-541303D02*
X1683727Y-541268D01*
G01Y-541308D02*
X1683698Y-541343D01*
G01X1683934Y-541404D02*
X1683944Y-541414D01*
G01Y-541313D02*
X1683934Y-541303D01*
G01X1683412Y-541283D02*
X1683432Y-541303D01*
G01X1683624Y-541308D02*
X1683614Y-541298D01*
G01X1684165Y-541459D02*
X1684175Y-541469D01*
G01X1684283Y-541283D02*
X1684303Y-541303D01*
G01X1683269D02*
X1683289Y-541283D01*
G01X1683614Y-541364D02*
X1683624Y-541353D01*
G01X1683934Y-541364D02*
X1683944Y-541353D01*
G01Y-541459D02*
X1683934Y-541469D01*
G01X1684145Y-541303D02*
X1684165Y-541283D01*
G01X1684263Y-541364D02*
X1684273Y-541353D01*
G01Y-541469D02*
X1684283Y-541459D01*
G01X1683259Y-541479D02*
X1683397Y-541353D01*
G01X1683422Y-541368D02*
X1683299Y-541479D01*
G01X1683397Y-541308D02*
X1683383Y-541298D01*
G01X1684032Y-541454D02*
X1684017Y-541444D01*
G01X1684165Y-541489D02*
X1684150Y-541479D01*
G01X1684081Y-541318D02*
X1684096Y-541328D01*
G01X1684278Y-541408D02*
X1684263Y-541399D01*
G01X1684273Y-541308D02*
X1684259Y-541298D01*
G01X1683619Y-541273D02*
X1683639Y-541288D01*
G01X1683939Y-541273D02*
X1683958Y-541288D01*
G01X1683639Y-541379D02*
X1683619Y-541394D01*
G01X1683958Y-541484D02*
X1683939Y-541499D01*
G01X1684293Y-541368D02*
X1684273Y-541384D01*
G01X1683314Y-541298D02*
X1683299Y-541308D01*
G01X1684190Y-541298D02*
X1684175Y-541308D01*
G01X1684298Y-541479D02*
X1684283Y-541489D01*
G01X1683393Y-541273D02*
X1683412Y-541283D01*
G01X1683948Y-541384D02*
X1683958Y-541388D01*
G01X1684185Y-541499D02*
X1684165Y-541489D01*
G01X1684175Y-541469D02*
X1684185Y-541474D01*
G01X1684263Y-541273D02*
X1684283Y-541283D01*
G01X1683289D02*
X1683309Y-541273D01*
G01X1683958Y-541379D02*
X1683948Y-541384D01*
G01X1684165Y-541283D02*
X1684185Y-541273D01*
G01X1684263Y-541474D02*
X1684273Y-541469D01*
G01X1684283Y-541489D02*
X1684263Y-541499D01*
G01X1683614Y-541298D02*
X1683599Y-541293D01*
G01X1683919Y-541399D02*
X1683934Y-541404D01*
G01Y-541303D02*
X1683919Y-541298D01*
G01X1684273Y-541384D02*
X1684298Y-541394D01*
G01X1683599Y-541368D02*
X1683614Y-541364D01*
G01X1683919Y-541368D02*
X1683934Y-541364D01*
G01Y-541469D02*
X1683919Y-541474D01*
G01X1684234Y-541373D02*
X1684263Y-541364D01*
G01X1684185Y-541474D02*
X1684209Y-541479D01*
G01X1683383Y-541298D02*
X1683358Y-541293D01*
G01X1683594Y-541268D02*
X1683619Y-541273D01*
G01X1683914Y-541268D02*
X1683939Y-541273D01*
G01X1684259Y-541298D02*
X1684234Y-541293D01*
G01X1684204Y-541504D02*
X1684185Y-541499D01*
G01X1684229Y-541268D02*
X1684263Y-541273D01*
G01X1683363Y-541268D02*
X1683393Y-541273D01*
G01X1684263Y-541399D02*
X1684234Y-541394D01*
G01X1690031Y-544890D02*
X1687275D01*
G01X1690031D02*
X1683732D01*
G01X1686714Y-542252D02*
X1686567D01*
G01X1687551D02*
X1687403D01*
G01X1687305Y-541951D02*
X1686813D01*
G01X1687280Y-541850D02*
X1686837D01*
G01X1684244Y-541504D02*
X1684204D01*
G01X1684460D02*
X1684431D01*
G01X1683220D02*
X1683191D01*
G01X1683122D02*
X1683082D01*
G01X1683437D02*
X1683259D01*
G01X1683506D02*
X1683476D01*
G01X1683757D02*
X1683727D01*
G01X1683914D02*
X1683796D01*
G01X1683299Y-541479D02*
X1683437D01*
G01X1684209D02*
X1684239D01*
G01X1683919Y-541474D02*
X1683826D01*
G01X1684135Y-541449D02*
X1684160D01*
G01X1683594Y-541399D02*
X1683506D01*
G01X1683826D02*
X1683919D01*
G01X1684234Y-541394D02*
X1684214D01*
G01Y-541373D02*
X1684234D01*
G01X1683506Y-541368D02*
X1683599D01*
G01X1683826D02*
X1683919D01*
G01X1684165Y-541323D02*
X1684141D01*
G01X1683289D02*
X1683265D01*
G01X1683919Y-541298D02*
X1683826D01*
G01X1684234Y-541293D02*
X1684214D01*
G01X1684431D02*
X1684352D01*
G01X1684539D02*
X1684460D01*
G01X1683358D02*
X1683338D01*
G01X1683599D02*
X1683506D01*
G01X1683176Y-541268D02*
X1683220D01*
G01X1683343D02*
X1683363D01*
G01X1683476D02*
X1683594D01*
G01X1683727D02*
X1683757D01*
G01X1683796D02*
X1683914D01*
G01X1684219D02*
X1684229D01*
G01X1684352D02*
X1684539D01*
G01X1686960Y-541071D02*
X1687157D01*
G01X1687275Y-538591D02*
X1690031D01*
G01X1683732D02*
X1690031D01*
G01X1684185Y-541273D02*
X1684219Y-541268D01*
G01X1683309Y-541273D02*
X1683343Y-541268D01*
G01X1684263Y-541499D02*
X1684244Y-541504D01*
G01X1684239Y-541479D02*
X1684263Y-541474D01*
G01X1683939Y-541499D02*
X1683914Y-541504D01*
G01X1684214Y-541293D02*
X1684190Y-541298D01*
G01X1683619Y-541394D02*
X1683594Y-541399D01*
G01X1683338Y-541293D02*
X1683314Y-541298D01*
G01X1683013Y-494074D02*
Y-494260D01*
G01X1683191D02*
Y-494074D01*
G01X1683220Y-494024D02*
Y-494260D01*
G01X1683259D02*
Y-494235D01*
G01X1683407Y-494089D02*
Y-494079D01*
G01X1683437Y-494235D02*
Y-494260D01*
G01Y-494079D02*
Y-494089D01*
G01X1683476Y-494260D02*
Y-494024D01*
G01X1683506Y-494155D02*
Y-494260D01*
G01Y-494049D02*
Y-494124D01*
G01X1683629Y-494094D02*
Y-494079D01*
G01X1683658D02*
Y-494099D01*
G01X1683698D02*
Y-494059D01*
G01X1683727Y-494260D02*
Y-494064D01*
G01X1683757Y-494024D02*
Y-494260D01*
G01X1683796D02*
Y-494024D01*
G01X1683826Y-494054D02*
Y-494124D01*
G01Y-494230D02*
Y-494155D01*
G01X1683948Y-494184D02*
Y-494200D01*
G01Y-494094D02*
Y-494084D01*
G01X1683978Y-494079D02*
Y-494099D01*
G01Y-494180D02*
Y-494205D01*
G01X1684214Y-494149D02*
Y-494129D01*
G01X1684283Y-494089D02*
Y-494079D01*
G01X1684288Y-494205D02*
Y-494184D01*
G01X1684308Y-494079D02*
Y-494089D01*
G01X1684313Y-494184D02*
Y-494205D01*
G01X1684352Y-494049D02*
Y-494024D01*
G01X1684431Y-494260D02*
Y-494049D01*
G01X1684460D02*
Y-494260D01*
G01X1684539Y-494024D02*
Y-494049D01*
G01X1683265Y-494079D02*
X1683269Y-494059D01*
G01X1683437Y-494089D02*
X1683432Y-494109D01*
G01X1684141Y-494079D02*
X1684145Y-494059D01*
G01X1684308Y-494089D02*
X1684303Y-494109D01*
G01X1683624D02*
X1683629Y-494094D01*
G01X1683658Y-494099D02*
X1683653Y-494114D01*
G01X1683944Y-494109D02*
X1683948Y-494094D01*
G01X1683978Y-494099D02*
X1683973Y-494114D01*
G01X1683948Y-494200D02*
X1683944Y-494215D01*
G01X1683978Y-494205D02*
X1683973Y-494220D01*
G01X1684313Y-494205D02*
X1684308Y-494220D01*
G01X1686837Y-494606D02*
X1687059Y-493927D01*
G01X1683102Y-494235D02*
X1683176Y-494024D01*
G01X1683191Y-494074D02*
X1683122Y-494260D01*
G01X1683397Y-494109D02*
X1683407Y-494089D01*
G01X1684273Y-494109D02*
X1684283Y-494089D01*
G01Y-494215D02*
X1684288Y-494205D01*
G01X1684017Y-494200D02*
X1684081Y-494074D01*
G01X1684096Y-494084D02*
X1684032Y-494210D01*
G01X1683299Y-494064D02*
X1683289Y-494079D01*
G01X1683432Y-494109D02*
X1683422Y-494124D01*
G01X1684175Y-494064D02*
X1684165Y-494079D01*
G01X1684303Y-494109D02*
X1684293Y-494124D01*
G01X1684308Y-494220D02*
X1684298Y-494235D01*
G01X1683653Y-494114D02*
X1683639Y-494134D01*
G01X1683973Y-494114D02*
X1683958Y-494134D01*
G01X1683973Y-494220D02*
X1683958Y-494240D01*
G01X1683698Y-494059D02*
X1683727Y-494024D01*
G01Y-494064D02*
X1683698Y-494099D01*
G01X1683269Y-494059D02*
X1683289Y-494039D01*
G01X1683614Y-494120D02*
X1683624Y-494109D01*
G01X1683934Y-494120D02*
X1683944Y-494109D01*
G01Y-494215D02*
X1683934Y-494225D01*
G01X1684145Y-494059D02*
X1684165Y-494039D01*
G01X1684263Y-494120D02*
X1684273Y-494109D01*
G01Y-494225D02*
X1684283Y-494215D01*
G01X1683259Y-494235D02*
X1683397Y-494109D01*
G01X1683422Y-494124D02*
X1683299Y-494235D01*
G01X1683639Y-494134D02*
X1683619Y-494149D01*
G01X1683958Y-494240D02*
X1683939Y-494255D01*
G01X1684293Y-494124D02*
X1684273Y-494140D01*
G01X1683314Y-494054D02*
X1683299Y-494064D01*
G01X1684190Y-494054D02*
X1684175Y-494064D01*
G01X1684298Y-494235D02*
X1684283Y-494245D01*
G01X1683028Y-494024D02*
X1683102Y-494235D01*
G01X1683629Y-494079D02*
X1683624Y-494064D01*
G01X1683653D02*
X1683658Y-494079D01*
G01X1683944Y-494170D02*
X1683948Y-494184D01*
G01X1683973Y-494164D02*
X1683978Y-494180D01*
G01X1683948Y-494084D02*
X1683944Y-494069D01*
G01X1683973Y-494064D02*
X1683978Y-494079D01*
G01X1684141Y-494220D02*
X1684135Y-494205D01*
G01X1683432Y-494059D02*
X1683437Y-494079D01*
G01X1684308Y-494164D02*
X1684313Y-494184D01*
G01X1684303Y-494059D02*
X1684308Y-494079D01*
G01X1683289Y-494039D02*
X1683309Y-494029D01*
G01X1683958Y-494134D02*
X1683948Y-494140D01*
G01X1684165Y-494039D02*
X1684185Y-494029D01*
G01X1684263Y-494230D02*
X1684273Y-494225D01*
G01X1684283Y-494245D02*
X1684263Y-494255D01*
G01X1684160Y-494205D02*
X1684165Y-494215D01*
G01X1684288Y-494184D02*
X1684278Y-494164D01*
G01X1683082Y-494260D02*
X1683013Y-494074D01*
G01X1687059Y-493927D02*
X1687280Y-494606D01*
G01X1683599Y-494124D02*
X1683614Y-494120D01*
G01X1683919Y-494124D02*
X1683934Y-494120D01*
G01Y-494225D02*
X1683919Y-494230D01*
G01X1684234Y-494129D02*
X1684263Y-494120D01*
G01X1683639Y-494044D02*
X1683653Y-494064D01*
G01X1683958Y-494144D02*
X1683973Y-494164D01*
G01X1683958Y-494044D02*
X1683973Y-494064D01*
G01X1683407Y-494079D02*
X1683397Y-494064D01*
G01X1684150Y-494235D02*
X1684141Y-494220D01*
G01X1684298Y-494149D02*
X1684308Y-494164D01*
G01X1684283Y-494079D02*
X1684273Y-494064D01*
G01X1683934Y-494160D02*
X1683944Y-494170D01*
G01Y-494069D02*
X1683934Y-494059D01*
G01X1683412Y-494039D02*
X1683432Y-494059D01*
G01X1683624Y-494064D02*
X1683614Y-494054D01*
G01X1684165Y-494215D02*
X1684175Y-494225D01*
G01X1684283Y-494039D02*
X1684303Y-494059D01*
G01X1683397Y-494064D02*
X1683383Y-494054D01*
G01X1684032Y-494210D02*
X1684017Y-494200D01*
G01X1684165Y-494245D02*
X1684150Y-494235D01*
G01X1684081Y-494074D02*
X1684096Y-494084D01*
G01X1684278Y-494164D02*
X1684263Y-494155D01*
G01X1684273Y-494064D02*
X1684259Y-494054D01*
G01X1683619Y-494029D02*
X1683639Y-494044D01*
G01X1683939Y-494029D02*
X1683958Y-494044D01*
G01X1683393Y-494029D02*
X1683412Y-494039D01*
G01X1683948Y-494140D02*
X1683958Y-494144D01*
G01X1684185Y-494255D02*
X1684165Y-494245D01*
G01X1684175Y-494225D02*
X1684185Y-494230D01*
G01X1684263Y-494029D02*
X1684283Y-494039D01*
G01X1684273Y-494140D02*
X1684298Y-494149D01*
G01X1684204Y-494260D02*
X1684185Y-494255D01*
G01X1683614Y-494054D02*
X1683599Y-494049D01*
G01X1683919Y-494155D02*
X1683934Y-494160D01*
G01Y-494059D02*
X1683919Y-494054D01*
G01X1684229Y-494024D02*
X1684263Y-494029D01*
G01X1683363Y-494024D02*
X1683393Y-494029D01*
G01X1684263Y-494155D02*
X1684234Y-494149D01*
G01X1684185Y-494230D02*
X1684209Y-494235D01*
G01X1683383Y-494054D02*
X1683358Y-494049D01*
G01X1683594Y-494024D02*
X1683619Y-494029D01*
G01X1683914Y-494024D02*
X1683939Y-494029D01*
G01X1684259Y-494054D02*
X1684234Y-494049D01*
G01X1687280Y-494606D02*
X1686837D01*
G01X1684244Y-494260D02*
X1684204D01*
G01X1684460D02*
X1684431D01*
G01X1683220D02*
X1683191D01*
G01X1683122D02*
X1683082D01*
G01X1683437D02*
X1683259D01*
G01X1683506D02*
X1683476D01*
G01X1683757D02*
X1683727D01*
G01X1683914D02*
X1683796D01*
G01X1683299Y-494235D02*
X1683437D01*
G01X1684209D02*
X1684239D01*
G01X1683919Y-494230D02*
X1683826D01*
G01X1684135Y-494205D02*
X1684160D01*
G01X1683594Y-494155D02*
X1683506D01*
G01X1683826D02*
X1683919D01*
G01X1684234Y-494149D02*
X1684214D01*
G01Y-494129D02*
X1684234D01*
G01X1683506Y-494124D02*
X1683599D01*
G01X1683826D02*
X1683919D01*
G01X1684165Y-494079D02*
X1684141D01*
G01X1683289D02*
X1683265D01*
G01X1683919Y-494054D02*
X1683826D01*
G01X1684234Y-494049D02*
X1684214D01*
G01X1684431D02*
X1684352D01*
G01X1684539D02*
X1684460D01*
G01X1683358D02*
X1683338D01*
G01X1683599D02*
X1683506D01*
G01X1683176Y-494024D02*
X1683220D01*
G01X1683343D02*
X1683363D01*
G01X1683476D02*
X1683594D01*
G01X1683727D02*
X1683757D01*
G01X1683796D02*
X1683914D01*
G01X1684219D02*
X1684229D01*
G01X1684352D02*
X1684539D01*
G01X1686960Y-493827D02*
X1687157D01*
G01X1687275Y-491347D02*
X1690031D01*
G01X1683732D02*
X1690031D01*
G01X1684263Y-494255D02*
X1684244Y-494260D01*
G01X1684239Y-494235D02*
X1684263Y-494230D01*
G01X1683939Y-494255D02*
X1683914Y-494260D01*
G01X1684214Y-494049D02*
X1684190Y-494054D01*
G01X1683619Y-494149D02*
X1683594Y-494155D01*
G01X1683338Y-494049D02*
X1683314Y-494054D01*
G01X1684185Y-494029D02*
X1684219Y-494024D01*
G01X1683309Y-494029D02*
X1683343Y-494024D01*
G01X1683732Y-497646D02*
Y-491347D01*
G01Y-497646D02*
Y-491347D01*
G01X1685372Y-497646D02*
Y-491347D01*
G01X1685700Y-497646D02*
Y-491347D01*
G01X1687275Y-497646D02*
Y-491347D01*
G01X1686813Y-494707D02*
X1686714Y-495008D01*
G01X1686567D02*
X1686960Y-493827D01*
G01X1690031Y-491347D02*
Y-497646D01*
G01Y-491347D02*
Y-497646D01*
G01X1687157Y-493827D02*
X1687551Y-495008D01*
G01X1687403D02*
X1687305Y-494707D01*
G01X1690031Y-497646D02*
X1687275D01*
G01X1690031D02*
X1683732D01*
G01X1686714Y-495008D02*
X1686567D01*
G01X1687551D02*
X1687403D01*
G01X1687305Y-494707D02*
X1686813D01*
G01X1709716Y-462292D02*
X1740504Y-431504D01*
G01X1690799Y-438668D02*
X1709026Y-417347D01*
G01D02*
X1731863Y-399676D01*
G01X1842393Y-415756D02*
X1711082D01*
G01X1842393D02*
X1711082D01*
G01X1709716Y-427567D02*
Y-327275D01*
G01Y-431504D02*
X1881763D01*
G01X1709716Y-331212D02*
X1795740D01*
G01X1687550Y-30304D02*
X1686575Y-29582D01*
X1686088Y-28860D01*
X1685601Y-27417D01*
Y-24530D01*
X1686088Y-23086D01*
X1686575Y-22364D01*
X1687550Y-21643D01*
X1688524Y-22364D01*
X1689011Y-23086D01*
X1689498Y-24530D01*
Y-27417D01*
X1689011Y-28860D01*
X1688524Y-29582D01*
X1687550Y-30304D01*
G01X1696807Y-25251D02*
X1694858Y-26695D01*
X1693883Y-28138D01*
X1693396Y-30304D01*
X1697294D01*
G01X1693396Y-23086D02*
X1693883Y-22364D01*
X1694858Y-21643D01*
X1695832D01*
X1696807Y-22364D01*
X1697294Y-23086D01*
Y-24530D01*
X1696807Y-25251D01*
G01X1733668Y913763D02*
X1700389D01*
G01X1704326Y1009791D02*
Y916322D01*
G01Y913763D02*
Y894078D01*
G01D02*
Y916322D01*
G01X1702161Y949016D02*
Y948529D01*
X1701439D01*
X1702161Y949016D01*
G01X1693499Y941221D02*
X1702161D01*
G01X1735531Y918881D02*
X1700389D01*
G01X1704326D02*
Y1009791D01*
G01X1697830Y958273D02*
X1699274Y959247D01*
X1699995D01*
G01X1702161Y982507D02*
X1701439Y981533D01*
X1700717Y981045D01*
X1699274Y980558D01*
X1696386D01*
X1694943Y981045D01*
X1694221Y981533D01*
X1693499Y982507D01*
X1694221Y983481D01*
X1694943Y983969D01*
X1696386Y984456D01*
X1699274D01*
X1700717Y983969D01*
X1701439Y983481D01*
X1702161Y982507D01*
G01Y964607D02*
X1701439Y963632D01*
X1700717Y963145D01*
X1699274Y962658D01*
X1696386D01*
X1694943Y963145D01*
X1694221Y963632D01*
X1693499Y964607D01*
X1694221Y965581D01*
X1694943Y966068D01*
X1696386Y966556D01*
X1699274D01*
X1700717Y966068D01*
X1701439Y965581D01*
X1702161Y964607D01*
G01X1697108Y956325D02*
Y957299D01*
G01X1697830Y968505D02*
Y977166D01*
G01X1702161Y968505D02*
Y977166D01*
G01X1693499Y972835D02*
X1702161D01*
G01X1694221Y955350D02*
X1693499Y956325D01*
Y957299D01*
X1694221Y958273D01*
X1694943Y958760D01*
X1695665D01*
X1696386Y958273D01*
X1697108Y957299D01*
X1697830Y958273D01*
G01X1699995Y959247D02*
X1701439Y958273D01*
X1702161Y957299D01*
Y956325D01*
X1701439Y955350D01*
X1700717Y954863D01*
G01X1697830Y1007355D02*
X1699274Y1008329D01*
X1699995D01*
G01X1697108Y1005406D02*
Y1006380D01*
G01X1702161Y990303D02*
Y989815D01*
X1701439D01*
X1702161Y990303D01*
G01X1694221Y1004431D02*
X1693499Y1005406D01*
Y1006380D01*
X1694221Y1007355D01*
X1694943Y1007842D01*
X1695665D01*
X1696386Y1007355D01*
X1697108Y1006380D01*
X1697830Y1007355D01*
G01X1693499Y998097D02*
X1702161D01*
G01X1699995Y1008329D02*
X1701439Y1007355D01*
X1702161Y1006380D01*
Y1005406D01*
X1701439Y1004431D01*
X1700717Y1003944D01*
G01X1724370Y-1120610D02*
Y-1139623D01*
G01X1742854Y-744016D02*
X1738957D01*
Y-735354D01*
X1742854D01*
G01X1723854Y-741128D02*
X1726777D01*
G01X1738957Y-739685D02*
X1741393D01*
G01X1731161Y-735354D02*
Y-744016D01*
X1735059D01*
G01X1722879D02*
X1725315Y-735354D01*
X1727751Y-744016D01*
G01X1746265Y-722362D02*
X1751137D01*
G01X1748701D02*
Y-731023D01*
G01X1738957Y-726693D02*
X1741393D01*
G01X1731161Y-722362D02*
X1733110D01*
X1734085Y-723084D01*
X1735059Y-724527D01*
G01D02*
X1735546Y-726693D01*
X1735059Y-728858D01*
X1734085Y-730301D01*
G01X1742854Y-731023D02*
X1738957D01*
Y-722362D01*
X1742854D01*
G01X1734085Y-730301D02*
X1733110Y-731023D01*
X1731161D01*
Y-722362D01*
G01X1752840Y-644103D02*
X1749690D01*
G01X1752840D02*
X1749690D01*
G01D02*
Y-632308D01*
G01Y-644103D02*
Y-632308D01*
G01X1734992Y-644103D02*
X1731842D01*
G01X1734992D02*
X1731842D01*
G01D02*
Y-618906D01*
G01Y-644103D02*
Y-618906D01*
G01X1734992Y-632308D02*
Y-644103D01*
G01Y-632308D02*
Y-644103D01*
G01X1749690Y-618906D02*
X1752840D01*
G01X1749690D02*
X1752840D01*
G01X1749690Y-629092D02*
Y-618906D01*
G01Y-629092D02*
Y-618906D01*
G01X1734992Y-629092D02*
X1749690D01*
G01X1734992D02*
X1749690D01*
G01X1731842Y-618906D02*
X1734992D01*
G01X1731842D02*
X1734992D01*
G01D02*
Y-629092D01*
G01Y-618906D02*
Y-629092D01*
G01X1749690Y-632308D02*
X1734992D01*
G01X1749690D02*
X1734992D01*
G01X1749086Y-536229D02*
Y-344731D01*
G01X1761685Y-540166D02*
G03I-12599J0D01*
G01D02*
G03I-12599J0D01*
G01X1731863Y-399676D02*
X1784129Y-379326D01*
G01X1749086Y-348668D02*
X1815425D01*
G01X1743904Y1558D02*
Y913763D01*
G01X1737605Y1558D02*
X1743904D01*
G01X1737605Y5495D02*
X1743904D01*
G01X1737605Y1558D02*
Y20643D01*
G01Y1558D02*
Y913763D01*
G01X1743904Y13369D02*
X1737605D01*
G01X1743904Y17306D02*
X1737605D01*
G01X1743904Y21243D02*
X1737605D01*
G01X1743904Y25180D02*
X1737605D01*
G01X1743904Y29118D02*
X1737605D01*
G01X1743904Y36204D02*
X1737605D01*
G01Y20643D02*
Y21243D01*
G01D02*
Y123044D01*
G01Y9432D02*
X1743904D01*
G01Y48803D02*
X1737605D01*
G01Y54432D02*
X1743904D01*
G01X1737605Y57464D02*
X1743904D01*
G01Y59432D02*
X1737605D01*
G01X1743904Y61401D02*
X1737605D01*
G01Y63094D02*
X1743904D01*
G01X1737605Y70850D02*
X1743904D01*
G01X1737605Y83448D02*
X1743904D01*
G01Y92897D02*
X1737605D01*
G01X1743904Y94866D02*
X1737605D01*
G01X1743904Y96834D02*
X1737605D01*
G01X1743904Y105495D02*
X1737605D01*
G01X1743904Y115771D02*
X1737605D01*
G01X1743904Y118094D02*
X1737605D01*
G01X1743904Y123645D02*
X1737605D01*
G01X1743904Y131519D02*
X1737605D01*
G01Y861795D02*
Y123645D01*
G01Y123044D02*
Y123645D01*
G01Y149590D02*
X1743904D01*
G01X1737605Y164551D02*
X1743904D01*
G01X1737605Y250377D02*
X1743904D01*
G01X1737605Y251165D02*
X1743904D01*
G01X1737605Y263763D02*
X1743904D01*
G01X1737605Y266913D02*
X1743904D01*
G01X1737605Y298409D02*
X1743904D01*
G01X1737605Y311007D02*
X1743904D01*
G01X1737605Y666913D02*
X1743904D01*
G01Y671913D02*
X1737605D01*
G01Y814944D02*
X1743904D01*
G01X1737605Y829905D02*
X1743904D01*
G01Y842110D02*
X1737605D01*
G01X1724690Y865652D02*
G03X1743904Y861957I19214J48111D01*
G01X1737605Y861795D02*
Y862191D01*
G01D02*
Y894866D01*
G01X1743904Y857858D02*
X1737605D01*
G01Y861795D02*
X1743904D01*
G01X1737605Y866913D02*
X1743904D01*
G01Y913763D02*
X1742042Y918881D01*
G01X1745251Y910064D02*
X1762970Y861382D01*
G01X1739468Y918881D02*
X1737605Y913763D01*
G01D02*
Y904708D01*
G01Y913763D02*
Y904708D01*
G01Y913763D02*
Y904708D01*
G01Y904118D02*
Y902149D01*
G01Y904118D02*
Y902149D01*
G01Y903531D02*
Y902735D01*
G01D02*
Y902149D01*
G01Y894866D02*
Y895132D01*
G01D02*
Y918881D01*
G01Y903531D02*
Y904118D01*
G01X1743904Y892897D02*
X1737605D01*
G01Y894866D02*
X1743904D01*
G01X1737605Y896834D02*
X1743904D01*
G01Y897228D02*
X1737605D01*
G01X1743904Y913763D02*
X1737605D01*
G01X1743904Y917700D02*
Y959787D01*
G01X1737605Y917700D02*
Y959787D01*
G01X1742042Y918881D02*
X1739468D01*
G01X1743904Y955850D02*
X1851424D01*
G01X1737605D02*
X1717920D01*
G01D02*
X1740755D01*
G01X1851424D02*
X1740755D01*
G01X1724370Y2171102D02*
Y2152090D01*
G01X1779882Y-744016D02*
X1778907Y-743294D01*
X1778420Y-742572D01*
X1777933Y-741128D01*
Y-738241D01*
X1778420Y-736797D01*
X1778907Y-736076D01*
X1779882Y-735354D01*
X1780856Y-736076D01*
X1781344Y-736797D01*
X1781831Y-738241D01*
Y-741128D01*
X1781344Y-742572D01*
X1780856Y-743294D01*
X1779882Y-744016D01*
G01X1772087D02*
X1771600D01*
Y-743294D01*
X1772087Y-744016D01*
G01X1762343Y-736797D02*
X1762830Y-736076D01*
X1763804Y-735354D01*
X1764779D01*
X1765753Y-736076D01*
X1766240Y-736797D01*
Y-738241D01*
X1765753Y-738963D01*
G01D02*
X1763804Y-740407D01*
X1762830Y-741850D01*
X1762343Y-744016D01*
X1766240D01*
G01X1755035Y-728136D02*
X1757958D01*
G01X1764291Y-722362D02*
Y-731023D01*
G01X1770138Y-722362D02*
Y-731023D01*
X1774035D01*
G01X1754060D02*
X1756496Y-722362D01*
X1758932Y-731023D01*
G01X1775937Y-643566D02*
X1779086Y-644103D01*
G01X1775937Y-643566D02*
X1779086Y-644103D01*
G01Y-641422D02*
X1781711Y-640886D01*
G01X1779086Y-641422D02*
X1781711Y-640886D01*
G01X1779086Y-644103D02*
X1782236Y-643566D01*
G01X1779086Y-644103D02*
X1782236Y-643566D01*
G01X1776462Y-640886D02*
X1779086Y-641422D01*
G01X1776462Y-640886D02*
X1779086Y-641422D01*
G01X1774887Y-639814D02*
X1776462Y-640886D01*
G01X1774887Y-639814D02*
X1776462Y-640886D01*
G01X1783286Y-639814D02*
X1785385Y-636597D01*
G01X1783286Y-639814D02*
X1785385Y-636597D01*
G01X1781711Y-640886D02*
X1783286Y-639814D01*
G01X1781711Y-640886D02*
X1783286Y-639814D01*
G01X1782236Y-643566D02*
X1784861Y-641958D01*
G01X1782236Y-643566D02*
X1784861Y-641958D01*
G01X1765438Y-635525D02*
X1757039D01*
G01X1765438D02*
X1757039D01*
G01X1773312Y-641958D02*
X1775937Y-643566D01*
G01X1773312Y-641958D02*
X1775937Y-643566D01*
G01X1771737Y-640350D02*
X1773312Y-641958D01*
G01X1771737Y-640350D02*
X1773312Y-641958D01*
G01X1772787Y-636597D02*
X1774887Y-639814D01*
G01X1772787Y-636597D02*
X1774887Y-639814D01*
G01X1770687Y-638205D02*
X1771737Y-640350D01*
G01X1770687Y-638205D02*
X1771737Y-640350D01*
G01X1770163Y-636597D02*
X1770687Y-638205D01*
G01X1770163Y-636597D02*
X1770687Y-638205D01*
G01X1752840Y-618906D02*
Y-644103D01*
G01Y-618906D02*
Y-644103D01*
G01X1757039Y-635525D02*
Y-633381D01*
G01Y-635525D02*
Y-633381D01*
G01X1769637Y-633917D02*
X1770163Y-636597D01*
G01X1769637Y-633917D02*
X1770163Y-636597D01*
G01X1772262Y-633381D02*
X1772787Y-636597D01*
G01X1772262Y-633381D02*
X1772787Y-636597D01*
G01X1765438Y-633381D02*
Y-635525D01*
G01Y-633381D02*
Y-635525D01*
G01X1782236Y-619442D02*
X1779086Y-618906D01*
G01X1782236Y-619442D02*
X1779086Y-618906D01*
G01X1781711Y-622122D02*
X1779086Y-621586D01*
G01X1781711Y-622122D02*
X1779086Y-621586D01*
G01D02*
X1776462Y-622122D01*
G01X1779086Y-621586D02*
X1776462Y-622122D01*
G01X1779086Y-618906D02*
X1775937Y-619442D01*
G01X1779086Y-618906D02*
X1775937Y-619442D01*
G01X1784861Y-621050D02*
X1782236Y-619442D01*
G01X1784861Y-621050D02*
X1782236Y-619442D01*
G01X1783286Y-623195D02*
X1781711Y-622122D01*
G01X1783286Y-623195D02*
X1781711Y-622122D01*
G01X1785385Y-626411D02*
X1783286Y-623195D01*
G01X1785385Y-626411D02*
X1783286Y-623195D01*
G01X1776462Y-622122D02*
X1774887Y-623195D01*
G01X1776462Y-622122D02*
X1774887Y-623195D01*
G01X1765438Y-629092D02*
X1757039D01*
G01X1765438D02*
X1757039D01*
G01Y-626947D02*
X1765438D01*
G01X1757039D02*
X1765438D01*
G01X1757039Y-629092D02*
Y-626947D01*
G01Y-629092D02*
Y-626947D01*
G01X1765438D02*
Y-629092D01*
G01Y-626947D02*
Y-629092D01*
G01X1772787Y-626411D02*
X1772262Y-629628D01*
G01X1772787Y-626411D02*
X1772262Y-629628D01*
G01X1770163Y-626411D02*
X1769637Y-629092D01*
G01X1770163Y-626411D02*
X1769637Y-629092D01*
G01X1770687Y-624803D02*
X1770163Y-626411D01*
G01X1770687Y-624803D02*
X1770163Y-626411D01*
G01X1771737Y-622658D02*
X1770687Y-624803D01*
G01X1771737Y-622658D02*
X1770687Y-624803D01*
G01X1774887Y-623195D02*
X1772787Y-626411D01*
G01X1774887Y-623195D02*
X1772787Y-626411D01*
G01X1773312Y-621050D02*
X1771737Y-622658D01*
G01X1773312Y-621050D02*
X1771737Y-622658D01*
G01X1775937Y-619442D02*
X1773312Y-621050D01*
G01X1775937Y-619442D02*
X1773312Y-621050D01*
G01X1757039Y-633381D02*
X1765438D01*
G01X1757039D02*
X1765438D01*
G01X1769637Y-629092D02*
Y-633917D01*
G01Y-629092D02*
Y-633917D01*
G01X1772262Y-629628D02*
Y-633381D01*
G01Y-629628D02*
Y-633381D01*
G01X1771755Y-384105D02*
G03X1834381Y-377369I31268J3782D01*
G01X1771755Y-384105D02*
G03X1834381Y-377369I31268J3782D01*
G01X1784129Y-379326D02*
X1788176Y-379169D01*
G01X1761623Y865082D02*
G03X1795687Y915314I-17719J48681D01*
G01X1784861Y910983D02*
X1783886Y911705D01*
X1783399Y912426D01*
X1782912Y913870D01*
Y916757D01*
X1783399Y918201D01*
X1783886Y918922D01*
X1784861Y919644D01*
X1785835Y918922D01*
X1786322Y918201D01*
X1786809Y916757D01*
Y913870D01*
X1786322Y912426D01*
X1785835Y911705D01*
X1784861Y910983D01*
G01X1777065D02*
X1776578D01*
Y911705D01*
X1777065Y910983D01*
G01X1762936Y916035D02*
X1760987Y914592D01*
X1760013Y913148D01*
X1759526Y910983D01*
X1763423D01*
G01X1759526Y918201D02*
X1760013Y918922D01*
X1760987Y919644D01*
X1761962D01*
X1762936Y918922D01*
X1763423Y918201D01*
Y916757D01*
X1762936Y916035D01*
G01X1769270Y910983D02*
X1768296Y911705D01*
X1767808Y912426D01*
X1767321Y913870D01*
Y916757D01*
X1767808Y918201D01*
X1768296Y918922D01*
X1769270Y919644D01*
X1770244Y918922D01*
X1770731Y918201D01*
X1771219Y916757D01*
Y913870D01*
X1770731Y912426D01*
X1770244Y911705D01*
X1769270Y910983D01*
G01X1782855Y966677D02*
Y958015D01*
G01X1787677Y-744016D02*
X1786703Y-743294D01*
X1786216Y-742572D01*
X1785728Y-741128D01*
Y-738241D01*
X1786216Y-736797D01*
X1786703Y-736076D01*
X1787677Y-735354D01*
X1788652Y-736076D01*
X1789139Y-736797D01*
X1789626Y-738241D01*
Y-741128D01*
X1789139Y-742572D01*
X1788652Y-743294D01*
X1787677Y-744016D01*
G01X1795472D02*
X1794498Y-743294D01*
X1794011Y-742572D01*
X1793524Y-741128D01*
Y-738241D01*
X1794011Y-736797D01*
X1794498Y-736076D01*
X1795472Y-735354D01*
X1796447Y-736076D01*
X1796934Y-736797D01*
X1797421Y-738241D01*
Y-741128D01*
X1796934Y-742572D01*
X1796447Y-743294D01*
X1795472Y-744016D01*
G01X1794011Y-730301D02*
X1793037Y-728858D01*
X1792549Y-726693D01*
X1793037Y-724527D01*
G01D02*
X1794011Y-723084D01*
X1794985Y-722362D01*
X1795960D01*
X1796934Y-723084D01*
X1797421Y-723805D01*
G01Y-729580D02*
X1796934Y-730301D01*
X1795960Y-731023D01*
X1794985D01*
X1794011Y-730301D01*
G01X1818981Y-644103D02*
X1816357D01*
G01X1812157D02*
X1809533D01*
G01X1818981D02*
X1816357D01*
G01X1812157D02*
X1809533D01*
G01D02*
Y-631236D01*
G01Y-644103D02*
Y-631236D01*
G01X1812157D02*
Y-644103D01*
G01Y-631236D02*
Y-644103D01*
G01X1816357D02*
Y-626947D01*
G01Y-644103D02*
Y-626947D01*
G01X1803758Y-644103D02*
X1801133D01*
G01X1795359D02*
X1792735D01*
G01X1803758D02*
X1801133D01*
G01X1795359D02*
X1792735D01*
G01D02*
Y-626947D01*
G01Y-644103D02*
Y-626947D01*
G01X1795359Y-630700D02*
Y-644103D01*
G01Y-630700D02*
Y-644103D01*
G01X1801133D02*
Y-631236D01*
G01Y-644103D02*
Y-631236D01*
G01X1803758D02*
Y-644103D01*
G01Y-631236D02*
Y-644103D01*
G01X1785385Y-636597D02*
X1785911Y-633381D01*
G01X1785385Y-636597D02*
X1785911Y-633381D01*
G01X1788010Y-636597D02*
X1788535Y-633917D01*
G01X1788010Y-636597D02*
X1788535Y-633917D01*
G01X1787485Y-638205D02*
X1788010Y-636597D01*
G01X1787485Y-638205D02*
X1788010Y-636597D01*
G01X1786435Y-640350D02*
X1787485Y-638205D01*
G01X1786435Y-640350D02*
X1787485Y-638205D01*
G01X1784861Y-641958D02*
X1786435Y-640350D01*
G01X1784861Y-641958D02*
X1786435Y-640350D01*
G01X1784834Y-651977D02*
X1823657Y-613154D01*
G01X1816357Y-626947D02*
X1818981D01*
G01X1816357D02*
X1818981D01*
G01X1808483D02*
X1810057Y-627483D01*
G01X1808483Y-626947D02*
X1810057Y-627483D01*
G01D02*
X1811107Y-628556D01*
G01X1810057Y-627483D02*
X1811107Y-628556D01*
G01X1809007Y-630164D02*
X1808483Y-629628D01*
G01X1809007Y-630164D02*
X1808483Y-629628D01*
G01X1809533Y-631236D02*
X1809007Y-630164D01*
G01X1809533Y-631236D02*
X1809007Y-630164D01*
G01X1811107Y-628556D02*
X1812157Y-631236D01*
G01X1811107Y-628556D02*
X1812157Y-631236D01*
G01X1807433Y-629092D02*
X1805858D01*
G01X1799034D02*
X1797984D01*
G01X1807433D02*
X1805858D01*
G01X1799034D02*
X1797984D01*
G01X1792735Y-626947D02*
X1795359D01*
G01X1792735D02*
X1795359D01*
G01X1797984D02*
X1800084D01*
G01X1797984D02*
X1800084D01*
G01X1806383D02*
X1808483D01*
G01X1806383D02*
X1808483D01*
G01X1800084D02*
X1801659Y-627483D01*
G01X1800084Y-626947D02*
X1801659Y-627483D01*
G01X1800084Y-629628D02*
X1799034Y-629092D01*
G01X1800084Y-629628D02*
X1799034Y-629092D01*
G01X1808483Y-629628D02*
X1807433Y-629092D01*
G01X1808483Y-629628D02*
X1807433Y-629092D01*
G01X1786435Y-622658D02*
X1784861Y-621050D01*
G01X1786435Y-622658D02*
X1784861Y-621050D01*
G01X1801659Y-627483D02*
X1803233Y-629092D01*
G01X1801659Y-627483D02*
X1803233Y-629092D01*
G01X1787485Y-624803D02*
X1786435Y-622658D01*
G01X1787485Y-624803D02*
X1786435Y-622658D01*
G01X1788010Y-626411D02*
X1787485Y-624803D01*
G01X1788010Y-626411D02*
X1787485Y-624803D01*
G01X1788535Y-629092D02*
X1788010Y-626411D01*
G01X1788535Y-629092D02*
X1788010Y-626411D01*
G01X1785911Y-629628D02*
X1785385Y-626411D01*
G01X1785911Y-629628D02*
X1785385Y-626411D01*
G01X1795359Y-626947D02*
Y-628556D01*
G01Y-626947D02*
Y-628556D01*
G01D02*
X1796409Y-627483D01*
G01X1795359Y-628556D02*
X1796409Y-627483D01*
G01X1803233Y-629092D02*
X1804808Y-627483D01*
G01X1803233Y-629092D02*
X1804808Y-627483D01*
G01X1796409D02*
X1797984Y-626947D01*
G01X1796409Y-627483D02*
X1797984Y-626947D01*
G01X1805858Y-629092D02*
X1804808Y-629628D01*
G01X1805858Y-629092D02*
X1804808Y-629628D01*
G01X1797984Y-629092D02*
X1796409Y-629628D01*
G01X1797984Y-629092D02*
X1796409Y-629628D01*
G01X1804808Y-627483D02*
X1806383Y-626947D01*
G01X1804808Y-627483D02*
X1806383Y-626947D01*
G01X1800609Y-630164D02*
X1800084Y-629628D01*
G01X1800609Y-630164D02*
X1800084Y-629628D01*
G01X1801133Y-631236D02*
X1800609Y-630164D01*
G01X1801133Y-631236D02*
X1800609Y-630164D01*
G01X1785911Y-633381D02*
Y-629628D01*
G01Y-633381D02*
Y-629628D01*
G01X1788535Y-633917D02*
Y-629092D01*
G01Y-633917D02*
Y-629092D01*
G01X1804283Y-630164D02*
X1803758Y-631236D01*
G01X1804283Y-630164D02*
X1803758Y-631236D01*
G01X1796409Y-629628D02*
X1795359Y-630700D01*
G01X1796409Y-629628D02*
X1795359Y-630700D01*
G01X1804808Y-629628D02*
X1804283Y-630164D01*
G01X1804808Y-629628D02*
X1804283Y-630164D01*
G01X1817757Y-378022D02*
X1839658Y-377173D01*
G01X1788108Y-379164D02*
G03X1817805Y-378015I14916J-1159D01*
G01X1788108Y-379164D02*
G03X1817805Y-378015I14916J-1159D01*
G01X1881763Y-348668D02*
X1815425D01*
G01D02*
X1997767D01*
G01X1881763Y-331212D02*
X1795740D01*
G01D02*
X1992546D01*
G01X1816330Y910983D02*
X1815843D01*
Y911705D01*
X1816330Y910983D01*
G01X1798863Y919644D02*
Y910983D01*
G01X1794532D02*
X1803194D01*
G01X1794532Y915314D02*
X1803194D01*
G01X1810484Y919644D02*
X1807561D01*
X1807073Y916035D01*
X1808048Y916757D01*
X1809022D01*
X1809996Y916035D01*
X1810484Y915314D01*
X1810971Y913870D01*
X1810484Y912426D01*
X1809996Y911705D01*
X1809022Y910983D01*
X1808048D01*
X1807073Y911705D01*
X1806586Y912426D01*
G01X1788758Y921088D02*
Y919644D01*
X1789480Y918922D01*
X1790923D01*
X1791645Y919644D01*
Y921088D01*
X1790923Y921810D01*
X1789480D01*
X1788758Y921088D01*
G01X1814469Y966677D02*
Y958015D01*
G01X1810138D02*
X1818800D01*
G01X1810138Y962346D02*
X1818800D01*
G01X1796496Y960903D02*
X1796983Y962346D01*
X1798445Y963068D01*
X1799907Y962346D01*
X1800394Y960903D01*
X1799907Y959459D01*
X1799420Y958737D01*
X1798445Y958015D01*
X1797471Y958737D01*
X1796983Y959459D01*
X1796496Y960903D01*
Y963790D01*
X1796983Y965233D01*
X1797471Y965955D01*
X1798445Y966677D01*
X1799420Y965955D01*
X1799907Y965233D01*
G01X1790650Y958015D02*
X1790163D01*
Y958737D01*
X1790650Y958015D01*
G01X1806241D02*
X1805266Y958737D01*
X1804779Y959459D01*
X1804292Y960903D01*
Y963790D01*
X1804779Y965233D01*
X1805266Y965955D01*
X1806241Y966677D01*
X1807215Y965955D01*
X1807702Y965233D01*
X1808189Y963790D01*
Y960903D01*
X1807702Y959459D01*
X1807215Y958737D01*
X1806241Y958015D01*
G01X1846048Y-1124413D02*
Y-1135820D01*
G01X1834641Y-1124413D02*
Y-1135820D01*
G01X1835779Y-644103D02*
X1833155D01*
G01X1827380D02*
X1824756D01*
G01X1835779D02*
X1833155D01*
G01X1827380D02*
X1824756D01*
G01X1818981Y-630700D02*
Y-644103D01*
G01Y-630700D02*
Y-644103D01*
G01X1824756D02*
Y-631236D01*
G01Y-644103D02*
Y-631236D01*
G01X1827380D02*
Y-644103D01*
G01Y-631236D02*
Y-644103D01*
G01X1833155D02*
Y-631236D01*
G01Y-644103D02*
Y-631236D01*
G01X1835779D02*
Y-644103D01*
G01Y-631236D02*
Y-644103D01*
G01X1835700Y-605520D02*
Y-366551D01*
G01X1831055Y-629092D02*
X1829480D01*
G01X1822656D02*
X1821606D01*
G01X1831055D02*
X1829480D01*
G01X1822656D02*
X1821606D01*
G01Y-626947D02*
X1823706D01*
G01X1821606D02*
X1823706D01*
G01X1830005D02*
X1832105D01*
G01X1830005D02*
X1832105D01*
G01X1823706D02*
X1825281Y-627483D01*
G01X1823706Y-626947D02*
X1825281Y-627483D01*
G01X1832105Y-626947D02*
X1833680Y-627483D01*
G01X1832105Y-626947D02*
X1833680Y-627483D01*
G01X1823706Y-629628D02*
X1822656Y-629092D01*
G01X1823706Y-629628D02*
X1822656Y-629092D01*
G01X1832105Y-629628D02*
X1831055Y-629092D01*
G01X1832105Y-629628D02*
X1831055Y-629092D01*
G01X1825281Y-627483D02*
X1826856Y-629092D01*
G01X1825281Y-627483D02*
X1826856Y-629092D01*
G01X1833680Y-627483D02*
X1834730Y-628556D01*
G01X1833680Y-627483D02*
X1834730Y-628556D01*
G01X1818981Y-626947D02*
Y-628556D01*
G01Y-626947D02*
Y-628556D01*
G01D02*
X1820031Y-627483D01*
G01X1818981Y-628556D02*
X1820031Y-627483D01*
G01X1826856Y-629092D02*
X1828430Y-627483D01*
G01X1826856Y-629092D02*
X1828430Y-627483D01*
G01X1829480Y-629092D02*
X1828430Y-629628D01*
G01X1829480Y-629092D02*
X1828430Y-629628D01*
G01X1820031Y-627483D02*
X1821606Y-626947D01*
G01X1820031Y-627483D02*
X1821606Y-626947D01*
G01Y-629092D02*
X1820031Y-629628D01*
G01X1821606Y-629092D02*
X1820031Y-629628D01*
G01X1828430Y-627483D02*
X1830005Y-626947D01*
G01X1828430Y-627483D02*
X1830005Y-626947D01*
G01X1848299Y-609457D02*
G03I-12599J0D01*
G01D02*
G03I-12599J0D01*
G01X1824231Y-630164D02*
X1823706Y-629628D01*
G01X1824231Y-630164D02*
X1823706Y-629628D01*
G01X1832630Y-630164D02*
X1832105Y-629628D01*
G01X1832630Y-630164D02*
X1832105Y-629628D01*
G01X1824756Y-631236D02*
X1824231Y-630164D01*
G01X1824756Y-631236D02*
X1824231Y-630164D01*
G01X1833155Y-631236D02*
X1832630Y-630164D01*
G01X1833155Y-631236D02*
X1832630Y-630164D01*
G01X1834730Y-628556D02*
X1835779Y-631236D01*
G01X1834730Y-628556D02*
X1835779Y-631236D01*
G01X1827905Y-630164D02*
X1827380Y-631236D01*
G01X1827905Y-630164D02*
X1827380Y-631236D01*
G01X1820031Y-629628D02*
X1818981Y-630700D01*
G01X1820031Y-629628D02*
X1818981Y-630700D01*
G01X1828430Y-629628D02*
X1827905Y-630164D01*
G01X1828430Y-629628D02*
X1827905Y-630164D01*
G01X1839398Y-597413D02*
X1871133Y-565677D01*
G01X1848299Y-470874D02*
G03I-12599J0D01*
G01D02*
G03I-12599J0D01*
G01X1842393Y-415756D02*
Y-378258D01*
G01Y-415756D02*
Y-378258D01*
G01X1871133Y-395801D02*
X1851448D01*
G01D02*
X1876448D01*
G01X1835700Y-370488D02*
X1858732D01*
G01X1839658Y-377173D02*
X1881763Y-393867D01*
G01X1824126Y910983D02*
X1823151Y911705D01*
X1822664Y912426D01*
X1822177Y913870D01*
Y916757D01*
X1822664Y918201D01*
X1823151Y918922D01*
X1824126Y919644D01*
X1825100Y918922D01*
X1825587Y918201D01*
X1826074Y916757D01*
Y913870D01*
X1825587Y912426D01*
X1825100Y911705D01*
X1824126Y910983D01*
G01X1828023Y921088D02*
Y919644D01*
X1828745Y918922D01*
X1830189D01*
X1830910Y919644D01*
Y921088D01*
X1830189Y921810D01*
X1828745D01*
X1828023Y921088D01*
G01X1845578Y960903D02*
X1846065Y962346D01*
X1847527Y963068D01*
X1848988Y962346D01*
X1849475Y960903D01*
X1848988Y959459D01*
X1848501Y958737D01*
X1847527Y958015D01*
X1846552Y958737D01*
X1846065Y959459D01*
X1845578Y960903D01*
Y963790D01*
X1846065Y965233D01*
X1846552Y965955D01*
X1847527Y966677D01*
X1848501Y965955D01*
X1848988Y965233D01*
G01X1839731Y966677D02*
Y958015D01*
G01X1831936D02*
X1831449D01*
Y958737D01*
X1831936Y958015D01*
G01X1824141D02*
X1823166Y958737D01*
X1822679Y959459D01*
X1822192Y960903D01*
Y963790D01*
X1822679Y965233D01*
X1823166Y965955D01*
X1824141Y966677D01*
X1825115Y965955D01*
X1825602Y965233D01*
X1826089Y963790D01*
Y960903D01*
X1825602Y959459D01*
X1825115Y958737D01*
X1824141Y958015D01*
G01X1846048Y2167300D02*
Y2155892D01*
G01X1834641Y2167300D02*
Y2155892D01*
G01X1877826Y-651977D02*
X2097175D01*
G01X1881763Y-644103D02*
Y-579536D01*
G01Y-644103D02*
Y-579536D01*
G01Y-644103D02*
Y-579536D01*
G01X1873889Y-651977D02*
G03X1881763Y-644103I0J7874D01*
G01X1873889Y-651977D02*
G03X1881763Y-644103I0J7874D01*
G01X1873889Y-651977D02*
G03X1881763Y-644103I0J7874D01*
G01Y-575599D02*
X2036394D01*
G01X1881763Y-579536D02*
G03X1877826Y-575599I-3937J0D01*
G01X1881763Y-579536D02*
G03X1877826Y-575599I-3937J0D01*
G01X1881763Y-579536D02*
G03X1877826Y-575599I-3937J0D01*
G01X1881284Y-581418D02*
X1935124Y-610724D01*
G01X1877826Y-575599D02*
X1875070D01*
G01X1877826D02*
X1875070D01*
G01X1871133Y-508670D02*
Y-571662D01*
G01Y-508670D02*
Y-571662D01*
G01D02*
G03X1875070Y-575599I3937J0D01*
G01X1871133Y-571662D02*
G03X1875070Y-575599I3937J0D01*
G01X1877826D02*
X1875070D01*
G01X1871133Y-508670D02*
Y-571662D01*
G01D02*
G03X1875070Y-575599I3937J0D01*
G01X1881763Y-504732D02*
X2036836D01*
G01X1881763D02*
X2036394D01*
G01X1881763Y-500795D02*
Y-393867D01*
G01Y-500795D02*
Y-393867D01*
G01X1877826Y-504732D02*
G03X1881763Y-500795I0J3937D01*
G01X1877826Y-504732D02*
G03X1881763Y-500795I0J3937D01*
G01Y-431504D02*
Y-500795D01*
G01X1877826Y-504732D02*
G03X1881763Y-500795I0J3937D01*
G01X1871133Y-504732D02*
Y-391864D01*
G01X1877826Y-504732D02*
X1875070D01*
G01X1877826D02*
X1875070D01*
G01D02*
G03X1871133Y-508670I0J-3937D01*
G01X1875070Y-504732D02*
G03X1871133Y-508670I0J-3937D01*
G01X1877826Y-504732D02*
X1875070D01*
G01D02*
G03X1871133Y-508670I0J-3937D01*
G01X1881763Y-391709D02*
Y-327275D01*
G01Y-391709D02*
Y-366551D01*
G01Y-391709D02*
Y-344731D01*
G01Y-395801D02*
X1998882D01*
G01D02*
X1876448D01*
G01X1881763Y-370488D02*
X1858732D01*
G01D02*
X2006743D01*
G01X1885700Y-431504D02*
X2097175D01*
G01X1885700D02*
X2036836D01*
G01X1944911Y-1120610D02*
Y-1139623D01*
G01X1952294Y-608559D02*
Y-599897D01*
X1948884Y-606394D01*
X1953269D01*
G01X1935124Y-610724D02*
X1938274D01*
G01D02*
X2013917D01*
G01X1944911Y2171102D02*
Y2152090D01*
G01X1985767Y-608559D02*
X1985280D01*
Y-607837D01*
X1985767Y-608559D01*
G01X1977972Y-599897D02*
Y-608559D01*
G01X1957167Y-602785D02*
X1960090Y-608559D01*
G01X1962526Y-604228D02*
X1963248Y-602063D01*
X1964691Y-600620D01*
X1966856Y-599897D01*
X1969022Y-600620D01*
X1970466Y-602063D01*
X1971187Y-604228D01*
X1970466Y-606394D01*
X1969022Y-607837D01*
X1966856Y-608559D01*
X1964691Y-607837D01*
X1963248Y-606394D01*
X1962526Y-604228D01*
G01X1957167Y-608559D02*
X1960090Y-602785D01*
G01X1963248Y-610724D02*
X1970466Y-597732D01*
G01X1985728Y-385696D02*
X1986702Y-384975D01*
X1987677D01*
X1988651Y-385696D01*
X1989138Y-386418D01*
Y-387140D01*
X1988651Y-387862D01*
X1987677Y-388584D01*
X1988651Y-389305D01*
G01X1981409Y-359661D02*
X1978485D01*
X1977998Y-363270D01*
X1978973Y-362548D01*
X1979947D01*
X1980922Y-363270D01*
X1981409Y-363992D01*
X1981896Y-365435D01*
X1981409Y-366879D01*
X1980922Y-367601D01*
X1979947Y-368322D01*
X1978973D01*
X1977998Y-367601D01*
X1977511Y-366879D01*
G01X1989625Y-391471D02*
X1988651Y-392914D01*
X1987677Y-393636D01*
X1986702D01*
X1985728Y-392914D01*
X1985240Y-392192D01*
G01X1979394Y-393636D02*
X1978907D01*
Y-392914D01*
X1979394Y-393636D01*
G01X1965331Y-363270D02*
X1963382Y-364713D01*
X1962408Y-366157D01*
X1961920Y-368322D01*
X1965818D01*
G01X1970203D02*
X1973126Y-362548D01*
G01X1970203D02*
X1973126Y-368322D01*
G01X1971599Y-384975D02*
Y-393636D01*
G01X1983638Y-343616D02*
X1984612Y-342172D01*
X1985587Y-341451D01*
X1986561D01*
X1987536Y-342172D01*
G01X1988510Y-344338D02*
X1987536Y-345781D01*
X1986561Y-346503D01*
X1985587D01*
G01X1978279D02*
X1977791D01*
Y-345781D01*
X1978279Y-346503D01*
G01X1985587D02*
X1984612Y-345781D01*
G01X1985587Y-341451D02*
X1984612Y-340729D01*
X1984125Y-340007D01*
Y-339285D01*
X1984612Y-338564D01*
X1985587Y-337842D01*
X1986561D01*
X1987536Y-338564D01*
X1988023Y-339285D01*
Y-340007D01*
X1987536Y-340729D01*
X1986561Y-341451D01*
G01X1984612Y-345781D02*
X1983638Y-344338D01*
Y-343616D01*
G01X1968535D02*
X1969022Y-342172D01*
X1970483Y-341451D01*
X1971945Y-342172D01*
X1972432Y-343616D01*
X1971945Y-345060D01*
X1971458Y-345781D01*
X1970483Y-346503D01*
X1969509Y-345781D01*
X1969022Y-345060D01*
X1968535Y-343616D01*
Y-340729D01*
X1969022Y-339285D01*
X1969509Y-338564D01*
X1970483Y-337842D01*
X1971458Y-338564D01*
X1971945Y-339285D01*
G01X1962688Y-337842D02*
Y-346503D01*
G01X1961920Y-361105D02*
X1962408Y-360382D01*
X1963382Y-359661D01*
X1964357D01*
X1965331Y-360382D01*
X1965818Y-361105D01*
Y-362548D01*
X1965331Y-363270D01*
G01X1980367Y-323994D02*
X1979392Y-323272D01*
X1978905Y-322551D01*
Y-321829D01*
X1979392Y-321107D01*
X1980367Y-320385D01*
X1981341D01*
X1982315Y-321107D01*
X1982802Y-321829D01*
Y-322551D01*
X1982315Y-323272D01*
X1981341Y-323994D01*
G01X1979392Y-324716D02*
X1980367Y-323994D01*
X1981341D01*
X1982315Y-324716D01*
X1983290Y-326160D01*
G01X1982315Y-328325D02*
X1981341Y-329047D01*
X1980367D01*
G01X1978417Y-326881D02*
Y-326160D01*
X1979392Y-324716D01*
G01X1983290Y-326160D02*
Y-326881D01*
X1982315Y-328325D01*
G01X1980367Y-329047D02*
X1979392Y-328325D01*
X1978417Y-326881D01*
G01X1955519Y-321829D02*
X1956006Y-321107D01*
X1956981Y-320385D01*
X1957955D01*
X1958930Y-321107D01*
X1959417Y-321829D01*
Y-323272D01*
X1958930Y-323994D01*
G01D02*
X1956981Y-325438D01*
X1956006Y-326881D01*
X1955519Y-329047D01*
X1959417D01*
G01X1965263Y-320385D02*
Y-329047D01*
G01X1973058D02*
X1972571D01*
Y-328325D01*
X1973058Y-329047D01*
G01X1993563Y-608559D02*
X1992588Y-607837D01*
X1992101Y-607116D01*
X1991614Y-605672D01*
Y-602785D01*
X1992101Y-601341D01*
X1992588Y-600620D01*
X1993563Y-599897D01*
X1994537Y-600620D01*
X1995024Y-601341D01*
X1995511Y-602785D01*
Y-605672D01*
X1995024Y-607116D01*
X1994537Y-607837D01*
X1993563Y-608559D01*
G01X2001358D02*
X2000383Y-607837D01*
X1999896Y-607116D01*
X1999409Y-605672D01*
Y-602785D01*
X1999896Y-601341D01*
X2000383Y-600620D01*
X2001358Y-599897D01*
X2002332Y-600620D01*
X2002820Y-601341D01*
X2003307Y-602785D01*
Y-605672D01*
X2002820Y-607116D01*
X2002332Y-607837D01*
X2001358Y-608559D01*
G01X1992615Y-365435D02*
X1993589Y-363992D01*
X1994563Y-363270D01*
X1995538D01*
X1996512Y-363992D01*
G01X1997487Y-366157D02*
X1996512Y-367601D01*
X1995538Y-368322D01*
X1994563D01*
G01X1986702Y-388584D02*
X1987677D01*
G01X1987255Y-368322D02*
X1986768D01*
Y-367601D01*
X1987255Y-368322D01*
G01X2004795Y-359661D02*
X2001871D01*
X2001384Y-363270D01*
X2002359Y-362548D01*
X2003333D01*
X2004307Y-363270D01*
X2004795Y-363992D01*
X2005282Y-365435D01*
X2004795Y-366879D01*
X2004307Y-367601D01*
X2003333Y-368322D01*
X2002359D01*
X2001384Y-367601D01*
X2000897Y-366879D01*
G01X1994563Y-368322D02*
X1993589Y-367601D01*
G01X1988651Y-389305D02*
X1989625Y-390749D01*
Y-391471D01*
G01X1993589Y-367601D02*
X1992615Y-366157D01*
Y-365435D01*
G01X1996512Y-363992D02*
X1997487Y-365435D01*
Y-366157D01*
G01X1996933Y-384975D02*
X1994010D01*
X1993523Y-388584D01*
X1994497Y-387862D01*
X1995472D01*
X1996446Y-388584D01*
X1996933Y-389305D01*
X1997420Y-390749D01*
X1996933Y-392192D01*
X1996446Y-392914D01*
X1995472Y-393636D01*
X1994497D01*
X1993523Y-392914D01*
X1993036Y-392192D01*
G01X1995818Y-337842D02*
X1992895D01*
X1992408Y-341451D01*
X1993382Y-340729D01*
X1994357D01*
X1995331Y-341451D01*
X1995818Y-342172D01*
X1996306Y-343616D01*
X1995818Y-345060D01*
X1995331Y-345781D01*
X1994357Y-346503D01*
X1993382D01*
X1992408Y-345781D01*
X1991920Y-345060D01*
G01X1987536Y-342172D02*
X1988510Y-343616D01*
Y-344338D01*
G01X1994563Y-363270D02*
X1993589Y-362548D01*
X1993102Y-361826D01*
Y-361105D01*
X1993589Y-360382D01*
X1994563Y-359661D01*
X1995538D01*
X1996512Y-360382D01*
X1996999Y-361105D01*
Y-361826D01*
X1996512Y-362548D01*
X1995538Y-363270D01*
G01X1990598Y-320385D02*
X1987674D01*
X1987187Y-323994D01*
X1988162Y-323272D01*
X1989136D01*
X1990111Y-323994D01*
X1990598Y-324716D01*
X1991085Y-326160D01*
X1990598Y-327603D01*
X1990111Y-328325D01*
X1989136Y-329047D01*
X1988162D01*
X1987187Y-328325D01*
X1986700Y-327603D01*
G01X2053281Y-1124413D02*
Y-1135820D01*
G01X2032457Y-575599D02*
Y-540166D01*
G01Y-504732D02*
Y-540166D01*
G01X2024518Y-549910D02*
X2025962Y-550397D01*
X2026683Y-551858D01*
X2025962Y-553320D01*
X2024518Y-553807D01*
X2023074Y-553320D01*
X2022353Y-552833D01*
X2021631Y-551858D01*
X2022353Y-550884D01*
X2023074Y-550397D01*
X2024518Y-549910D01*
X2027405D01*
X2028849Y-550397D01*
X2029570Y-550884D01*
X2030292Y-551858D01*
X2029570Y-552833D01*
X2028849Y-553320D01*
G01X2030292Y-544063D02*
Y-544550D01*
X2029570D01*
X2030292Y-544063D01*
G01Y-536268D02*
X2029570Y-537242D01*
X2028849Y-537729D01*
X2027405Y-538217D01*
X2024518D01*
X2023074Y-537729D01*
X2022353Y-537242D01*
X2021631Y-536268D01*
X2022353Y-535294D01*
X2023074Y-534806D01*
X2024518Y-534319D01*
X2027405D01*
X2028849Y-534806D01*
X2029570Y-535294D01*
X2030292Y-536268D01*
G01X2032899Y-504732D02*
Y-468118D01*
G01X2030292Y-528473D02*
X2029570Y-529447D01*
X2028849Y-529934D01*
X2027405Y-530421D01*
X2024518D01*
X2023074Y-529934D01*
X2022353Y-529447D01*
X2021631Y-528473D01*
X2022353Y-527498D01*
X2023074Y-527011D01*
X2024518Y-526524D01*
X2027405D01*
X2028849Y-527011D01*
X2029570Y-527498D01*
X2030292Y-528473D01*
G01X2032899Y-431504D02*
Y-468118D01*
G01X2024959Y-477862D02*
X2026402Y-478349D01*
X2027124Y-479811D01*
X2026402Y-481273D01*
X2024959Y-481760D01*
X2023515Y-481273D01*
X2022794Y-480786D01*
X2022072Y-479811D01*
X2022794Y-478837D01*
X2023515Y-478349D01*
X2024959Y-477862D01*
X2027846D01*
X2029290Y-478349D01*
X2030012Y-478837D01*
X2030733Y-479811D01*
X2030012Y-480786D01*
X2029290Y-481273D01*
G01X2030733Y-472016D02*
Y-472503D01*
X2030012D01*
X2030733Y-472016D01*
G01X2030012Y-462759D02*
X2030733Y-463733D01*
Y-464708D01*
X2030012Y-465682D01*
X2029290Y-466170D01*
G01X2030733Y-456425D02*
X2030012Y-457400D01*
X2029290Y-457887D01*
X2027846Y-458374D01*
X2024959D01*
X2023515Y-457887D01*
X2022794Y-457400D01*
X2022072Y-456425D01*
X2022794Y-455451D01*
X2023515Y-454964D01*
X2024959Y-454477D01*
X2027846D01*
X2029290Y-454964D01*
X2030012Y-455451D01*
X2030733Y-456425D01*
G01X2027846Y-461784D02*
X2028568D01*
X2030012Y-462759D01*
G01X2025681Y-464708D02*
Y-463733D01*
G01X2022794Y-465682D02*
X2022072Y-464708D01*
Y-463733D01*
X2022794Y-462759D01*
X2023515Y-462272D01*
X2024237D01*
X2024959Y-462759D01*
X2025681Y-463733D01*
X2026402Y-462759D01*
X2027846Y-461784D01*
G01X2044528Y311949D02*
X2045250Y314115D01*
X2046693Y315558D01*
X2048858Y316280D01*
X2051024Y315558D01*
X2052467Y314115D01*
X2053189Y311949D01*
X2052467Y309784D01*
X2051024Y308340D01*
X2048858Y307619D01*
X2046693Y308340D01*
X2045250Y309784D01*
X2044528Y311949D01*
G01X2045250Y305453D02*
X2052467Y318445D01*
G01X2095919Y305453D02*
X2035866D01*
G01X2094856Y350144D02*
X2034803D01*
G01X2043465Y356640D02*
X2044186Y358805D01*
X2045630Y360249D01*
X2047795Y360971D01*
X2049960Y360249D01*
X2051404Y358805D01*
X2052126Y356640D01*
X2051404Y354475D01*
X2049960Y353031D01*
X2047795Y352309D01*
X2045630Y353031D01*
X2044186Y354475D01*
X2043465Y356640D01*
G01X2044186Y350144D02*
X2051404Y363136D01*
G01X2094352Y828659D02*
X2034299D01*
G01X2042961Y835155D02*
X2043682Y837320D01*
X2045126Y838764D01*
X2047291Y839486D01*
X2049457Y838764D01*
X2050900Y837320D01*
X2051622Y835155D01*
X2050900Y832990D01*
X2049457Y831546D01*
X2047291Y830824D01*
X2045126Y831546D01*
X2043682Y832990D01*
X2042961Y835155D01*
G01X2043682Y828659D02*
X2050900Y841651D01*
G01X2052388Y872334D02*
X2053363Y873056D01*
X2054337D01*
X2055312Y872334D01*
X2056286Y870891D01*
G01X2055312Y868725D02*
X2054337Y868003D01*
X2053363D01*
G01X2051414Y870169D02*
Y870891D01*
X2052388Y872334D01*
G01X2053363Y868003D02*
X2052388Y868725D01*
X2051414Y870169D01*
G01X2053363Y873056D02*
X2052388Y873778D01*
X2051901Y874499D01*
Y875221D01*
X2052388Y875943D01*
X2053363Y876665D01*
X2054337D01*
X2055312Y875943D01*
X2055799Y875221D01*
Y874499D01*
X2055312Y873778D01*
X2054337Y873056D01*
G01X2089795Y865838D02*
X2029743D01*
G01X2038404Y872334D02*
X2039126Y874499D01*
X2040569Y875943D01*
X2042734Y876665D01*
X2044900Y875943D01*
X2046343Y874499D01*
X2047065Y872334D01*
X2046343Y870169D01*
X2044900Y868725D01*
X2042734Y868003D01*
X2040569Y868725D01*
X2039126Y870169D01*
X2038404Y872334D01*
G01X2039126Y865838D02*
X2046343Y878830D01*
G01X2053281Y2167300D02*
Y2155892D01*
G01X2061836Y-1126314D02*
X2062549Y-1125364D01*
X2063975Y-1124413D01*
X2065401D01*
X2066827Y-1125364D01*
X2067540Y-1126314D01*
Y-1128215D01*
X2066827Y-1129166D01*
G01D02*
X2063975Y-1131067D01*
X2062549Y-1132968D01*
X2061836Y-1135820D01*
X2067540D01*
G01X2083855Y-559280D02*
X2083133Y-558793D01*
X2082411Y-557818D01*
Y-556844D01*
X2083133Y-555869D01*
X2083855Y-555382D01*
X2085298D01*
X2086020Y-555869D01*
G01X2088186Y-551972D02*
X2086742Y-550997D01*
X2086020Y-550023D01*
Y-549048D01*
X2086742Y-548074D01*
G01D02*
X2088186Y-547099D01*
X2088908D01*
G01X2091073Y-533945D02*
X2090351Y-534920D01*
X2089630Y-535407D01*
X2088186Y-535894D01*
X2085298D01*
X2083855Y-535407D01*
X2083133Y-534920D01*
X2082411Y-533945D01*
X2083133Y-532971D01*
X2083855Y-532484D01*
X2085298Y-531996D01*
X2088186D01*
X2089630Y-532484D01*
X2090351Y-532971D01*
X2091073Y-533945D01*
G01X2086020Y-550023D02*
X2085298Y-550997D01*
X2084577Y-551484D01*
X2083855D01*
X2083133Y-550997D01*
X2082411Y-550023D01*
Y-549048D01*
X2083133Y-548074D01*
X2083855Y-547587D01*
X2084577D01*
X2085298Y-548074D01*
X2086020Y-549048D01*
G01Y-555869D02*
X2087464Y-557818D01*
X2088908Y-558793D01*
X2091073Y-559280D01*
Y-555382D01*
G01Y-526150D02*
X2090351Y-527124D01*
X2089630Y-527611D01*
X2088186Y-528099D01*
X2085298D01*
X2083855Y-527611D01*
X2083133Y-527124D01*
X2082411Y-526150D01*
X2083133Y-525175D01*
X2083855Y-524688D01*
X2085298Y-524201D01*
X2088186D01*
X2089630Y-524688D01*
X2090351Y-525175D01*
X2091073Y-526150D01*
G01X2083360Y307619D02*
X2082385Y308340D01*
X2081898Y309062D01*
X2081411Y310506D01*
Y313393D01*
X2081898Y314836D01*
X2082385Y315558D01*
X2083360Y316280D01*
X2084334Y315558D01*
X2084821Y314836D01*
X2085308Y313393D01*
Y310506D01*
X2084821Y309062D01*
X2084334Y308340D01*
X2083360Y307619D01*
G01X2061435D02*
Y316280D01*
X2058025Y309784D01*
X2062410D01*
G01X2075077Y311227D02*
X2074103Y309784D01*
X2073615Y307619D01*
X2077513D01*
G01X2067769D02*
X2067282D01*
Y308340D01*
X2067769Y307619D01*
G01X2073615Y314836D02*
X2074103Y315558D01*
X2075077Y316280D01*
X2076052D01*
X2077026Y315558D01*
X2077513Y314836D01*
Y313393D01*
X2077026Y312671D01*
X2075077Y311227D01*
G01X2082296Y352309D02*
X2081322Y353031D01*
X2080835Y353753D01*
X2080348Y355196D01*
Y358083D01*
X2080835Y359527D01*
X2081322Y360249D01*
X2082296Y360971D01*
X2083271Y360249D01*
X2083758Y359527D01*
X2084245Y358083D01*
Y355196D01*
X2083758Y353753D01*
X2083271Y353031D01*
X2082296Y352309D01*
G01X2058911D02*
X2059398Y355918D01*
X2059885Y358083D01*
G01D02*
X2060859Y360971D01*
X2056962D01*
G01X2066706Y352309D02*
X2066219D01*
Y353031D01*
X2066706Y352309D01*
G01X2076450Y360971D02*
X2073527D01*
X2073039Y357362D01*
X2074014Y358083D01*
X2074989D01*
X2075963Y357362D01*
X2076450Y356640D01*
X2076937Y355196D01*
X2076450Y353753D01*
X2075963Y353031D01*
X2074989Y352309D01*
X2074014D01*
X2073039Y353031D01*
X2072552Y353753D01*
G01X2081793Y830824D02*
X2080818Y831546D01*
X2080331Y832268D01*
X2079844Y833711D01*
Y836598D01*
X2080331Y838042D01*
X2080818Y838764D01*
X2081793Y839486D01*
X2082767Y838764D01*
X2083254Y838042D01*
X2083741Y836598D01*
Y833711D01*
X2083254Y832268D01*
X2082767Y831546D01*
X2081793Y830824D01*
G01X2071561Y833711D02*
X2072536Y835155D01*
X2073510Y835877D01*
X2074484D01*
X2075459Y835155D01*
X2076433Y833711D01*
G01X2060843D02*
Y832990D01*
X2059869Y831546D01*
G01X2076433Y833711D02*
Y832990D01*
X2075459Y831546D01*
G01X2056945Y838764D02*
X2057920Y839486D01*
X2058894D01*
X2059869Y838764D01*
X2060356Y838042D01*
Y837320D01*
X2059869Y836598D01*
X2058894Y835877D01*
X2059869Y835155D01*
X2060843Y833711D01*
G01X2059869Y831546D02*
X2058894Y830824D01*
X2057920D01*
X2056945Y831546D01*
X2056458Y832268D01*
G01X2075459Y831546D02*
X2074484Y830824D01*
X2073510D01*
G01X2072536Y831546D02*
X2071561Y832990D01*
Y833711D01*
G01X2073510Y830824D02*
X2072536Y831546D01*
G01X2073510Y835877D02*
X2072536Y836598D01*
X2072048Y837320D01*
Y838042D01*
X2072536Y838764D01*
X2073510Y839486D01*
X2074484D01*
X2075459Y838764D01*
X2075946Y838042D01*
Y837320D01*
X2075459Y836598D01*
X2074484Y835877D01*
G01X2066202Y830824D02*
X2065715D01*
Y831546D01*
X2066202Y830824D01*
G01X2057920Y835877D02*
X2058894D01*
G01X2056286Y870891D02*
Y870169D01*
X2055312Y868725D01*
G01X2069441Y868003D02*
X2068466Y868725D01*
X2067979Y869447D01*
X2067492Y870891D01*
Y873778D01*
X2067979Y875221D01*
X2068466Y875943D01*
X2069441Y876665D01*
X2070415Y875943D01*
X2070902Y875221D01*
X2071389Y873778D01*
Y870891D01*
X2070902Y869447D01*
X2070415Y868725D01*
X2069441Y868003D01*
G01X2077236D02*
X2076261Y868725D01*
X2075774Y869447D01*
X2075287Y870891D01*
Y873778D01*
X2075774Y875221D01*
X2076261Y875943D01*
X2077236Y876665D01*
X2078210Y875943D01*
X2078698Y875221D01*
X2079185Y873778D01*
Y870891D01*
X2078698Y869447D01*
X2078210Y868725D01*
X2077236Y868003D01*
G01X2061645D02*
X2061158D01*
Y868725D01*
X2061645Y868003D01*
G01X2066827Y2162547D02*
X2063975Y2160645D01*
X2062549Y2158744D01*
X2061836Y2155892D01*
X2067540D01*
G01X2061836Y2165399D02*
X2062549Y2166349D01*
X2063975Y2167300D01*
X2065401D01*
X2066827Y2166349D01*
X2067540Y2165399D01*
Y2163497D01*
X2066827Y2162547D01*
G01X2093238Y-651977D02*
Y-541740D01*
G01Y-431504D02*
Y-541740D01*
G01X2088908Y-547099D02*
X2090351Y-548074D01*
X2091073Y-549048D01*
Y-550023D01*
G01X2090351Y-550997D02*
X2088908Y-551972D01*
X2088186D01*
G01X2091073Y-541740D02*
Y-542227D01*
X2090351D01*
X2091073Y-541740D01*
G01Y-550023D02*
X2090351Y-550997D01*
G01X2195289Y262045D02*
X2099068Y305453D01*
G01D02*
X2095919D01*
G01X2191704Y268354D02*
X2098005Y350144D01*
G01D02*
X2094856D01*
G01X2180355Y822940D02*
X2097501Y828659D01*
G01D02*
X2094352D01*
G01X2173498Y828977D02*
X2092944Y865838D01*
G01D02*
X2089795D01*
G01X2148448Y857858D02*
Y131519D01*
G01Y857858D02*
Y131519D01*
G01D02*
G03X2156322Y123645I7874J0D01*
G01X2148448Y131519D02*
G03X2156322Y123645I7874J0D01*
G01X2164196Y324393D02*
X2148448D01*
G01X2149786Y505220D02*
Y506824D01*
G01X2154975D02*
Y514311D01*
G01X2162621Y505220D02*
X2149786D01*
G01Y506824D02*
X2154975D01*
G01X2153882Y518055D02*
Y522333D01*
G01Y536237D02*
Y537574D01*
G01Y543189D02*
Y544258D01*
G01Y538911D02*
Y539980D01*
G01X2154975Y543724D02*
Y542921D01*
G01Y539445D02*
Y538911D01*
G01Y522333D02*
Y518055D01*
G01X2150059Y530889D02*
X2149786Y529285D01*
G01X2151425Y530622D02*
X2151152Y529285D01*
G01X2153882Y544258D02*
X2154156Y545061D01*
G01X2153882Y539980D02*
X2154156Y540782D01*
G01X2155248Y544258D02*
X2154975Y543724D01*
G01X2155248Y539980D02*
X2154975Y539445D01*
G01X2150878Y532226D02*
X2150059Y530889D01*
G01X2151152Y529285D02*
X2151425Y527948D01*
G01X2149786Y529285D02*
X2150059Y527680D01*
G01X2151971Y531424D02*
X2151425Y530622D01*
G01X2154156Y538108D02*
X2153882Y538911D01*
G01X2154975D02*
X2155248Y538108D01*
G01X2154156Y542387D02*
X2153882Y543189D01*
G01X2154156Y545061D02*
X2154702Y545595D01*
G01X2155521Y544526D02*
X2155248Y544258D01*
G01X2154156Y540782D02*
X2154975Y541585D01*
G01X2155521Y540248D02*
X2155248Y539980D01*
G01X2151698Y533028D02*
X2150878Y532226D01*
G01X2151425Y527948D02*
X2151971Y527146D01*
G01X2150059Y527680D02*
X2150878Y526343D01*
G01X2154975Y542921D02*
X2155248Y542387D01*
G01X2153609Y532493D02*
X2151971Y531424D01*
G01X2150878Y526343D02*
X2151698Y525542D01*
G01X2154702Y537574D02*
X2154156Y538108D01*
G01X2155248D02*
X2155794Y537574D01*
G01X2154975Y541585D02*
X2154156Y542387D01*
G01X2155248D02*
X2155521Y542119D01*
G01X2152790Y533563D02*
X2151698Y533028D01*
G01X2154702Y545595D02*
X2156067Y546130D01*
G01X2153609Y533830D02*
X2152790Y533563D01*
G01X2151971Y527146D02*
X2153609Y526076D01*
G01X2151698Y525542D02*
X2152790Y525006D01*
G01D02*
X2153609Y524739D01*
G01D02*
X2154975Y524472D01*
G01X2153609Y526076D02*
X2155248Y525809D01*
G01X2154975Y518055D02*
X2153882D01*
G01Y522333D02*
X2154975D01*
G01Y524472D02*
X2157432D01*
G01X2155248Y525809D02*
X2157159D01*
G01Y532761D02*
X2155248D01*
G01X2157432Y534098D02*
X2154975D01*
G01X2162621Y536237D02*
X2153882D01*
G01Y537574D02*
X2154702D01*
G01X2154975Y534098D02*
X2153609Y533830D01*
G01X2155248Y532761D02*
X2153609Y532493D01*
G01X2149786Y514311D02*
Y515916D01*
G01X2154975Y514311D02*
X2149786D01*
G01Y515916D02*
X2162621D01*
G01X2153882Y555221D02*
Y556291D01*
G01X2154975Y555756D02*
Y554954D01*
G01X2153882Y556291D02*
X2154156Y557093D01*
G01X2153882Y552013D02*
X2154156Y552815D01*
G01X2155248Y556291D02*
X2154975Y555756D01*
G01X2155248Y552013D02*
X2154975Y551478D01*
G01X2154156Y554419D02*
X2153882Y555221D01*
G01X2154156Y557093D02*
X2154702Y557628D01*
G01X2155521Y556558D02*
X2155248Y556291D01*
G01X2154156Y552815D02*
X2154975Y553617D01*
G01X2155521Y552280D02*
X2155248Y552013D01*
G01X2154975Y554954D02*
X2155248Y554419D01*
G01X2154975Y553617D02*
X2154156Y554419D01*
G01X2155248D02*
X2155521Y554152D01*
G01X2154702Y557628D02*
X2156067Y558163D01*
G01X2153882Y550943D02*
Y552013D01*
G01Y548269D02*
Y549606D01*
G01X2154975Y551478D02*
Y550943D01*
G01X2154156Y550141D02*
X2153882Y550943D01*
G01X2154975D02*
X2155248Y550141D01*
G01X2154702Y549606D02*
X2154156Y550141D01*
G01X2155248D02*
X2155794Y549606D01*
G01X2162621Y548269D02*
X2153882D01*
G01Y549606D02*
X2154702D01*
G01X2248448Y861795D02*
X2152385D01*
G01D02*
X3050582D01*
G01X2152385D02*
G03X2148448Y857858I0J-3937D01*
G01X2152385Y861795D02*
G03X2148448Y857858I0J-3937D01*
G01X2165452Y-1120610D02*
Y-1139623D01*
G01X2156322Y123645D02*
X2345101D01*
G01X2156322D02*
X2345101D01*
G01X2217590Y258645D02*
G03I-14764J0D01*
G01X2164196Y324393D02*
Y861795D01*
G01X2156613Y514311D02*
Y506824D01*
G01X2162621D02*
Y505220D01*
G01X2156613Y506824D02*
X2162621D01*
G01X2157159Y518055D02*
Y522333D01*
G01X2158252D02*
Y518055D01*
G01X2162621Y546130D02*
Y544793D01*
G01Y541852D02*
Y540515D01*
G01Y537574D02*
Y536237D01*
G01X2162348Y527680D02*
X2162621Y529285D01*
G01X2160982Y527948D02*
X2161256Y529285D01*
G01D02*
X2160982Y530622D01*
G01X2162621Y529285D02*
X2162348Y530889D01*
G01X2161528Y526343D02*
X2162348Y527680D01*
G01X2160436Y527146D02*
X2160982Y527948D01*
G01X2160709Y525542D02*
X2161528Y526343D01*
G01X2160982Y530622D02*
X2160436Y531424D01*
G01X2162348Y530889D02*
X2161528Y532226D01*
G01X2158798Y526076D02*
X2160436Y527146D01*
G01X2161528Y532226D02*
X2160709Y533028D01*
G01X2156067Y544793D02*
X2155521Y544526D01*
G01X2156067Y540515D02*
X2155521Y540248D01*
G01X2159617Y525006D02*
X2160709Y525542D01*
G01X2158798Y524739D02*
X2159617Y525006D01*
G01X2160436Y531424D02*
X2158798Y532493D01*
G01X2160709Y533028D02*
X2159617Y533563D01*
G01X2155521Y542119D02*
X2156067Y541852D01*
G01X2159617Y533563D02*
X2158798Y533830D01*
G01Y532493D02*
X2157159Y532761D01*
G01X2158798Y533830D02*
X2157432Y534098D01*
G01X2158252Y518055D02*
X2157159D01*
G01Y522333D02*
X2158252D01*
G01X2155794Y537574D02*
X2162621D01*
G01Y540515D02*
X2156067D01*
G01Y541852D02*
X2162621D01*
G01Y544793D02*
X2156067D01*
G01Y546130D02*
X2162621D01*
G01X2157432Y524472D02*
X2158798Y524739D01*
G01X2157159Y525809D02*
X2158798Y526076D01*
G01X2162621Y515916D02*
Y514311D01*
G01D02*
X2156613D01*
G01X2162621Y558163D02*
Y556826D01*
G01Y553884D02*
Y552547D01*
G01X2156067Y556826D02*
X2155521Y556558D01*
G01X2156067Y552547D02*
X2155521Y552280D01*
G01Y554152D02*
X2156067Y553884D01*
G01X2162621Y552547D02*
X2156067D01*
G01Y553884D02*
X2162621D01*
G01Y556826D02*
X2156067D01*
G01Y558163D02*
X2162621D01*
G01Y549606D02*
Y548269D01*
G01X2155794Y549606D02*
X2162621D01*
G01X2195298Y822425D02*
G03I-7480J0D01*
G01D02*
G03I-7480J0D01*
G01X2203566D02*
G03I-15748J0D01*
G01X2165452Y2171102D02*
Y2152090D01*
G01X2211094Y258645D02*
G03I-8268J0D01*
G01D02*
G03I-8268J0D01*
G01X2215621D02*
G03I-12795J0D01*
G01X2253566Y892897D02*
Y866913D01*
G01Y892897D02*
Y866913D01*
G01X2248448Y861795D02*
G03X2253566Y866913I0J5118D01*
G01X2248448Y861795D02*
G03X2253566Y866913I0J5118D01*
G01X2258684Y894866D02*
X2255534D01*
G01X2258684D02*
X2255534D01*
G01D02*
G03X2253566Y892897I1J-1969D01*
G01X2255534Y894866D02*
G03X2253566Y892897I1J-1969D01*
G01X2284516Y-1129166D02*
X2285942D01*
G01X2287368Y-1130117D02*
X2288794Y-1132018D01*
Y-1132968D01*
G01X2283090Y-1125364D02*
X2284516Y-1124413D01*
X2285942D01*
X2287368Y-1125364D01*
X2288081Y-1126314D01*
Y-1127265D01*
X2287368Y-1128215D01*
X2285942Y-1129166D01*
X2287368Y-1130117D01*
G01X2288794Y-1132968D02*
X2287368Y-1134870D01*
X2285942Y-1135820D01*
X2284516D01*
X2283090Y-1134870D01*
X2282377Y-1133919D01*
G01X2273822Y-1124413D02*
Y-1135820D01*
G01X2281617Y913763D02*
Y904708D01*
G01X2283782D02*
Y913763D01*
G01X2284767D02*
Y904708D01*
G01X2286932D02*
Y913763D01*
G01X2287916D02*
Y904708D01*
G01X2290081D02*
Y913763D01*
G01X2281617Y904708D02*
X2283782D01*
G01X2284767D02*
X2286932D01*
G01X2287916D02*
X2290081D01*
G01Y913763D02*
X2287916D01*
G01X2286932D02*
X2284767D01*
G01X2283782D02*
X2281617D01*
G01X2260652D02*
X2264589Y918881D01*
G01X2260652Y913763D02*
X2264589Y918881D01*
G01X2260849Y903824D02*
X2260785Y903657D01*
G01X2262250Y903824D02*
X2262186Y903657D01*
G01X2261740Y902442D02*
X2261804Y902610D01*
G01X2263141Y902442D02*
X2263204Y902610D01*
G01X2261040Y903782D02*
X2260912Y903531D01*
G01X2261549Y902484D02*
X2261676Y902735D01*
G01X2262441Y903782D02*
X2262313Y903531D01*
G01X2262950Y902484D02*
X2263077Y902735D01*
G01X2264191Y903782D02*
X2264287Y903950D01*
G01X2264191Y902903D02*
X2264287Y903070D01*
G01X2263714Y902484D02*
X2263905Y902777D01*
G01Y902442D02*
X2263714Y902149D01*
G01X2260944Y903950D02*
X2260849Y903824D01*
G01X2262345Y903950D02*
X2262250Y903824D01*
G01X2261644Y902316D02*
X2261740Y902442D01*
G01X2263045Y902316D02*
X2263141Y902442D01*
G01X2264382Y903740D02*
X2264446Y903824D01*
G01Y902945D02*
X2264382Y902861D01*
G01X2264287Y903950D02*
X2264414Y904075D01*
G01X2261135Y903866D02*
X2261040Y903782D01*
G01X2262536Y903866D02*
X2262441Y903782D01*
G01X2261454Y902400D02*
X2261549Y902484D01*
G01X2262854Y902400D02*
X2262950Y902484D01*
G01X2261104Y904075D02*
X2260944Y903950D01*
G01X2262504Y904075D02*
X2262345Y903950D01*
G01X2261485Y902191D02*
X2261644Y902316D01*
G01X2262886Y902191D02*
X2263045Y902316D01*
G01X2264287Y903070D02*
X2264350Y903112D01*
G01X2260912Y903531D02*
X2260881Y903280D01*
G01X2261676Y902735D02*
X2261708Y902987D01*
G01X2262313Y903531D02*
X2262281Y903280D01*
G01X2263077Y902735D02*
X2263109Y902987D01*
G01X2260753Y903531D02*
X2260721Y903322D01*
G01X2261835Y902735D02*
X2261867Y902945D01*
G01X2262154Y903531D02*
X2262122Y903322D01*
G01X2263236Y902735D02*
X2263268Y902945D01*
G01X2260785Y903657D02*
X2260753Y903531D01*
G01X2261804Y902610D02*
X2261835Y902735D01*
G01X2262186Y903657D02*
X2262154Y903531D01*
G01X2263204Y902610D02*
X2263236Y902735D01*
G01X2264159Y903657D02*
X2264191Y903782D01*
G01X2264350Y903615D02*
X2264382Y903740D01*
G01X2264159Y902777D02*
X2264191Y902903D01*
G01X2264382Y902861D02*
X2264350Y902735D01*
G01X2264446Y903824D02*
X2264541Y903866D01*
G01Y902987D02*
X2264446Y902945D01*
G01X2260652Y913763D02*
Y896834D01*
G01Y913763D02*
Y896834D01*
G01X2260721Y903322D02*
Y902945D01*
G01X2260881Y903280D02*
Y902987D01*
G01X2261708D02*
Y903280D01*
G01X2261867Y902945D02*
Y903322D01*
G01X2262122D02*
Y902945D01*
G01X2262281Y903280D02*
Y902987D01*
G01X2262719Y913763D02*
Y904708D01*
G01X2263109Y902987D02*
Y903280D01*
G01X2263268Y902945D02*
Y903322D01*
G01X2263523Y902149D02*
Y904118D01*
G01X2263714D02*
Y902484D01*
G01X2263905Y902777D02*
Y902442D01*
G01X2264159Y902610D02*
Y902777D01*
G01Y903447D02*
Y903657D01*
G01X2264350Y902735D02*
Y902651D01*
G01Y903489D02*
Y903615D01*
G01X2264885Y904708D02*
Y913763D01*
G01X2265146Y903866D02*
Y903238D01*
G01Y902400D02*
Y902987D01*
G01X2265337Y904118D02*
Y902149D01*
G01X2265869Y913763D02*
Y904708D01*
G01X2268034D02*
Y913763D01*
G01X2269019D02*
Y904708D01*
G01X2271184D02*
Y913763D01*
G01X2272168D02*
Y904708D01*
G01X2274333D02*
Y913763D01*
G01X2275318D02*
Y904708D01*
G01X2277483D02*
Y913763D01*
G01X2278467D02*
Y904708D01*
G01X2280633D02*
Y913763D01*
G01X2260881Y902987D02*
X2260912Y902735D01*
G01X2261708Y903280D02*
X2261676Y903531D01*
G01X2262281Y902987D02*
X2262313Y902735D01*
G01X2263109Y903280D02*
X2263077Y903531D01*
G01X2260721Y902945D02*
X2260753Y902735D01*
G01X2261867Y903322D02*
X2261835Y903531D01*
G01X2262122Y902945D02*
X2262154Y902735D01*
G01X2263268Y903322D02*
X2263236Y903531D01*
G01X2260753Y902735D02*
X2260785Y902610D01*
G01X2261835Y903531D02*
X2261804Y903657D01*
G01X2262154Y902735D02*
X2262186Y902610D01*
G01X2263236Y903531D02*
X2263204Y903657D01*
G01X2264191Y902484D02*
X2264159Y902610D01*
G01X2264350Y902651D02*
X2264382Y902526D01*
G01X2264191Y903322D02*
X2264159Y903447D01*
G01X2264382Y903364D02*
X2264350Y903489D01*
G01X2260785Y902610D02*
X2260849Y902442D01*
G01X2262186Y902610D02*
X2262250Y902442D01*
G01X2261804Y903657D02*
X2261740Y903824D01*
G01X2263204Y903657D02*
X2263141Y903824D01*
G01X2260912Y902735D02*
X2261040Y902484D01*
G01X2261676Y903531D02*
X2261549Y903782D01*
G01X2262313Y902735D02*
X2262441Y902484D01*
G01X2263077Y903531D02*
X2262950Y903782D01*
G01X2264287Y902316D02*
X2264191Y902484D01*
G01X2264287Y903154D02*
X2264191Y903322D01*
G01X2260849Y902442D02*
X2260944Y902316D01*
G01X2262250Y902442D02*
X2262345Y902316D01*
G01X2261740Y903824D02*
X2261644Y903950D01*
G01X2263141Y903824D02*
X2263045Y903950D01*
G01X2264382Y902526D02*
X2264446Y902442D01*
G01Y903280D02*
X2264382Y903364D01*
G01X2264414Y902191D02*
X2264287Y902316D01*
G01X2260944D02*
X2261104Y902191D01*
G01X2262345Y902316D02*
X2262504Y902191D01*
G01X2261644Y903950D02*
X2261485Y904075D01*
G01X2263045Y903950D02*
X2262886Y904075D01*
G01X2261040Y902484D02*
X2261135Y902400D01*
G01X2262441Y902484D02*
X2262536Y902400D01*
G01X2261549Y903782D02*
X2261454Y903866D01*
G01X2262950Y903782D02*
X2262854Y903866D01*
G01X2264350Y903112D02*
X2264287Y903154D01*
G01X2264446Y902442D02*
X2264541Y902400D01*
G01Y903238D02*
X2264446Y903280D01*
G01X2261135Y902400D02*
X2261294Y902358D01*
G01X2262536Y902400D02*
X2262695Y902358D01*
G01X2264573Y902149D02*
X2264414Y902191D01*
G01X2261454Y903866D02*
X2261294Y903908D01*
G01X2262854Y903866D02*
X2262695Y903908D01*
G01X2261104Y902191D02*
X2261294Y902149D01*
G01X2262504Y902191D02*
X2262695Y902149D01*
G01X2261485Y904075D02*
X2261294Y904118D01*
G01X2262886Y904075D02*
X2262695Y904118D01*
G01X2265337Y902149D02*
X2264573D01*
G01X2263714D02*
X2263523D01*
G01X2264541Y902400D02*
X2265146D01*
G01Y902987D02*
X2264541D01*
G01X2265146Y903238D02*
X2264541D01*
G01Y903866D02*
X2265146D01*
G01X2263523Y904118D02*
X2263714D01*
G01X2264573D02*
X2265337D01*
G01X2262719Y904708D02*
X2264885D01*
G01X2265869D02*
X2268034D01*
G01X2272168D02*
X2274333D01*
G01X2269019D02*
X2271184D01*
G01X2275318D02*
X2277483D01*
G01X2278467D02*
X2280633D01*
G01Y913763D02*
X2278467D01*
G01X2277483D02*
X2275318D01*
G01X2274333D02*
X2272168D01*
G01X2271184D02*
X2269019D01*
G01X2268034D02*
X2265869D01*
G01X2264885D02*
X2262719D01*
G01X2260652D02*
X2440574D01*
G01X2262695Y902149D02*
X2262886Y902191D01*
G01X2261294Y902149D02*
X2261485Y902191D01*
G01X2262695Y904118D02*
X2262504Y904075D01*
G01X2261294Y904118D02*
X2261104Y904075D01*
G01X2262695Y902358D02*
X2262854Y902400D01*
G01X2261294Y902358D02*
X2261454Y902400D01*
G01X2264414Y904075D02*
X2264573Y904118D01*
G01X2262695Y903908D02*
X2262536Y903866D01*
G01X2261294Y903908D02*
X2261135Y903866D01*
G01X2258684Y894866D02*
G03X2260652Y896834I0J1968D01*
G01X2258684Y894866D02*
G03X2260652Y896834I0J1968D01*
G01X2436637Y918881D02*
X2264589D01*
G01D02*
X2436637D01*
G01X2283090Y2166349D02*
X2284516Y2167300D01*
X2285942D01*
X2287368Y2166349D01*
X2288081Y2165399D01*
Y2164448D01*
X2287368Y2163497D01*
X2285942Y2162547D01*
X2287368Y2161596D01*
G01X2288794Y2158744D02*
X2287368Y2156843D01*
X2285942Y2155892D01*
X2284516D01*
X2283090Y2156843D01*
X2282377Y2157793D01*
G01X2287368Y2161596D02*
X2288794Y2159695D01*
Y2158744D01*
G01X2284516Y2162547D02*
X2285942D01*
G01X2273822Y2167300D02*
Y2155892D01*
G01X2315278Y904708D02*
Y913763D01*
G01X2316263D02*
Y904708D01*
G01X2318428D02*
Y913763D01*
G01X2319412D02*
Y904708D01*
G01X2321578D02*
Y913763D01*
G01X2322562D02*
Y904708D01*
G01X2319412D02*
X2321578D01*
G01X2316263D02*
X2318428D01*
G01X2322562D02*
X2324727D01*
G01Y913763D02*
X2322562D01*
G01X2321578D02*
X2319412D01*
G01X2318428D02*
X2316263D01*
G01X2291066D02*
Y904708D01*
G01X2293231D02*
Y913763D01*
G01X2294215D02*
Y904708D01*
G01X2296381D02*
Y913763D01*
G01X2297365D02*
Y904708D01*
G01X2299530D02*
Y913763D01*
G01X2300515D02*
Y904708D01*
G01X2302680D02*
Y913763D01*
G01X2303664D02*
Y904708D01*
G01X2305830D02*
Y913763D01*
G01X2306814D02*
Y904708D01*
G01X2308979D02*
Y913763D01*
G01X2309963D02*
Y904708D01*
G01X2312129D02*
Y913763D01*
G01X2313113D02*
Y904708D01*
G01X2291066D02*
X2293231D01*
G01X2294215D02*
X2296381D01*
G01X2300515D02*
X2302680D01*
G01X2297365D02*
X2299530D01*
G01X2303664D02*
X2305830D01*
G01X2309963D02*
X2312129D01*
G01X2306814D02*
X2308979D01*
G01X2313113D02*
X2315278D01*
G01Y913763D02*
X2313113D01*
G01X2312129D02*
X2309963D01*
G01X2308979D02*
X2306814D01*
G01X2305830D02*
X2303664D01*
G01X2302680D02*
X2300515D01*
G01X2299530D02*
X2297365D01*
G01X2296381D02*
X2294215D01*
G01X2293231D02*
X2291066D01*
G01X2352975Y115771D02*
Y29118D01*
G01Y115771D02*
Y29118D01*
G01D02*
G03X2360849Y21243I7874J-1D01*
G01X2352975Y29118D02*
G03X2360849Y21243I7874J-1D01*
G01X2352975Y115771D02*
G03X2345101Y123645I-7874J0D01*
G01X2352975Y115771D02*
G03X2345101Y123645I-7874J0D01*
G01X2349924Y904708D02*
Y913763D01*
G01X2350908D02*
Y904708D01*
G01X2353074D02*
Y913763D01*
G01X2354058D02*
Y904708D01*
G01X2356223D02*
Y913763D01*
G01X2357207D02*
Y904708D01*
G01X2350908D02*
X2353074D01*
G01X2357207D02*
X2359373D01*
G01X2354058D02*
X2356223D01*
G01X2359373Y913763D02*
X2357207D01*
G01X2356223D02*
X2354058D01*
G01X2353074D02*
X2350908D01*
G01X2324727Y904708D02*
Y913763D01*
G01X2325711D02*
Y904708D01*
G01X2327877D02*
Y913763D01*
G01X2328861D02*
Y904708D01*
G01X2331026D02*
Y913763D01*
G01X2332011D02*
Y904708D01*
G01X2334176D02*
Y913763D01*
G01X2335160D02*
Y904708D01*
G01X2337326D02*
Y913763D01*
G01X2338310D02*
Y904708D01*
G01X2340475D02*
Y913763D01*
G01X2341459D02*
Y904708D01*
G01X2343625D02*
Y913763D01*
G01X2344609D02*
Y904708D01*
G01X2346774D02*
Y913763D01*
G01X2347759D02*
Y904708D01*
G01X2328861D02*
X2331026D01*
G01X2325711D02*
X2327877D01*
G01X2332011D02*
X2334176D01*
G01X2338310D02*
X2340475D01*
G01X2335160D02*
X2337326D01*
G01X2341459D02*
X2343625D01*
G01X2347759D02*
X2349924D01*
G01X2344609D02*
X2346774D01*
G01X2349924Y913763D02*
X2347759D01*
G01X2346774D02*
X2344609D01*
G01X2343625D02*
X2341459D01*
G01X2340475D02*
X2338310D01*
G01X2337326D02*
X2335160D01*
G01X2334176D02*
X2332011D01*
G01X2331026D02*
X2328861D01*
G01X2327877D02*
X2325711D01*
G01X2385993Y-1120610D02*
Y-1139623D01*
G01X2360849Y21243D02*
X2619461D01*
G01X2360849D02*
X2619461D01*
G01X2387139Y881813D02*
X2386400Y881059D01*
G01D02*
X2385908Y880054D01*
G01X2387877Y880808D02*
X2386893Y879300D01*
G01X2388615Y881310D02*
X2387877Y880808D01*
G01X2391076Y872515D02*
X2391814Y873018D01*
G01X2388369Y882567D02*
X2387139Y881813D01*
G01X2391322Y871258D02*
X2392552Y872012D01*
G01X2386893Y879300D02*
X2386646Y877792D01*
G01X2385662Y879300D02*
X2385416Y878043D01*
G01X2385908Y880054D02*
X2385662Y879300D01*
G01X2383448Y879049D02*
Y878043D01*
G01Y876033D02*
Y875028D01*
G01X2385416Y878043D02*
Y875782D01*
G01X2386646Y877792D02*
Y876033D01*
G01X2385416Y875782D02*
X2385662Y874525D01*
G01X2386646Y876033D02*
X2386893Y874525D01*
G01X2385662D02*
X2385908Y873771D01*
G01D02*
X2386400Y872766D01*
G01X2386893Y874525D02*
X2387877Y873018D01*
G01X2386400Y872766D02*
X2387139Y872012D01*
G01X2387877Y873018D02*
X2388615Y872515D01*
G01X2391814Y880808D02*
X2391076Y881310D01*
G01X2387139Y872012D02*
X2388369Y871258D01*
G01X2392552Y881813D02*
X2391322Y882567D01*
G01X2388369Y871258D02*
X2389845Y871007D01*
G01X2391322Y882567D02*
X2389845Y882818D01*
G01X2388615Y872515D02*
X2389845Y872264D01*
G01X2391076Y881310D02*
X2389845Y881562D01*
G01Y872264D02*
X2391076Y872515D01*
G01X2389845Y881562D02*
X2388615Y881310D01*
G01X2389845Y871007D02*
X2391322Y871258D01*
G01X2389845Y882818D02*
X2388369Y882567D01*
G01X2367700Y871007D02*
Y882818D01*
G01X2369176D02*
Y878043D01*
G01Y876536D02*
Y871007D01*
G01X2376066D02*
Y876536D01*
G01Y878043D02*
Y882818D01*
G01X2377542D02*
Y871007D01*
G01X2379511Y875028D02*
Y876033D01*
G01Y878043D02*
Y879049D01*
G01X2377542Y871007D02*
X2376066D01*
G01X2369176D02*
X2367700D01*
G01X2383448Y875028D02*
X2379511D01*
G01Y876033D02*
X2383448D01*
G01X2376066Y876536D02*
X2369176D01*
G01X2383448Y878043D02*
X2379511D01*
G01X2369176D02*
X2376066D01*
G01X2379511Y879049D02*
X2383448D01*
G01X2367700Y882818D02*
X2369176D01*
G01X2376066D02*
X2377542D01*
G01X2382404Y913763D02*
Y904708D01*
G01X2384570D02*
Y913763D01*
G01X2385554D02*
Y904708D01*
G01X2387719D02*
Y913763D01*
G01X2388704D02*
Y904708D01*
G01X2390869D02*
Y913763D01*
G01X2385554Y904708D02*
X2387719D01*
G01X2382404D02*
X2384570D01*
G01X2388704D02*
X2390869D01*
G01Y913763D02*
X2388704D01*
G01X2387719D02*
X2385554D01*
G01X2384570D02*
X2382404D01*
G01X2359373Y904708D02*
Y913763D01*
G01X2360357D02*
Y904708D01*
G01X2362522D02*
Y913763D01*
G01X2363507D02*
Y904708D01*
G01X2365672D02*
Y913763D01*
G01X2366656D02*
Y904708D01*
G01X2368822D02*
Y913763D01*
G01X2369806D02*
Y904708D01*
G01X2371971D02*
Y913763D01*
G01X2372956D02*
Y904708D01*
G01X2375121D02*
Y913763D01*
G01X2376105D02*
Y904708D01*
G01X2378270D02*
Y913763D01*
G01X2379255D02*
Y904708D01*
G01X2381420D02*
Y913763D01*
G01X2360357Y904708D02*
X2362522D01*
G01X2366656D02*
X2368822D01*
G01X2363507D02*
X2365672D01*
G01X2369806D02*
X2371971D01*
G01X2376105D02*
X2378270D01*
G01X2372956D02*
X2375121D01*
G01X2379255D02*
X2381420D01*
G01Y913763D02*
X2379255D01*
G01X2378270D02*
X2376105D01*
G01X2375121D02*
X2372956D01*
G01X2371971D02*
X2369806D01*
G01X2368822D02*
X2366656D01*
G01X2365672D02*
X2363507D01*
G01X2362522D02*
X2360357D01*
G01X2385993Y2171102D02*
Y2152090D01*
G01X2416420Y877038D02*
Y871007D01*
G01X2415928Y878295D02*
X2416420Y877038D01*
G01X2393290Y872766D02*
X2393782Y873771D01*
G01X2401656Y877541D02*
X2401410Y877038D01*
G01X2412729Y877541D02*
X2412483Y877038D01*
G01X2391814Y873018D02*
X2392798Y874525D01*
G01X2397473Y878295D02*
X2397965Y878797D01*
G01Y877792D02*
X2397473Y877290D01*
G01X2392552Y872012D02*
X2393290Y872766D01*
G01X2401164Y878043D02*
X2401902Y878797D01*
G01Y877792D02*
X2401656Y877541D01*
G01X2408546Y878295D02*
X2409038Y878797D01*
G01Y877792D02*
X2408546Y877290D01*
G01X2412237Y878043D02*
X2412975Y878797D01*
G01Y877792D02*
X2412729Y877541D01*
G01X2402394Y878043D02*
X2401902Y877792D01*
G01X2413467Y878043D02*
X2412975Y877792D01*
G01X2392798Y874525D02*
X2393044Y876033D01*
G01X2394028Y874525D02*
X2394274Y875782D01*
G01X2393782Y873771D02*
X2394028Y874525D01*
G01X2397965Y878797D02*
X2398704Y879049D01*
G01Y878043D02*
X2397965Y877792D01*
G01X2401902Y878797D02*
X2402641Y879049D01*
G01X2409038Y878797D02*
X2409776Y879049D01*
G01Y878043D02*
X2409038Y877792D01*
G01X2412975Y878797D02*
X2413713Y879049D01*
G01X2393044Y876033D02*
Y877792D01*
G01X2394274Y875782D02*
Y878043D01*
G01X2396243Y871007D02*
Y879049D01*
G01X2397473D02*
Y878295D01*
G01Y877290D02*
Y871007D01*
G01X2400180D02*
Y877038D01*
G01X2401410D02*
Y871007D01*
G01X2404117D02*
Y877038D01*
G01X2405347D02*
Y871007D01*
G01X2407316D02*
Y879049D01*
G01X2408546D02*
Y878295D01*
G01Y877290D02*
Y871007D01*
G01X2411253D02*
Y877038D01*
G01X2412483D02*
Y871007D01*
G01X2415190D02*
Y877038D01*
G01X2394274Y878043D02*
X2394028Y879300D01*
G01X2393044Y877792D02*
X2392798Y879300D01*
G01X2394028D02*
X2393782Y880054D01*
G01X2404855Y878295D02*
X2405347Y877038D01*
G01X2393782Y880054D02*
X2393290Y881059D01*
G01X2400180Y877038D02*
X2399934Y877541D01*
G01X2404117Y877038D02*
X2403871Y877541D01*
G01X2411253Y877038D02*
X2411007Y877541D01*
G01X2415190Y877038D02*
X2414944Y877541D01*
G01X2392798Y879300D02*
X2391814Y880808D01*
G01X2393290Y881059D02*
X2392552Y881813D01*
G01X2399934Y877541D02*
X2399688Y877792D01*
G01X2400426Y878797D02*
X2401164Y878043D01*
G01X2403871Y877541D02*
X2403625Y877792D01*
G01X2404363Y878797D02*
X2404855Y878295D01*
G01X2411007Y877541D02*
X2410761Y877792D01*
G01X2411499Y878797D02*
X2412237Y878043D01*
G01X2414944Y877541D02*
X2414698Y877792D01*
G01X2415436Y878797D02*
X2415928Y878295D01*
G01X2399688Y877792D02*
X2399196Y878043D01*
G01X2403625Y877792D02*
X2403133Y878043D01*
G01X2410761Y877792D02*
X2410269Y878043D01*
G01X2414698Y877792D02*
X2414206Y878043D01*
G01X2399688Y879049D02*
X2400426Y878797D01*
G01X2403625Y879049D02*
X2404363Y878797D01*
G01X2410761Y879049D02*
X2411499Y878797D01*
G01X2414698Y879049D02*
X2415436Y878797D01*
G01X2416420Y871007D02*
X2415190D01*
G01X2412483D02*
X2411253D01*
G01X2408546D02*
X2407316D01*
G01X2405347D02*
X2404117D01*
G01X2401410D02*
X2400180D01*
G01X2397473D02*
X2396243D01*
G01X2414206Y878043D02*
X2413467D01*
G01X2410269D02*
X2409776D01*
G01X2403133D02*
X2402394D01*
G01X2399196D02*
X2398704D01*
G01X2396243Y879049D02*
X2397473D01*
G01X2398704D02*
X2399688D01*
G01X2402641D02*
X2403625D01*
G01X2407316D02*
X2408546D01*
G01X2409776D02*
X2410761D01*
G01X2413713D02*
X2414698D01*
G01X2416066Y904708D02*
Y913763D01*
G01X2417050D02*
Y904708D01*
G01X2419215D02*
Y913763D01*
G01X2420200D02*
Y904708D01*
G01X2422365D02*
Y913763D01*
G01X2423349D02*
Y904708D01*
G01X2417050D02*
X2419215D01*
G01X2423349D02*
X2425515D01*
G01X2420200D02*
X2422365D01*
G01X2425515Y913763D02*
X2423349D01*
G01X2422365D02*
X2420200D01*
G01X2419215D02*
X2417050D01*
G01X2391853D02*
Y904708D01*
G01X2394019D02*
Y913763D01*
G01X2395003D02*
Y904708D01*
G01X2397168D02*
Y913763D01*
G01X2398152D02*
Y904708D01*
G01X2400318D02*
Y913763D01*
G01X2401302D02*
Y904708D01*
G01X2403467D02*
Y913763D01*
G01X2404452D02*
Y904708D01*
G01X2406617D02*
Y913763D01*
G01X2407601D02*
Y904708D01*
G01X2409767D02*
Y913763D01*
G01X2410751D02*
Y904708D01*
G01X2412916D02*
Y913763D01*
G01X2413900D02*
Y904708D01*
G01X2395003D02*
X2397168D01*
G01X2391853D02*
X2394019D01*
G01X2398152D02*
X2400318D01*
G01X2404452D02*
X2406617D01*
G01X2401302D02*
X2403467D01*
G01X2407601D02*
X2409767D01*
G01X2413900D02*
X2416066D01*
G01X2410751D02*
X2412916D01*
G01X2416066Y913763D02*
X2413900D01*
G01X2412916D02*
X2410751D01*
G01X2409767D02*
X2407601D01*
G01X2406617D02*
X2404452D01*
G01X2403467D02*
X2401302D01*
G01X2400318D02*
X2398152D01*
G01X2397168D02*
X2395003D01*
G01X2394019D02*
X2391853D01*
G01X2457306Y77149D02*
G03I-15748J0D01*
G01X2447857D02*
G03I-6299J0D01*
G01D02*
G03I-6299J0D01*
G01X2451696Y904708D02*
Y913763D01*
G01X2453861D02*
Y904708D01*
G01X2454845D02*
Y913763D01*
G01X2457011D02*
Y904708D01*
G01X2457995D02*
Y913763D01*
G01X2460160Y904708D02*
X2457995D01*
G01X2453861D02*
X2451696D01*
G01X2457011D02*
X2454845D01*
G01X2451696Y913763D02*
X2453861D01*
G01X2454845D02*
X2457011D01*
G01X2457995D02*
X2460160D01*
G01X2449235D02*
X2453172Y918881D01*
G01X2449235Y913763D02*
X2453172Y918881D01*
G01X2425515Y904708D02*
Y913763D01*
G01X2426499D02*
Y904708D01*
G01X2428664D02*
Y913763D01*
G01X2429648D02*
Y904708D01*
G01X2431814D02*
Y913763D01*
G01X2432798D02*
Y904708D01*
G01X2434963D02*
Y913763D01*
G01X2435948D02*
Y904708D01*
G01X2438113D02*
Y913763D01*
G01X2440574D02*
Y897228D01*
G01Y913763D02*
Y897228D01*
G01X2449235Y913763D02*
Y897228D01*
G01Y913763D02*
Y897228D01*
G01X2436637Y918881D02*
X2440574Y913763D01*
G01X2436637Y918881D02*
X2440574Y913763D01*
G01X2426499Y904708D02*
X2428664D01*
G01X2429648D02*
X2431814D01*
G01X2435948D02*
X2438113D01*
G01X2432798D02*
X2434963D01*
G01X2438113Y913763D02*
X2435948D01*
G01X2434963D02*
X2432798D01*
G01X2431814D02*
X2429648D01*
G01X2428664D02*
X2426499D01*
G01X2449235D02*
X2591361D01*
G01X2440574Y897228D02*
G03X2449235I4330J0D01*
G01X2440574D02*
G03X2449235I4330J0D01*
G01X2587424Y918881D02*
X2453172D01*
G01D02*
X2587424D01*
G01X2500613Y42503D02*
G03I-15748J0D01*
G01X2491164D02*
G03I-6299J0D01*
G01D02*
G03I-6299J0D01*
G01X2500613Y111795D02*
G03I-15748J0D01*
G01X2491164D02*
G03I-6299J0D01*
G01D02*
G03I-6299J0D01*
G01X2483192Y904708D02*
Y913763D01*
G01X2485357D02*
Y904708D01*
G01X2486341D02*
Y913763D01*
G01X2488507D02*
Y904708D01*
G01X2489491D02*
Y913763D01*
G01X2491656D02*
Y904708D01*
G01X2492641D02*
Y913763D01*
G01X2491656Y904708D02*
X2489491D01*
G01X2494806D02*
X2492641D01*
G01X2488507D02*
X2486341D01*
G01X2485357D02*
X2483192D01*
G01Y913763D02*
X2485357D01*
G01X2486341D02*
X2488507D01*
G01X2489491D02*
X2491656D01*
G01X2492641D02*
X2494806D01*
G01X2460160D02*
Y904708D01*
G01X2461144D02*
Y913763D01*
G01X2463310D02*
Y904708D01*
G01X2464294D02*
Y913763D01*
G01X2466459D02*
Y904708D01*
G01X2467444D02*
Y913763D01*
G01X2469609D02*
Y904708D01*
G01X2470593D02*
Y913763D01*
G01X2472759D02*
Y904708D01*
G01X2473743D02*
Y913763D01*
G01X2475908D02*
Y904708D01*
G01X2476893D02*
Y913763D01*
G01X2479058D02*
Y904708D01*
G01X2480042D02*
Y913763D01*
G01X2482207D02*
Y904708D01*
G01D02*
X2480042D01*
G01X2479058D02*
X2476893D01*
G01X2472759D02*
X2470593D01*
G01X2475908D02*
X2473743D01*
G01X2469609D02*
X2467444D01*
G01X2463310D02*
X2461144D01*
G01X2466459D02*
X2464294D01*
G01X2461144Y913763D02*
X2463310D01*
G01X2464294D02*
X2466459D01*
G01X2467444D02*
X2469609D01*
G01X2470593D02*
X2472759D01*
G01X2473743D02*
X2475908D01*
G01X2476893D02*
X2479058D01*
G01X2480042D02*
X2482207D01*
G01X2494363Y-1124413D02*
Y-1135820D01*
G01X2507909D02*
Y-1124413D01*
X2502918Y-1132968D01*
X2509335D01*
G01X2502581Y92897D02*
Y61401D01*
G01X2504550Y59432D02*
X2514393D01*
G01X2516361Y61401D02*
Y92897D01*
G01X2514393Y59432D02*
G03X2516361Y61401I-1J1969D01*
G01X2502581D02*
G03X2504550Y59432I1969J0D01*
G01X2514393Y94866D02*
X2504550D01*
G01X2516361Y92897D02*
G03X2514393Y94866I-1969J0D01*
G01X2504550D02*
G03X2502581Y92897I0J-1969D01*
G01X2516853Y913763D02*
Y904708D01*
G01X2517837D02*
Y913763D01*
G01X2520003D02*
Y904708D01*
G01X2520987D02*
Y913763D01*
G01X2523152D02*
Y904708D01*
G01X2524137D02*
Y913763D01*
G01X2526302D02*
Y904708D01*
G01D02*
X2524137D01*
G01X2520003D02*
X2517837D01*
G01X2523152D02*
X2520987D01*
G01X2517837Y913763D02*
X2520003D01*
G01X2520987D02*
X2523152D01*
G01X2524137D02*
X2526302D01*
G01X2494806D02*
Y904708D01*
G01X2495790D02*
Y913763D01*
G01X2497956D02*
Y904708D01*
G01X2498940D02*
Y913763D01*
G01X2501105D02*
Y904708D01*
G01X2502089D02*
Y913763D01*
G01X2504255D02*
Y904708D01*
G01X2505239D02*
Y913763D01*
G01X2507404D02*
Y904708D01*
G01X2508389D02*
Y913763D01*
G01X2510554D02*
Y904708D01*
G01X2511538D02*
Y913763D01*
G01X2513704D02*
Y904708D01*
G01X2514688D02*
Y913763D01*
G01X2516853Y904708D02*
X2514688D01*
G01X2510554D02*
X2508389D01*
G01X2513704D02*
X2511538D01*
G01X2507404D02*
X2505239D01*
G01X2501105D02*
X2498940D01*
G01X2504255D02*
X2502089D01*
G01X2497956D02*
X2495790D01*
G01Y913763D02*
X2497956D01*
G01X2498940D02*
X2501105D01*
G01X2502089D02*
X2504255D01*
G01X2505239D02*
X2507404D01*
G01X2508389D02*
X2510554D01*
G01X2511538D02*
X2513704D01*
G01X2514688D02*
X2516853D01*
G01X2494363Y2167300D02*
Y2155892D01*
G01X2507909D02*
Y2167300D01*
X2502918Y2158744D01*
X2509335D01*
G01X2551499Y913763D02*
Y904708D01*
G01X2552483D02*
Y913763D01*
G01X2554648D02*
Y904708D01*
G01X2555633D02*
Y913763D01*
G01X2557798D02*
Y904708D01*
G01X2558782D02*
Y913763D01*
G01X2557798Y904708D02*
X2555633D01*
G01X2560948D02*
X2558782D01*
G01X2554648D02*
X2552483D01*
G01Y913763D02*
X2554648D01*
G01X2555633D02*
X2557798D01*
G01X2558782D02*
X2560948D01*
G01X2527286Y904708D02*
Y913763D01*
G01X2529452D02*
Y904708D01*
G01X2530436D02*
Y913763D01*
G01X2532601D02*
Y904708D01*
G01X2533585D02*
Y913763D01*
G01X2535751D02*
Y904708D01*
G01X2536735D02*
Y913763D01*
G01X2538900D02*
Y904708D01*
G01X2539885D02*
Y913763D01*
G01X2542050D02*
Y904708D01*
G01X2543034D02*
Y913763D01*
G01X2545200D02*
Y904708D01*
G01X2546184D02*
Y913763D01*
G01X2548349D02*
Y904708D01*
G01X2549333D02*
Y913763D01*
G01X2548349Y904708D02*
X2546184D01*
G01X2551499D02*
X2549333D01*
G01X2545200D02*
X2543034D01*
G01X2538900D02*
X2536735D01*
G01X2542050D02*
X2539885D01*
G01X2535751D02*
X2533585D01*
G01X2529452D02*
X2527286D01*
G01X2532601D02*
X2530436D01*
G01X2527286Y913763D02*
X2529452D01*
G01X2530436D02*
X2532601D01*
G01X2533585D02*
X2535751D01*
G01X2536735D02*
X2538900D01*
G01X2539885D02*
X2542050D01*
G01X2543034D02*
X2545200D01*
G01X2546184D02*
X2548349D01*
G01X2549333D02*
X2551499D01*
G01X2588275Y903950D02*
X2588439Y904075D01*
G01X2588275Y903070D02*
X2588357Y903112D01*
G01X2588480Y903824D02*
X2588604Y903866D01*
G01Y902987D02*
X2588480Y902945D01*
G01X2588152Y903782D02*
X2588275Y903950D01*
G01X2588152Y902903D02*
X2588275Y903070D01*
G01X2587537Y902484D02*
X2587783Y902777D01*
G01Y902442D02*
X2587537Y902149D01*
G01X2588398Y903740D02*
X2588480Y903824D01*
G01Y902945D02*
X2588398Y902861D01*
G01X2588111Y903657D02*
X2588152Y903782D01*
G01X2588357Y903615D02*
X2588398Y903740D01*
G01X2588111Y902777D02*
X2588152Y902903D01*
G01X2588398Y902861D02*
X2588357Y902735D01*
G01X2586144Y913763D02*
Y904708D01*
G01X2587129D02*
Y913763D01*
G01X2587291Y902149D02*
Y904118D01*
G01X2587537D02*
Y902484D01*
G01X2587783Y902777D02*
Y902442D01*
G01X2588111Y902610D02*
Y902777D01*
G01Y903447D02*
Y903657D01*
G01X2588357Y902735D02*
Y902651D01*
G01Y903489D02*
Y903615D01*
G01X2589294Y913763D02*
Y904708D01*
G01X2589383Y903866D02*
Y903238D01*
G01Y902400D02*
Y902987D01*
G01X2589629Y904118D02*
Y902149D01*
G01X2591361Y896834D02*
Y913763D01*
G01Y896834D02*
Y913763D01*
G01X2588152Y902484D02*
X2588111Y902610D01*
G01X2588357Y902651D02*
X2588398Y902526D01*
G01X2588152Y903322D02*
X2588111Y903447D01*
G01X2588398Y903364D02*
X2588357Y903489D01*
G01X2588275Y902316D02*
X2588152Y902484D01*
G01X2588275Y903154D02*
X2588152Y903322D01*
G01X2587424Y918881D02*
X2591361Y913763D01*
G01X2587424Y918881D02*
X2591361Y913763D01*
G01X2588398Y902526D02*
X2588480Y902442D01*
G01Y903280D02*
X2588398Y903364D01*
G01X2588439Y902191D02*
X2588275Y902316D01*
G01X2588357Y903112D02*
X2588275Y903154D01*
G01X2588480Y902442D02*
X2588604Y902400D01*
G01Y903238D02*
X2588480Y903280D01*
G01X2588644Y902149D02*
X2588439Y902191D01*
G01X2596479Y894866D02*
X2593330D01*
G01X2596479D02*
X2593330D01*
G01X2589629Y902149D02*
X2588644D01*
G01X2587537D02*
X2587291D01*
G01X2588604Y902400D02*
X2589383D01*
G01Y902987D02*
X2588604D01*
G01X2589383Y903238D02*
X2588604D01*
G01Y903866D02*
X2589383D01*
G01X2588644Y904118D02*
X2589629D01*
G01X2587291D02*
X2587537D01*
G01X2589294Y904708D02*
X2587129D01*
G01Y913763D02*
X2589294D01*
G01X2588439Y904075D02*
X2588644Y904118D01*
G01X2591361Y896834D02*
G03X2593330Y894866I1968J0D01*
G01X2591361Y896834D02*
G03X2593330Y894866I1968J0D01*
G01X2560948Y913763D02*
Y904708D01*
G01X2561932D02*
Y913763D01*
G01X2564097D02*
Y904708D01*
G01X2565081D02*
Y913763D01*
G01X2567247D02*
Y904708D01*
G01X2568231D02*
Y913763D01*
G01X2570396D02*
Y904708D01*
G01X2571381D02*
Y913763D01*
G01X2573546D02*
Y904708D01*
G01X2574530D02*
Y913763D01*
G01X2576696D02*
Y904708D01*
G01X2577680D02*
Y913763D01*
G01X2579845D02*
Y904708D01*
G01X2580830D02*
Y913763D01*
G01X2582995D02*
Y904708D01*
G01X2583979D02*
Y913763D01*
G01X2586144Y904708D02*
X2583979D01*
G01X2582995D02*
X2580830D01*
G01X2576696D02*
X2574530D01*
G01X2579845D02*
X2577680D01*
G01X2573546D02*
X2571381D01*
G01X2567247D02*
X2565081D01*
G01X2570396D02*
X2568231D01*
G01X2564097D02*
X2561932D01*
G01Y913763D02*
X2564097D01*
G01X2565081D02*
X2567247D01*
G01X2568231D02*
X2570396D01*
G01X2571381D02*
X2573546D01*
G01X2574530D02*
X2576696D01*
G01X2577680D02*
X2579845D01*
G01X2580830D02*
X2582995D01*
G01X2583979D02*
X2586144D01*
G01X2606534Y-1120610D02*
Y-1139623D01*
G01X2627335Y13369D02*
G03X2619461Y21243I-7874J0D01*
G01X2627335Y13369D02*
G03X2619461Y21243I-7874J0D01*
G01X2627335Y9432D02*
Y13369D01*
G01Y9432D02*
Y13369D01*
G01Y9432D02*
G03X2635209Y1558I7874J0D01*
G01X2627335Y9432D02*
G03X2635209Y1558I7874J0D01*
G01X2598448Y866913D02*
Y892897D01*
G01Y866913D02*
Y892897D01*
G01X2665770Y861795D02*
X2603566D01*
G01X2598448Y866913D02*
G03X2603566Y861795I5118J0D01*
G01X2598448Y866913D02*
G03X2603566Y861795I5118J0D01*
G01X2598448Y892897D02*
G03X2596479Y894866I-1969J0D01*
G01X2598448Y892897D02*
G03X2596479Y894866I-1969J0D01*
G01X2606534Y2171102D02*
Y2152090D01*
G01X3450613Y1558D02*
X2635209D01*
G01X3450613D02*
X2635209D01*
G01X2687344Y49364D02*
X2724866Y-71343D01*
G01X2686626Y55035D02*
X2745613Y-44730D01*
G01X2694265Y58763D02*
G03I-9843J0D01*
G01X2688753D02*
G03I-4331J0D01*
G01D02*
G03I-4331J0D01*
G01X2670889Y892897D02*
Y866913D01*
G01Y892897D02*
Y866913D01*
G01X2665770Y861795D02*
G03X2670889Y866913I1J5118D01*
G01X2665770Y861795D02*
G03X2670889Y866913I1J5118D01*
G01X2686341Y913763D02*
Y904708D01*
G01X2688507D02*
Y913763D01*
G01X2689491D02*
Y904708D01*
G01X2691656D02*
Y913763D01*
G01X2692641D02*
Y904708D01*
G01X2694806D02*
Y913763D01*
G01X2689491Y904708D02*
X2691656D01*
G01X2686341D02*
X2688507D01*
G01X2692641D02*
X2694806D01*
G01Y913763D02*
X2692641D01*
G01X2691656D02*
X2689491D01*
G01X2688507D02*
X2686341D01*
G01X2678426Y904075D02*
X2678267Y903950D01*
G01X2679827Y904075D02*
X2679668Y903950D01*
G01X2678808Y902191D02*
X2678967Y902316D01*
G01X2680209Y902191D02*
X2680368Y902316D01*
G01X2681610Y903070D02*
X2681673Y903112D01*
G01X2681769Y903824D02*
X2681864Y903866D01*
G01Y902987D02*
X2681769Y902945D01*
G01X2678267Y903950D02*
X2678172Y903824D01*
G01X2679668Y903950D02*
X2679572Y903824D01*
G01X2678967Y902316D02*
X2679063Y902442D01*
G01X2680368Y902316D02*
X2680464Y902442D01*
G01X2681705Y903740D02*
X2681769Y903824D01*
G01Y902945D02*
X2681705Y902861D01*
G01X2677975Y913763D02*
X2681912Y918881D01*
G01X2677975Y913763D02*
X2681912Y918881D01*
G01X2681610Y903950D02*
X2681737Y904075D01*
G01X2678458Y903866D02*
X2678363Y903782D01*
G01X2679859Y903866D02*
X2679763Y903782D01*
G01X2678776Y902400D02*
X2678872Y902484D01*
G01X2680177Y902400D02*
X2680272Y902484D01*
G01X2678363Y903782D02*
X2678235Y903531D01*
G01X2678872Y902484D02*
X2678999Y902735D01*
G01X2679763Y903782D02*
X2679636Y903531D01*
G01X2680272Y902484D02*
X2680400Y902735D01*
G01X2681514Y903782D02*
X2681610Y903950D01*
G01X2681514Y902903D02*
X2681610Y903070D01*
G01X2681037Y902484D02*
X2681228Y902777D01*
G01Y902442D02*
X2681037Y902149D01*
G01X2678172Y903824D02*
X2678108Y903657D01*
G01X2679572Y903824D02*
X2679509Y903657D01*
G01X2679063Y902442D02*
X2679127Y902610D01*
G01X2680464Y902442D02*
X2680527Y902610D01*
G01X2678235Y903531D02*
X2678204Y903280D01*
G01X2678076Y903531D02*
X2678044Y903322D01*
G01X2679158Y902735D02*
X2679190Y902945D01*
G01X2679477Y903531D02*
X2679445Y903322D01*
G01X2680559Y902735D02*
X2680591Y902945D01*
G01X2678108Y903657D02*
X2678076Y903531D01*
G01X2679127Y902610D02*
X2679158Y902735D01*
G01X2679509Y903657D02*
X2679477Y903531D01*
G01X2680527Y902610D02*
X2680559Y902735D01*
G01X2681482Y903657D02*
X2681514Y903782D01*
G01X2681673Y903615D02*
X2681705Y903740D01*
G01X2681482Y902777D02*
X2681514Y902903D01*
G01X2681705Y902861D02*
X2681673Y902735D01*
G01X2677975Y913763D02*
Y896834D01*
G01Y913763D02*
Y896834D01*
G01X2678044Y903322D02*
Y902945D01*
G01X2678204Y903280D02*
Y902987D01*
G01X2679031D02*
Y903280D01*
G01X2679190Y902945D02*
Y903322D01*
G01X2679445D02*
Y902945D01*
G01X2679604Y903280D02*
Y902987D01*
G01X2680042Y913763D02*
Y904708D01*
G01X2678999Y902735D02*
X2679031Y902987D01*
G01X2679636Y903531D02*
X2679604Y903280D01*
G01X2680400Y902735D02*
X2680432Y902987D01*
G01D02*
Y903280D01*
G01X2680591Y902945D02*
Y903322D01*
G01X2680846Y902149D02*
Y904118D01*
G01X2681037D02*
Y902484D01*
G01X2681228Y902777D02*
Y902442D01*
G01X2681482Y902610D02*
Y902777D01*
G01Y903447D02*
Y903657D01*
G01X2681673Y902735D02*
Y902651D01*
G01Y903489D02*
Y903615D01*
G01X2682207Y904708D02*
Y913763D01*
G01X2682469Y903866D02*
Y903238D01*
G01Y902400D02*
Y902987D01*
G01X2682660Y904118D02*
Y902149D01*
G01X2683192Y913763D02*
Y904708D01*
G01X2685357D02*
Y913763D01*
G01X2678204Y902987D02*
X2678235Y902735D01*
G01X2679031Y903280D02*
X2678999Y903531D01*
G01X2678076Y902735D02*
X2678108Y902610D01*
G01X2678044Y902945D02*
X2678076Y902735D01*
G01X2679190Y903322D02*
X2679158Y903531D01*
G01X2679445Y902945D02*
X2679477Y902735D01*
G01X2680591Y903322D02*
X2680559Y903531D01*
G01X2679604Y902987D02*
X2679636Y902735D01*
G01X2680432Y903280D02*
X2680400Y903531D01*
G01X2678108Y902610D02*
X2678172Y902442D01*
G01X2679509Y902610D02*
X2679572Y902442D01*
G01X2679127Y903657D02*
X2679063Y903824D01*
G01X2679158Y903531D02*
X2679127Y903657D01*
G01X2679477Y902735D02*
X2679509Y902610D01*
G01X2680559Y903531D02*
X2680527Y903657D01*
G01X2681514Y902484D02*
X2681482Y902610D01*
G01X2681673Y902651D02*
X2681705Y902526D01*
G01X2681514Y903322D02*
X2681482Y903447D01*
G01X2681705Y903364D02*
X2681673Y903489D01*
G01X2678235Y902735D02*
X2678363Y902484D01*
G01X2678999Y903531D02*
X2678872Y903782D01*
G01X2679636Y902735D02*
X2679763Y902484D01*
G01X2680400Y903531D02*
X2680272Y903782D01*
G01X2680527Y903657D02*
X2680464Y903824D01*
G01X2681610Y902316D02*
X2681514Y902484D01*
G01X2681610Y903154D02*
X2681514Y903322D01*
G01X2678172Y902442D02*
X2678267Y902316D01*
G01X2679572Y902442D02*
X2679668Y902316D01*
G01X2679063Y903824D02*
X2678967Y903950D01*
G01X2680464Y903824D02*
X2680368Y903950D01*
G01X2681705Y902526D02*
X2681769Y902442D01*
G01Y903280D02*
X2681705Y903364D01*
G01X2678363Y902484D02*
X2678458Y902400D01*
G01X2679763Y902484D02*
X2679859Y902400D01*
G01X2678872Y903782D02*
X2678776Y903866D01*
G01X2680272Y903782D02*
X2680177Y903866D01*
G01X2681737Y902191D02*
X2681610Y902316D01*
G01X2681673Y903112D02*
X2681610Y903154D01*
G01X2678267Y902316D02*
X2678426Y902191D01*
G01X2679668Y902316D02*
X2679827Y902191D01*
G01X2678967Y903950D02*
X2678808Y904075D01*
G01X2680368Y903950D02*
X2680209Y904075D01*
G01X2681769Y902442D02*
X2681864Y902400D01*
G01Y903238D02*
X2681769Y903280D01*
G01X2678426Y902191D02*
X2678617Y902149D01*
G01X2679827Y902191D02*
X2680018Y902149D01*
G01X2678808Y904075D02*
X2678617Y904118D01*
G01X2680209Y904075D02*
X2680018Y904118D01*
G01X2678458Y902400D02*
X2678617Y902358D01*
G01X2679859Y902400D02*
X2680018Y902358D01*
G01X2681896Y902149D02*
X2681737Y902191D01*
G01X2678776Y903866D02*
X2678617Y903908D01*
G01X2680177Y903866D02*
X2680018Y903908D01*
G01X2676007Y894866D02*
X2672857D01*
G01X2676007D02*
X2672857D01*
G01X2682660Y902149D02*
X2681896D01*
G01X2681037D02*
X2680846D01*
G01X2681864Y902400D02*
X2682469D01*
G01Y902987D02*
X2681864D01*
G01X2682469Y903238D02*
X2681864D01*
G01Y903866D02*
X2682469D01*
G01X2680846Y904118D02*
X2681037D01*
G01X2681896D02*
X2682660D01*
G01X2680042Y904708D02*
X2682207D01*
G01X2683192D02*
X2685357D01*
G01Y913763D02*
X2683192D01*
G01X2682207D02*
X2680042D01*
G01X2677975D02*
X2857896D01*
G01X2680018Y902358D02*
X2680177Y902400D01*
G01X2678617Y902358D02*
X2678776Y902400D01*
G01X2681737Y904075D02*
X2681896Y904118D01*
G01X2680018Y903908D02*
X2679859Y903866D01*
G01X2678617Y903908D02*
X2678458Y903866D01*
G01X2680018Y902149D02*
X2680209Y902191D01*
G01X2678617Y902149D02*
X2678808Y902191D01*
G01X2680018Y904118D02*
X2679827Y904075D01*
G01X2678617Y904118D02*
X2678426Y904075D01*
G01X2672857Y894866D02*
G03X2670889Y892897I1J-1969D01*
G01X2676007Y894866D02*
G03X2677975Y896834I0J1968D01*
G01X2672857Y894866D02*
G03X2670889Y892897I1J-1969D01*
G01X2676007Y894866D02*
G03X2677975Y896834I0J1968D01*
G01X2853959Y918881D02*
X2681912D01*
G01D02*
X2853959D01*
G01X2729163Y-1124413D02*
X2724885D01*
X2724172Y-1129166D01*
X2725598Y-1128215D01*
X2727024D01*
X2728450Y-1129166D01*
X2729163Y-1130117D01*
X2729876Y-1132018D01*
X2729163Y-1133919D01*
X2728450Y-1134870D01*
X2727024Y-1135820D01*
X2725598D01*
X2724172Y-1134870D01*
X2723459Y-1133919D01*
G01X2714904Y-1124413D02*
Y-1135820D01*
G01X2724866Y-71343D02*
X2728015D01*
G01D02*
X2990745D01*
G01X2732060Y58763D02*
G03I-4331J0D01*
G01D02*
G03I-4331J0D01*
G01X2737572D02*
G03I-9843J0D01*
G01X2720003Y904708D02*
Y913763D01*
G01X2720987D02*
Y904708D01*
G01X2723152D02*
Y913763D01*
G01X2724137D02*
Y904708D01*
G01X2726302D02*
Y913763D01*
G01X2727286D02*
Y904708D01*
G01X2720987D02*
X2723152D01*
G01X2727286D02*
X2729452D01*
G01X2724137D02*
X2726302D01*
G01X2729452Y913763D02*
X2727286D01*
G01X2726302D02*
X2724137D01*
G01X2723152D02*
X2720987D01*
G01X2695790D02*
Y904708D01*
G01X2697956D02*
Y913763D01*
G01X2698940D02*
Y904708D01*
G01X2701105D02*
Y913763D01*
G01X2702089D02*
Y904708D01*
G01X2704255D02*
Y913763D01*
G01X2705239D02*
Y904708D01*
G01X2707404D02*
Y913763D01*
G01X2708389D02*
Y904708D01*
G01X2710554D02*
Y913763D01*
G01X2711538D02*
Y904708D01*
G01X2713704D02*
Y913763D01*
G01X2714688D02*
Y904708D01*
G01X2716853D02*
Y913763D01*
G01X2717837D02*
Y904708D01*
G01X2698940D02*
X2701105D01*
G01X2695790D02*
X2697956D01*
G01X2702089D02*
X2704255D01*
G01X2708389D02*
X2710554D01*
G01X2705239D02*
X2707404D01*
G01X2711538D02*
X2713704D01*
G01X2717837D02*
X2720003D01*
G01X2714688D02*
X2716853D01*
G01X2720003Y913763D02*
X2717837D01*
G01X2716853D02*
X2714688D01*
G01X2713704D02*
X2711538D01*
G01X2710554D02*
X2708389D01*
G01X2707404D02*
X2705239D01*
G01X2704255D02*
X2702089D01*
G01X2701105D02*
X2698940D01*
G01X2697956D02*
X2695790D01*
G01X2729163Y2167300D02*
X2724885D01*
X2724172Y2162547D01*
X2725598Y2163497D01*
X2727024D01*
X2728450Y2162547D01*
X2729163Y2161596D01*
X2729876Y2159695D01*
X2729163Y2157793D01*
X2728450Y2156843D01*
X2727024Y2155892D01*
X2725598D01*
X2724172Y2156843D01*
X2723459Y2157793D01*
G01X2714904Y2167300D02*
Y2155892D01*
G01X2746908Y-63403D02*
X2749831Y-69177D01*
G01X2742036D02*
Y-60516D01*
X2738626Y-67012D01*
X2743010D01*
G01X2752267Y-64847D02*
X2752989Y-62681D01*
X2754433Y-61238D01*
X2756598Y-60516D01*
X2758763Y-61238D01*
X2760207Y-62681D01*
X2760929Y-64847D01*
X2760207Y-67012D01*
X2758763Y-68455D01*
X2756598Y-69177D01*
X2754433Y-68455D01*
X2752989Y-67012D01*
X2752267Y-64847D01*
G01X2746908Y-69177D02*
X2749831Y-63403D01*
G01X2752989Y-71343D02*
X2760207Y-58351D01*
G01X2762783Y-42565D02*
Y-33903D01*
X2759373Y-40399D01*
X2763758D01*
G01X2745613Y-44730D02*
X2748763D01*
G01D02*
X2871178D01*
G01X2780879Y58763D02*
G03I-9843J0D01*
G01X2754648Y904708D02*
Y913763D01*
G01X2755633D02*
Y904708D01*
G01X2757798D02*
Y913763D01*
G01X2758782D02*
Y904708D01*
G01X2760948D02*
Y913763D01*
G01X2761932D02*
Y904708D01*
G01X2755633D02*
X2757798D01*
G01X2758782D02*
X2760948D01*
G01X2761932D02*
X2764097D01*
G01Y913763D02*
X2761932D01*
G01X2760948D02*
X2758782D01*
G01X2757798D02*
X2755633D01*
G01X2729452Y904708D02*
Y913763D01*
G01X2730436D02*
Y904708D01*
G01X2732601D02*
Y913763D01*
G01X2733585D02*
Y904708D01*
G01X2735751D02*
Y913763D01*
G01X2736735D02*
Y904708D01*
G01X2738900D02*
Y913763D01*
G01X2739885D02*
Y904708D01*
G01X2742050D02*
Y913763D01*
G01X2743034D02*
Y904708D01*
G01X2745200D02*
Y913763D01*
G01X2746184D02*
Y904708D01*
G01X2748349D02*
Y913763D01*
G01X2749333D02*
Y904708D01*
G01X2751499D02*
Y913763D01*
G01X2752483D02*
Y904708D01*
G01X2730436D02*
X2732601D01*
G01X2736735D02*
X2738900D01*
G01X2733585D02*
X2735751D01*
G01X2739885D02*
X2742050D01*
G01X2746184D02*
X2748349D01*
G01X2743034D02*
X2745200D01*
G01X2749333D02*
X2751499D01*
G01X2752483D02*
X2754648D01*
G01Y913763D02*
X2752483D01*
G01X2751499D02*
X2749333D01*
G01X2748349D02*
X2746184D01*
G01X2745200D02*
X2743034D01*
G01X2742050D02*
X2739885D01*
G01X2738900D02*
X2736735D01*
G01X2735751D02*
X2733585D01*
G01X2732601D02*
X2730436D01*
G01X2791099Y-69177D02*
X2790125Y-68455D01*
X2789638Y-67734D01*
X2789150Y-66290D01*
Y-63403D01*
X2789638Y-61960D01*
X2790125Y-61238D01*
X2791099Y-60516D01*
X2792074Y-61238D01*
X2792561Y-61960D01*
X2793048Y-63403D01*
Y-66290D01*
X2792561Y-67734D01*
X2792074Y-68455D01*
X2791099Y-69177D01*
G01X2775509D02*
X2775022D01*
Y-68455D01*
X2775509Y-69177D01*
G01X2769662Y-60516D02*
X2766739D01*
X2766252Y-64125D01*
X2767226Y-63403D01*
X2768201D01*
X2769175Y-64125D01*
X2769662Y-64847D01*
X2770150Y-66290D01*
X2769662Y-67734D01*
X2769175Y-68455D01*
X2768201Y-69177D01*
X2767226D01*
X2766252Y-68455D01*
X2765765Y-67734D01*
G01X2783304Y-69177D02*
X2782330Y-68455D01*
X2781843Y-67734D01*
X2781355Y-66290D01*
Y-63403D01*
X2781843Y-61960D01*
X2782330Y-61238D01*
X2783304Y-60516D01*
X2784279Y-61238D01*
X2784766Y-61960D01*
X2785253Y-63403D01*
Y-66290D01*
X2784766Y-67734D01*
X2784279Y-68455D01*
X2783304Y-69177D01*
G01X2796256Y-42565D02*
X2795769D01*
Y-41843D01*
X2796256Y-42565D01*
G01X2767656Y-36790D02*
X2770579Y-42565D01*
G01X2773015Y-38234D02*
X2773736Y-36068D01*
X2775180Y-34625D01*
X2777345Y-33903D01*
X2779511Y-34625D01*
X2780954Y-36068D01*
X2781676Y-38234D01*
X2780954Y-40399D01*
X2779511Y-41843D01*
X2777345Y-42565D01*
X2775180Y-41843D01*
X2773736Y-40399D01*
X2773015Y-38234D01*
G01X2767656Y-42565D02*
X2770579Y-36790D01*
G01X2773736Y-44730D02*
X2780954Y-31738D01*
G01X2787974Y-38956D02*
X2786999Y-40399D01*
X2786512Y-42565D01*
X2790409D01*
G01X2786512Y-35347D02*
X2786999Y-34625D01*
X2787974Y-33903D01*
X2788948D01*
X2789922Y-34625D01*
X2790409Y-35347D01*
Y-36790D01*
X2789922Y-37512D01*
X2787974Y-38956D01*
G01X2775367Y58763D02*
G03I-4331J0D01*
G01D02*
G03I-4331J0D01*
G01X2787129Y913763D02*
Y904708D01*
G01X2789294D02*
Y913763D01*
G01X2790278D02*
Y904708D01*
G01X2792444D02*
Y913763D01*
G01X2793428D02*
Y904708D01*
G01X2795593D02*
Y913763D01*
G01X2787129Y904708D02*
X2789294D01*
G01X2790278D02*
X2792444D01*
G01X2793428D02*
X2795593D01*
G01Y913763D02*
X2793428D01*
G01X2792444D02*
X2790278D01*
G01X2789294D02*
X2787129D01*
G01X2764097Y904708D02*
Y913763D01*
G01X2765081D02*
Y904708D01*
G01X2767247D02*
Y913763D01*
G01X2768231D02*
Y904708D01*
G01X2770396D02*
Y913763D01*
G01X2771381D02*
Y904708D01*
G01X2773546D02*
Y913763D01*
G01X2774530D02*
Y904708D01*
G01X2776696D02*
Y913763D01*
G01X2777680D02*
Y904708D01*
G01X2779845D02*
Y913763D01*
G01X2780830D02*
Y904708D01*
G01X2782995D02*
Y913763D01*
G01X2783979D02*
Y904708D01*
G01X2786144D02*
Y913763D01*
G01X2765081Y904708D02*
X2767247D01*
G01X2768231D02*
X2770396D01*
G01X2771381D02*
X2773546D01*
G01X2777680D02*
X2779845D01*
G01X2774530D02*
X2776696D01*
G01X2780830D02*
X2782995D01*
G01X2783979D02*
X2786144D01*
G01Y913763D02*
X2783979D01*
G01X2782995D02*
X2780830D01*
G01X2779845D02*
X2777680D01*
G01X2776696D02*
X2774530D01*
G01X2773546D02*
X2771381D01*
G01X2770396D02*
X2768231D01*
G01X2767247D02*
X2765081D01*
G01X2827076Y-1120610D02*
Y-1139623D01*
G01X2812536Y-69177D02*
Y-60516D01*
X2816434Y-69177D01*
Y-60516D01*
G01X2807177D02*
X2806203Y-61960D01*
X2805715Y-64125D01*
Y-65568D01*
X2806203Y-67734D01*
X2807177Y-69177D01*
G01X2824230Y-67012D02*
X2823255Y-68455D01*
X2822280Y-69177D01*
X2821306Y-68455D01*
X2820331Y-67012D01*
Y-65568D01*
X2821306Y-64125D01*
X2822280Y-63403D01*
X2823255Y-64125D01*
X2824230Y-65568D01*
Y-67012D01*
G01X2827924Y-33903D02*
X2826950Y-35347D01*
X2826463Y-37512D01*
Y-38956D01*
X2826950Y-41121D01*
X2827924Y-42565D01*
G01X2811846D02*
X2810872Y-41843D01*
X2810385Y-41121D01*
X2809898Y-39677D01*
Y-36790D01*
X2810385Y-35347D01*
X2810872Y-34625D01*
X2811846Y-33903D01*
X2812821Y-34625D01*
X2813308Y-35347D01*
X2813795Y-36790D01*
Y-39677D01*
X2813308Y-41121D01*
X2812821Y-41843D01*
X2811846Y-42565D01*
G01X2802103Y-35347D02*
X2802590Y-34625D01*
X2803564Y-33903D01*
X2804539D01*
X2805513Y-34625D01*
X2806000Y-35347D01*
Y-36790D01*
X2805513Y-37512D01*
G01D02*
X2803564Y-38956D01*
X2802590Y-40399D01*
X2802103Y-42565D01*
X2806000D01*
G01X2824186Y58763D02*
G03I-9843J0D01*
G01X2818674D02*
G03I-4331J0D01*
G01D02*
G03I-4331J0D01*
G01X2826341Y884261D02*
X2826095Y882753D01*
G01X2825111Y884261D02*
X2824865Y883004D01*
G01X2822896Y884009D02*
Y883004D01*
G01Y880994D02*
Y879989D01*
G01X2824865Y883004D02*
Y880743D01*
G01X2826095Y882753D02*
Y880994D01*
G01X2824865Y880743D02*
X2825111Y879486D01*
G01X2826095Y880994D02*
X2826341Y879486D01*
G01X2825111D02*
X2825357Y878732D01*
G01D02*
X2825849Y877727D01*
G01X2826341Y879486D02*
X2827326Y877978D01*
G01X2825849Y877727D02*
X2826587Y876973D01*
G01X2827326Y877978D02*
X2828064Y877476D01*
G01X2826587Y876973D02*
X2827818Y876219D01*
G01X2829294Y877224D02*
X2830524Y877476D01*
G01X2829294Y875968D02*
X2830770Y876219D01*
G01X2827818D02*
X2829294Y875968D01*
G01X2828064Y877476D02*
X2829294Y877224D01*
G01X2807148Y875968D02*
Y887779D01*
G01X2808625D02*
Y883004D01*
G01Y881496D02*
Y875968D01*
G01X2815515D02*
Y881496D01*
G01Y883004D02*
Y887779D01*
G01X2816991D02*
Y875968D01*
G01X2818959Y879989D02*
Y880994D01*
G01Y883004D02*
Y884009D01*
G01X2816991Y875968D02*
X2815515D01*
G01X2808625D02*
X2807148D01*
G01X2822896Y879989D02*
X2818959D01*
G01Y880994D02*
X2822896D01*
G01X2815515Y881496D02*
X2808625D01*
G01X2822896Y883004D02*
X2818959D01*
G01X2808625D02*
X2815515D01*
G01X2820790Y904708D02*
Y913763D01*
G01X2821774D02*
Y904708D01*
G01X2823940D02*
Y913763D01*
G01X2824924D02*
Y904708D01*
G01X2827089D02*
Y913763D01*
G01X2828074D02*
Y904708D01*
G01X2824924D02*
X2827089D01*
G01X2821774D02*
X2823940D01*
G01X2828074D02*
X2830239D01*
G01Y913763D02*
X2828074D01*
G01X2827089D02*
X2824924D01*
G01X2823940D02*
X2821774D01*
G01X2828064Y886271D02*
X2827326Y885768D01*
G01X2827818Y887528D02*
X2826587Y886774D01*
G01D02*
X2825849Y886020D01*
G01X2827326Y885768D02*
X2826341Y884261D01*
G01X2825849Y886020D02*
X2825357Y885015D01*
G01D02*
X2825111Y884261D01*
G01X2829294Y886522D02*
X2828064Y886271D01*
G01X2829294Y887779D02*
X2827818Y887528D01*
G01X2830770D02*
X2829294Y887779D01*
G01X2830524Y886271D02*
X2829294Y886522D01*
G01X2796578Y913763D02*
Y904708D01*
G01X2798743D02*
Y913763D01*
G01X2799727D02*
Y904708D01*
G01X2801893D02*
Y913763D01*
G01X2802877D02*
Y904708D01*
G01X2805042D02*
Y913763D01*
G01X2806026D02*
Y904708D01*
G01X2808192D02*
Y913763D01*
G01X2809176D02*
Y904708D01*
G01X2811341D02*
Y913763D01*
G01X2812326D02*
Y904708D01*
G01X2814491D02*
Y913763D01*
G01X2815475D02*
Y904708D01*
G01X2817641D02*
Y913763D01*
G01X2818625D02*
Y904708D01*
G01X2796578D02*
X2798743D01*
G01X2799727D02*
X2801893D01*
G01X2806026D02*
X2808192D01*
G01X2802877D02*
X2805042D01*
G01X2809176D02*
X2811341D01*
G01X2815475D02*
X2817641D01*
G01X2812326D02*
X2814491D01*
G01X2818625D02*
X2820790D01*
G01Y913763D02*
X2818625D01*
G01X2817641D02*
X2815475D01*
G01X2814491D02*
X2812326D01*
G01X2811341D02*
X2809176D01*
G01X2808192D02*
X2806026D01*
G01X2805042D02*
X2802877D01*
G01X2801893D02*
X2799727D01*
G01X2798743D02*
X2796578D01*
G01X2818959Y884009D02*
X2822896D01*
G01X2807148Y887779D02*
X2808625D01*
G01X2815515D02*
X2816991D01*
G01X2827076Y2171102D02*
Y2152090D01*
G01X2855411Y-63403D02*
Y-69177D01*
G01X2862231Y-68455D02*
X2861257Y-69177D01*
X2860282Y-68455D01*
X2859308Y-67012D01*
Y-65568D01*
X2860282Y-64125D01*
X2861257Y-63403D01*
X2862231Y-64125D01*
G01X2836409D02*
X2839333D01*
G01X2837871Y-69177D02*
Y-60516D01*
G01X2844205Y-69177D02*
Y-63403D01*
G01Y-64847D02*
X2845179Y-63403D01*
X2846154D01*
X2846641Y-64125D01*
G01X2855411Y-67012D02*
X2854436Y-68455D01*
X2853462Y-69177D01*
X2852487Y-68455D01*
X2851513Y-67012D01*
Y-65568D01*
X2852487Y-64125D01*
X2853462Y-63403D01*
X2854436Y-64125D01*
X2855411Y-65568D01*
G01X2858131Y-33903D02*
X2859106Y-35347D01*
X2859593Y-37512D01*
Y-38956D01*
X2859106Y-41121D01*
X2858131Y-42565D01*
G01X2848874Y-38234D02*
X2852772D01*
G01X2840592Y-33903D02*
X2845464D01*
G01X2833284Y-42565D02*
Y-33903D01*
X2835720D01*
X2836694Y-34625D01*
X2837181Y-35347D01*
Y-36790D01*
X2836694Y-37512D01*
X2835720Y-38234D01*
X2833284D01*
G01X2843028Y-33903D02*
Y-42565D01*
G01X2848874Y-33903D02*
Y-42565D01*
G01X2852772Y-33903D02*
Y-42565D01*
G01X2854639Y875968D02*
Y881999D01*
G01X2855869D02*
Y875968D01*
G01X2855377Y883256D02*
X2855869Y881999D01*
G01X2854639D02*
X2854393Y882502D01*
G01X2854885Y883758D02*
X2855377Y883256D01*
G01X2855869Y875968D02*
X2854639D01*
G01X2838152Y883004D02*
X2837414Y882753D01*
G01X2849225Y883004D02*
X2848487Y882753D01*
G01X2830524Y877476D02*
X2831263Y877978D01*
G01X2830770Y876219D02*
X2832001Y876973D01*
G01X2841843Y883004D02*
X2841351Y882753D01*
G01X2852916Y883004D02*
X2852424Y882753D01*
G01X2836922Y883256D02*
X2837414Y883758D01*
G01Y882753D02*
X2836922Y882250D01*
G01X2832001Y876973D02*
X2832739Y877727D01*
G01X2840613Y883004D02*
X2841351Y883758D01*
G01Y882753D02*
X2841105Y882502D01*
G01X2847995Y883256D02*
X2848487Y883758D01*
G01Y882753D02*
X2847995Y882250D01*
G01X2851686Y883004D02*
X2852424Y883758D01*
G01Y882753D02*
X2852178Y882502D01*
G01X2831263Y877978D02*
X2832247Y879486D01*
G01X2832739Y877727D02*
X2833231Y878732D01*
G01X2841105Y882502D02*
X2840859Y881999D01*
G01X2852178Y882502D02*
X2851932Y881999D01*
G01X2833231Y878732D02*
X2833477Y879486D01*
G01X2832247D02*
X2832493Y880994D01*
G01X2833477Y879486D02*
X2833723Y880743D01*
G01X2832493Y880994D02*
Y882753D01*
G01X2833723Y880743D02*
Y883004D01*
G01X2835692Y875968D02*
Y884009D01*
G01X2836922D02*
Y883256D01*
G01Y882250D02*
Y875968D01*
G01X2839629D02*
Y881999D01*
G01X2840859D02*
Y875968D01*
G01X2843566D02*
Y881999D01*
G01X2844796D02*
Y875968D01*
G01X2846765D02*
Y884009D01*
G01X2847995D02*
Y883256D01*
G01Y882250D02*
Y875968D01*
G01X2850702D02*
Y881999D01*
G01X2851932D02*
Y875968D01*
G01X2832493Y882753D02*
X2832247Y884261D01*
G01X2833723Y883004D02*
X2833477Y884261D01*
G01X2844304Y883256D02*
X2844796Y881999D01*
G01X2839629D02*
X2839383Y882502D01*
G01X2843566Y881999D02*
X2843320Y882502D01*
G01X2850702Y881999D02*
X2850456Y882502D01*
G01X2839383D02*
X2839137Y882753D01*
G01X2839875Y883758D02*
X2840613Y883004D01*
G01X2843320Y882502D02*
X2843074Y882753D01*
G01X2843812Y883758D02*
X2844304Y883256D01*
G01X2850456Y882502D02*
X2850209Y882753D01*
G01X2850948Y883758D02*
X2851686Y883004D01*
G01X2854393Y882502D02*
X2854146Y882753D01*
G01X2839137D02*
X2838644Y883004D01*
G01X2843074Y882753D02*
X2842581Y883004D01*
G01X2850209Y882753D02*
X2849717Y883004D01*
G01X2854146Y882753D02*
X2853654Y883004D01*
G01X2851932Y875968D02*
X2850702D01*
G01X2847995D02*
X2846765D01*
G01X2844796D02*
X2843566D01*
G01X2836922D02*
X2835692D01*
G01X2840859D02*
X2839629D01*
G01X2853654Y883004D02*
X2852916D01*
G01X2849717D02*
X2849225D01*
G01X2842581D02*
X2841843D01*
G01X2838644D02*
X2838152D01*
G01X2855436Y904708D02*
Y913763D01*
G01X2857896D02*
Y897228D01*
G01Y913763D02*
Y897228D01*
G01D02*
G03X2866558I4331J0D01*
G01X2857896D02*
G03X2866558I4331J0D01*
G01X2830239Y904708D02*
Y913763D01*
G01X2831223D02*
Y904708D01*
G01X2833389D02*
Y913763D01*
G01X2834373D02*
Y904708D01*
G01X2836538D02*
Y913763D01*
G01X2837522D02*
Y904708D01*
G01X2839688D02*
Y913763D01*
G01X2840672D02*
Y904708D01*
G01X2842837D02*
Y913763D01*
G01X2843822D02*
Y904708D01*
G01X2845987D02*
Y913763D01*
G01X2846971D02*
Y904708D01*
G01X2849137D02*
Y913763D01*
G01X2850121D02*
Y904708D01*
G01X2852286D02*
Y913763D01*
G01X2853270D02*
Y904708D01*
G01X2853959Y918881D02*
X2857896Y913763D01*
G01X2853959Y918881D02*
X2857896Y913763D01*
G01X2834373Y904708D02*
X2836538D01*
G01X2831223D02*
X2833389D01*
G01X2837522D02*
X2839688D01*
G01X2843822D02*
X2845987D01*
G01X2840672D02*
X2842837D01*
G01X2846971D02*
X2849137D01*
G01X2853270D02*
X2855436D01*
G01X2850121D02*
X2852286D01*
G01X2855436Y913763D02*
X2853270D01*
G01X2852286D02*
X2850121D01*
G01X2849137D02*
X2846971D01*
G01X2845987D02*
X2843822D01*
G01X2842837D02*
X2840672D01*
G01X2839688D02*
X2837522D01*
G01X2836538D02*
X2834373D01*
G01X2833389D02*
X2831223D01*
G01X2837414Y883758D02*
X2838152Y884009D01*
G01X2841351Y883758D02*
X2842089Y884009D01*
G01X2848487Y883758D02*
X2849225Y884009D01*
G01X2852424Y883758D02*
X2853162Y884009D01*
G01X2833477Y884261D02*
X2833231Y885015D01*
G01D02*
X2832739Y886020D01*
G01X2832247Y884261D02*
X2831263Y885768D01*
G01D02*
X2830524Y886271D01*
G01X2832739Y886020D02*
X2832001Y886774D01*
G01X2839137Y884009D02*
X2839875Y883758D01*
G01X2832001Y886774D02*
X2830770Y887528D01*
G01X2835692Y884009D02*
X2836922D01*
G01X2838152D02*
X2839137D01*
G01X2842089D02*
X2843074D01*
G01X2846765D02*
X2847995D01*
G01X2849225D02*
X2850209D01*
G01X2853162D02*
X2854146D01*
G01X2843074D02*
X2843812Y883758D01*
G01X2850209Y884009D02*
X2850948Y883758D01*
G01X2854146Y884009D02*
X2854885Y883758D01*
G01X2890976Y-64125D02*
X2893900D01*
G01X2892438Y-69177D02*
Y-60516D01*
G01X2886591Y-63403D02*
Y-69177D01*
G01X2870514Y-67734D02*
X2870027Y-68455D01*
X2869052Y-69177D01*
X2868078Y-68455D01*
X2867103Y-67012D01*
Y-65568D01*
X2868078Y-64125D01*
X2869052Y-63403D01*
X2870027Y-64125D01*
X2870514Y-65568D01*
X2867103D01*
G01X2886591Y-67012D02*
X2885617Y-68455D01*
X2884643Y-69177D01*
X2883668Y-68455D01*
X2882694Y-67012D01*
Y-65568D01*
X2883668Y-64125D01*
X2884643Y-63403D01*
X2885617Y-64125D01*
X2886591Y-65568D01*
G01X2890081Y913763D02*
Y904708D01*
G01X2891066D02*
Y913763D01*
G01X2893231D02*
Y904708D01*
G01X2894215D02*
Y913763D01*
G01X2896381D02*
Y904708D01*
G01X2897365D02*
Y913763D01*
G01X2899530Y904708D02*
X2897365D01*
G01X2896381D02*
X2894215D01*
G01X2893231D02*
X2891066D01*
G01Y913763D02*
X2893231D01*
G01X2894215D02*
X2896381D01*
G01X2897365D02*
X2899530D01*
G01X2866558D02*
X2870495Y918881D01*
G01X2866558Y913763D02*
X2870495Y918881D01*
G01X2866558Y913763D02*
Y897228D01*
G01Y913763D02*
Y897228D01*
G01X2869019Y904708D02*
Y913763D01*
G01X2871184D02*
Y904708D01*
G01X2872168D02*
Y913763D01*
G01X2874333D02*
Y904708D01*
G01X2875318D02*
Y913763D01*
G01X2877483D02*
Y904708D01*
G01X2878467D02*
Y913763D01*
G01X2880633D02*
Y904708D01*
G01X2881617D02*
Y913763D01*
G01X2883782D02*
Y904708D01*
G01X2884767D02*
Y913763D01*
G01X2886932D02*
Y904708D01*
G01X2887916D02*
Y913763D01*
G01X2890081Y904708D02*
X2887916D01*
G01X2886932D02*
X2884767D01*
G01X2880633D02*
X2878467D01*
G01X2883782D02*
X2881617D01*
G01X2877483D02*
X2875318D01*
G01X2871184D02*
X2869019D01*
G01X2874333D02*
X2872168D01*
G01X2866558Y913763D02*
X3008684D01*
G01X2869019D02*
X2871184D01*
G01X2872168D02*
X2874333D01*
G01X2875318D02*
X2877483D01*
G01X2878467D02*
X2880633D01*
G01X2881617D02*
X2883782D01*
G01X2884767D02*
X2886932D01*
G01X2887916D02*
X2890081D01*
G01X3004747Y918881D02*
X2870495D01*
G01D02*
X3004747D01*
G01X2926457Y-224184D02*
X2925970Y-223462D01*
X2924995Y-222740D01*
X2924021D01*
X2923046Y-223462D01*
X2922559Y-224184D01*
Y-224906D01*
X2923046Y-225627D01*
X2924021Y-226349D01*
X2925970Y-227793D01*
X2926457Y-228515D01*
Y-229958D01*
X2925970Y-230680D01*
X2924995Y-231402D01*
X2924021D01*
X2923046Y-230680D01*
X2922072Y-229236D01*
G01X2934252D02*
X2933278Y-230680D01*
X2932303Y-231402D01*
X2931329Y-230680D01*
X2930354Y-229236D01*
Y-227793D01*
X2931329Y-226349D01*
X2932303Y-225627D01*
X2933278Y-226349D01*
X2934252Y-227793D01*
Y-229236D01*
G01X2923619Y-69177D02*
Y-60516D01*
G01X2909977Y-63403D02*
Y-69177D01*
G01X2915824D02*
Y-60516D01*
G01X2909977Y-67012D02*
X2909003Y-68455D01*
X2908029Y-69177D01*
X2907054Y-68455D01*
X2906080Y-67012D01*
Y-65568D01*
X2907054Y-64125D01*
X2908029Y-63403D01*
X2909003Y-64125D01*
X2909977Y-65568D01*
G01X2954046Y257464D02*
G03I-15748J0D01*
G01Y304708D02*
G03I-15748J0D01*
G01X2922562Y904708D02*
Y913763D01*
G01X2924727D02*
Y904708D01*
G01X2925711D02*
Y913763D01*
G01X2927877D02*
Y904708D01*
G01X2928861D02*
Y913763D01*
G01X2931026D02*
Y904708D01*
G01X2927877D02*
X2925711D01*
G01X2931026D02*
X2928861D01*
G01X2924727D02*
X2922562D01*
G01Y913763D02*
X2924727D01*
G01X2925711D02*
X2927877D01*
G01X2928861D02*
X2931026D01*
G01X2899530D02*
Y904708D01*
G01X2900515D02*
Y913763D01*
G01X2902680D02*
Y904708D01*
G01X2903664D02*
Y913763D01*
G01X2905830D02*
Y904708D01*
G01X2906814D02*
Y913763D01*
G01X2908979D02*
Y904708D01*
G01X2909963D02*
Y913763D01*
G01X2912129D02*
Y904708D01*
G01X2913113D02*
Y913763D01*
G01X2915278D02*
Y904708D01*
G01X2916263D02*
Y913763D01*
G01X2918428D02*
Y904708D01*
G01X2919412D02*
Y913763D01*
G01X2921578D02*
Y904708D01*
G01X2918428D02*
X2916263D01*
G01X2921578D02*
X2919412D01*
G01X2915278D02*
X2913113D01*
G01X2908979D02*
X2906814D01*
G01X2912129D02*
X2909963D01*
G01X2905830D02*
X2903664D01*
G01X2902680D02*
X2900515D01*
G01Y913763D02*
X2902680D01*
G01X2903664D02*
X2905830D01*
G01X2906814D02*
X2908979D01*
G01X2909963D02*
X2912129D01*
G01X2913113D02*
X2915278D01*
G01X2916263D02*
X2918428D01*
G01X2919412D02*
X2921578D01*
G01X2935445Y-1124413D02*
Y-1135820D01*
G01X2944000Y-1132018D02*
X2944713Y-1130117D01*
X2946852Y-1129166D01*
X2948991Y-1130117D01*
X2949704Y-1132018D01*
X2948991Y-1133919D01*
X2948278Y-1134870D01*
X2946852Y-1135820D01*
X2945426Y-1134870D01*
X2944713Y-1133919D01*
X2944000Y-1132018D01*
Y-1128215D01*
X2944713Y-1126314D01*
X2945426Y-1125364D01*
X2946852Y-1124413D01*
X2948278Y-1125364D01*
X2948991Y-1126314D01*
G01X2962023Y-231402D02*
Y-225627D01*
G01X2940099Y-231402D02*
Y-222740D01*
G01X2949843D02*
Y-231402D01*
G01X2957151Y-229958D02*
X2956664Y-230680D01*
X2955689Y-231402D01*
X2954715Y-230680D01*
X2953740Y-229236D01*
Y-227793D01*
X2954715Y-226349D01*
X2955689Y-225627D01*
X2956664Y-226349D01*
X2957151Y-227793D01*
X2953740D01*
G01X2949843Y-229236D02*
X2948868Y-230680D01*
X2947894Y-231402D01*
X2946919Y-230680D01*
X2945945Y-229236D01*
Y-227793D01*
X2946919Y-226349D01*
X2947894Y-225627D01*
X2948868Y-226349D01*
X2949843Y-227793D01*
G01X2962023Y-227071D02*
X2962997Y-225627D01*
X2963972D01*
X2964459Y-226349D01*
G01X2964057Y-67734D02*
X2963570Y-68455D01*
X2962595Y-69177D01*
X2961621Y-68455D01*
X2960647Y-67012D01*
Y-65568D01*
X2961621Y-64125D01*
X2962595Y-63403D01*
X2963570Y-64125D01*
X2964057Y-65568D01*
X2960647D01*
G01X2952851Y-63403D02*
X2954800Y-68455D01*
X2954313Y-70621D01*
X2953339Y-72064D01*
X2952364D01*
G01X2939209Y-69177D02*
Y-60516D01*
G01X2948954Y-63403D02*
Y-69177D01*
G01X2954800Y-68455D02*
X2956749Y-63403D01*
G01X2948954Y-67012D02*
X2947980Y-68455D01*
X2947005Y-69177D01*
X2946031Y-68455D01*
X2945056Y-67012D01*
Y-65568D01*
X2946031Y-64125D01*
X2947005Y-63403D01*
X2947980Y-64125D01*
X2948954Y-65568D01*
G01X2946509Y241808D02*
X2946263Y241557D01*
G01X2945676Y254485D02*
X3049601Y215237D01*
G01X2944598Y257464D02*
G03I-6300J0D01*
G01D02*
G03I-6300J0D01*
G01X2942359Y301472D02*
X3052918Y214684D01*
G01X2944598Y304708D02*
G03I-6300J0D01*
G01D02*
G03I-6300J0D01*
G01X2956223Y913763D02*
Y904708D01*
G01X2957207D02*
Y913763D01*
G01X2959373D02*
Y904708D01*
G01X2960357D02*
Y913763D01*
G01X2962522D02*
Y904708D01*
G01X2963507D02*
Y913763D01*
G01X2965672Y904708D02*
X2963507D01*
G01X2959373D02*
X2957207D01*
G01X2962522D02*
X2960357D01*
G01X2957207Y913763D02*
X2959373D01*
G01X2960357D02*
X2962522D01*
G01X2963507D02*
X2965672D01*
G01X2932011Y904708D02*
Y913763D01*
G01X2934176D02*
Y904708D01*
G01X2935160D02*
Y913763D01*
G01X2937326D02*
Y904708D01*
G01X2938310D02*
Y913763D01*
G01X2940475D02*
Y904708D01*
G01X2941459D02*
Y913763D01*
G01X2943625D02*
Y904708D01*
G01X2944609D02*
Y913763D01*
G01X2946774D02*
Y904708D01*
G01X2947759D02*
Y913763D01*
G01X2949924D02*
Y904708D01*
G01X2950908D02*
Y913763D01*
G01X2953074D02*
Y904708D01*
G01X2954058D02*
Y913763D01*
G01X2956223Y904708D02*
X2954058D01*
G01X2949924D02*
X2947759D01*
G01X2953074D02*
X2950908D01*
G01X2946774D02*
X2944609D01*
G01X2943625D02*
X2941459D01*
G01X2937326D02*
X2935160D01*
G01X2940475D02*
X2938310D01*
G01X2934176D02*
X2932011D01*
G01Y913763D02*
X2934176D01*
G01X2935160D02*
X2937326D01*
G01X2938310D02*
X2940475D01*
G01X2941459D02*
X2943625D01*
G01X2944609D02*
X2946774D01*
G01X2947759D02*
X2949924D01*
G01X2950908D02*
X2953074D01*
G01X2954058D02*
X2956223D01*
G01X2944000Y2159695D02*
X2944713Y2161596D01*
X2946852Y2162547D01*
X2948991Y2161596D01*
X2949704Y2159695D01*
X2948991Y2157793D01*
X2948278Y2156843D01*
X2946852Y2155892D01*
X2945426Y2156843D01*
X2944713Y2157793D01*
X2944000Y2159695D01*
Y2163497D01*
X2944713Y2165399D01*
X2945426Y2166349D01*
X2946852Y2167300D01*
X2948278Y2166349D01*
X2948991Y2165399D01*
G01X2935445Y2167300D02*
Y2155892D01*
G01X2996615Y-222740D02*
Y-231402D01*
G01Y-229236D02*
X2995640Y-230680D01*
X2994666Y-231402D01*
X2993691Y-230680D01*
X2992717Y-229236D01*
Y-227793D01*
X2993691Y-226349D01*
X2994666Y-225627D01*
X2995640Y-226349D01*
X2996615Y-227793D01*
G01X2981024Y-224184D02*
X2980537Y-223462D01*
X2979562Y-222740D01*
X2978588D01*
X2977613Y-223462D01*
X2977126Y-224184D01*
Y-224906D01*
X2977613Y-225627D01*
X2978588Y-226349D01*
X2980537Y-227793D01*
X2981024Y-228515D01*
Y-229958D01*
X2980537Y-230680D01*
X2979562Y-231402D01*
X2978588D01*
X2977613Y-230680D01*
X2976639Y-229236D01*
G01X2986870Y-225627D02*
Y-231402D01*
G01Y-222740D02*
Y-223462D01*
G01X2977699Y-60516D02*
X2978673Y-61960D01*
X2979160Y-64125D01*
Y-65568D01*
X2978673Y-67734D01*
X2977699Y-69177D01*
G01X2968929D02*
Y-63403D01*
G01Y-64847D02*
X2969904Y-63403D01*
X2970878D01*
X2971365Y-64125D01*
G01X2990869Y913763D02*
Y904708D01*
G01X2991853D02*
Y913763D01*
G01X2994019D02*
Y904708D01*
G01X2995003D02*
Y913763D01*
G01X2997168D02*
Y904708D01*
G01X2998152D02*
Y913763D01*
G01X2997168Y904708D02*
X2995003D01*
G01X3000318D02*
X2998152D01*
G01X2994019D02*
X2991853D01*
G01Y913763D02*
X2994019D01*
G01X2995003D02*
X2997168D01*
G01X2998152D02*
X3000318D01*
G01X2965672D02*
Y904708D01*
G01X2966656D02*
Y913763D01*
G01X2968822D02*
Y904708D01*
G01X2969806D02*
Y913763D01*
G01X2971971D02*
Y904708D01*
G01X2972956D02*
Y913763D01*
G01X2975121D02*
Y904708D01*
G01X2976105D02*
Y913763D01*
G01X2978270D02*
Y904708D01*
G01X2979255D02*
Y913763D01*
G01X2981420D02*
Y904708D01*
G01X2982404D02*
Y913763D01*
G01X2984570D02*
Y904708D01*
G01X2985554D02*
Y913763D01*
G01X2987719D02*
Y904708D01*
G01X2988704D02*
Y913763D01*
G01X2987719Y904708D02*
X2985554D01*
G01X2990869D02*
X2988704D01*
G01X2984570D02*
X2982404D01*
G01X2978270D02*
X2976105D01*
G01X2981420D02*
X2979255D01*
G01X2975121D02*
X2972956D01*
G01X2968822D02*
X2966656D01*
G01X2971971D02*
X2969806D01*
G01X2966656Y913763D02*
X2968822D01*
G01X2969806D02*
X2971971D01*
G01X2972956D02*
X2975121D01*
G01X2976105D02*
X2978270D01*
G01X2979255D02*
X2981420D01*
G01X2982404D02*
X2984570D01*
G01X2985554D02*
X2987719D01*
G01X2988704D02*
X2990869D01*
G01X3003922Y-229958D02*
X3003435Y-230680D01*
X3002461Y-231402D01*
X3001486Y-230680D01*
X3000512Y-229236D01*
Y-227793D01*
X3001486Y-226349D01*
X3002461Y-225627D01*
X3003435Y-226349D01*
X3003922Y-227793D01*
X3000512D01*
G01X3015770Y866913D02*
Y892897D01*
G01Y866913D02*
Y892897D01*
G01X3050582Y861795D02*
X3020889D01*
G01X3015770Y866913D02*
G03X3020889Y861795I5118J0D01*
G01X3015770Y866913D02*
G03X3020889Y861795I5118J0D01*
G01X3005803Y903824D02*
X3005926Y903866D01*
G01Y902987D02*
X3005803Y902945D01*
G01X3005598Y903070D02*
X3005680Y903112D01*
G01X3005598Y903950D02*
X3005762Y904075D01*
G01X3004860Y902484D02*
X3005106Y902777D01*
G01Y902442D02*
X3004860Y902149D01*
G01X3005721Y903740D02*
X3005803Y903824D01*
G01Y902945D02*
X3005721Y902861D01*
G01X3005475Y903782D02*
X3005598Y903950D01*
G01X3005475Y902903D02*
X3005598Y903070D01*
G01X3005434Y903657D02*
X3005475Y903782D01*
G01X3005680Y903615D02*
X3005721Y903740D01*
G01X3005434Y902777D02*
X3005475Y902903D01*
G01X3005721Y902861D02*
X3005680Y902735D01*
G01X3000318Y913763D02*
Y904708D01*
G01X3001302D02*
Y913763D01*
G01X3003467D02*
Y904708D01*
G01X3004452D02*
Y913763D01*
G01X3004614Y902149D02*
Y904118D01*
G01X3004860D02*
Y902484D01*
G01X3005106Y902777D02*
Y902442D01*
G01X3005434Y902610D02*
Y902777D01*
G01Y903447D02*
Y903657D01*
G01X3005680Y902735D02*
Y902651D01*
G01Y903489D02*
Y903615D01*
G01X3006617Y913763D02*
Y904708D01*
G01X3006706Y903866D02*
Y903238D01*
G01Y902400D02*
Y902987D01*
G01X3006952Y904118D02*
Y902149D01*
G01X3008684Y896834D02*
Y913763D01*
G01Y896834D02*
Y913763D01*
G01X3005475Y902484D02*
X3005434Y902610D01*
G01X3005680Y902651D02*
X3005721Y902526D01*
G01X3005475Y903322D02*
X3005434Y903447D01*
G01X3005721Y903364D02*
X3005680Y903489D01*
G01X3004747Y918881D02*
X3008684Y913763D01*
G01X3004747Y918881D02*
X3008684Y913763D01*
G01X3005598Y902316D02*
X3005475Y902484D01*
G01X3005598Y903154D02*
X3005475Y903322D01*
G01X3005762Y904075D02*
X3005967Y904118D01*
G01X3013802Y894866D02*
X3010652D01*
G01X3013802D02*
X3010652D01*
G01X3006952Y902149D02*
X3005967D01*
G01X3004860D02*
X3004614D01*
G01X3005926Y902400D02*
X3006706D01*
G01Y902987D02*
X3005926D01*
G01X3006706Y903238D02*
X3005926D01*
G01Y903866D02*
X3006706D01*
G01X3005967Y904118D02*
X3006952D01*
G01X3004614D02*
X3004860D01*
G01X3006617Y904708D02*
X3004452D01*
G01X3003467D02*
X3001302D01*
G01Y913763D02*
X3003467D01*
G01X3004452D02*
X3006617D01*
G01X3005762Y902191D02*
X3005598Y902316D01*
G01X3005721Y902526D02*
X3005803Y902442D01*
G01Y903280D02*
X3005721Y903364D01*
G01X3005967Y902149D02*
X3005762Y902191D01*
G01X3005803Y902442D02*
X3005926Y902400D01*
G01Y903238D02*
X3005803Y903280D01*
G01X3005680Y903112D02*
X3005598Y903154D01*
G01X3008684Y896834D02*
G03X3010652Y894866I1968J0D01*
G01X3015770Y892897D02*
G03X3013802Y894866I-1969J0D01*
G01X3008684Y896834D02*
G03X3010652Y894866I1968J0D01*
G01X3015770Y892897D02*
G03X3013802Y894866I-1969J0D01*
G01X3047617Y-1120610D02*
Y-1139623D01*
G01X3063666Y210906D02*
X3063178D01*
Y211628D01*
X3063666Y210906D01*
G01X3069287Y217571D02*
X3068800Y218293D01*
X3067826Y219015D01*
X3066852D01*
X3065877Y218293D01*
X3065390Y217571D01*
Y216849D01*
X3065877Y216127D01*
X3066852Y215406D01*
X3067826Y214684D01*
X3068800Y213962D01*
X3069287Y213240D01*
Y211797D01*
X3068800Y211075D01*
X3067826Y210353D01*
X3066852D01*
X3065877Y211075D01*
X3064903Y212519D01*
G01X3052918Y214684D02*
X3063441D01*
G01X3049601Y215237D02*
X3059768D01*
G01X3050582Y861795D02*
Y647228D01*
G01D02*
X3156881D01*
G01X3070267Y842110D02*
G03X3050582Y861795I-19685J0D01*
G01X3047617Y2171102D02*
Y2152090D01*
G01X3088218Y239011D02*
X3087731D01*
Y239733D01*
X3088218Y239011D01*
G01X3081468Y216127D02*
X3082930Y210353D01*
X3084391Y216127D01*
G01X3077083D02*
Y210353D01*
G01X3092186Y211797D02*
X3091699Y211075D01*
X3090724Y210353D01*
X3089750Y211075D01*
X3088776Y212519D01*
Y213962D01*
X3089750Y215406D01*
X3090724Y216127D01*
X3091699Y215406D01*
X3092186Y213962D01*
X3088776D01*
G01X3077083Y212519D02*
X3076108Y211075D01*
X3075134Y210353D01*
X3074159Y211075D01*
X3073185Y212519D01*
Y213962D01*
X3074159Y215406D01*
X3075134Y216127D01*
X3076108Y215406D01*
X3077083Y213962D01*
G01X3098810Y656367D02*
X3094873D01*
G01Y657372D02*
X3098810D01*
G01Y659382D02*
X3094873D01*
G01Y660387D02*
X3098810D01*
G01X3091428Y664157D02*
X3092905D01*
G01X3091428Y659382D02*
Y664157D01*
G01X3094873Y659382D02*
Y660387D01*
G01Y656367D02*
Y657372D01*
G01X3098810Y660387D02*
Y659382D01*
G01Y657372D02*
Y656367D01*
G01X3092905Y652346D02*
X3091428D01*
G01D02*
Y657874D01*
G01X3092905Y664157D02*
Y652346D01*
G01X3070267Y671913D02*
Y842110D01*
G01X3084539Y664157D02*
Y659382D01*
G01X3091428Y657874D02*
X3084539D01*
G01Y659382D02*
X3091428D01*
G01X3083062Y664157D02*
X3084539D01*
G01X3075267Y666913D02*
X3132196D01*
G01X3070267Y671913D02*
G03X3075267Y666913I5000J0D01*
G01X3083062Y652346D02*
Y664157D01*
G01X3084539Y657874D02*
Y652346D01*
G01D02*
X3083062D01*
G01X3104854Y215406D02*
X3107777D01*
G01X3112649D02*
X3113623Y216127D01*
G01D02*
X3114598D01*
X3115572Y214684D01*
Y210353D01*
G01X3106315D02*
Y219015D01*
G01X3112649Y210353D02*
Y219015D01*
G01X3123367Y211797D02*
X3122880Y211075D01*
X3121906Y210353D01*
X3120931Y211075D01*
X3119957Y212519D01*
Y213962D01*
X3120931Y215406D01*
X3121906Y216127D01*
X3122880Y215406D01*
X3123367Y213962D01*
X3119957D01*
G01X3135621Y285023D02*
X3130700D01*
G01D02*
Y324393D01*
G01D02*
X3135621D01*
G01X3124401Y660136D02*
X3125139Y660387D01*
G01Y659382D02*
X3124401Y659131D01*
G01X3128338Y660136D02*
X3129076Y660387D01*
G01X3128830Y659382D02*
X3128338Y659131D01*
G01X3127600Y659382D02*
X3128338Y660136D01*
G01Y659131D02*
X3128092Y658880D01*
G01D02*
X3127846Y658377D01*
G01X3129568Y659382D02*
X3128830D01*
G01X3125631D02*
X3125139D01*
G01Y660387D02*
X3126123D01*
G01X3129076D02*
X3130060D01*
G01X3126123D02*
X3126861Y660136D01*
G01X3130060Y660387D02*
X3130798Y660136D01*
G01X3126123Y659131D02*
X3125631Y659382D01*
G01X3130060Y659131D02*
X3129568Y659382D01*
G01X3126369Y658880D02*
X3126123Y659131D01*
G01X3126861Y660136D02*
X3127600Y659382D01*
G01X3130306Y658880D02*
X3130060Y659131D01*
G01X3130798Y660136D02*
X3131291Y659634D01*
G01X3126615Y658377D02*
X3126369Y658880D01*
G01X3130552Y658377D02*
X3130306Y658880D01*
G01X3131291Y659634D02*
X3131783Y658377D01*
G01X3132196Y666913D02*
G03X3137196Y671913I0J5000D01*
G01X3131783Y652346D02*
X3130552D01*
G01X3127846D02*
X3126615D01*
G01D02*
Y658377D01*
G01X3127846D02*
Y652346D01*
G01X3130552D02*
Y658377D01*
G01X3131783D02*
Y652346D01*
G01X3113328Y660136D02*
X3114066Y660387D01*
G01Y659382D02*
X3113328Y659131D01*
G01X3117265Y660136D02*
X3118003Y660387D01*
G01X3103731Y663906D02*
X3102501Y663152D01*
G01X3117757Y659382D02*
X3117265Y659131D01*
G01X3103978Y662649D02*
X3103239Y662146D01*
G01X3106438Y653854D02*
X3107176Y654356D01*
G01X3106684Y652597D02*
X3107915Y653351D01*
G01X3102501Y663152D02*
X3101763Y662398D01*
G01X3112836Y659634D02*
X3113328Y660136D01*
G01Y659131D02*
X3112836Y658628D01*
G01X3107915Y653351D02*
X3108653Y654105D01*
G01X3116527Y659382D02*
X3117265Y660136D01*
G01Y659131D02*
X3117019Y658880D01*
G01X3123909Y659634D02*
X3124401Y660136D01*
G01Y659131D02*
X3123909Y658628D01*
G01X3103239Y662146D02*
X3102255Y660639D01*
G01X3107176Y654356D02*
X3108161Y655864D01*
G01X3101271Y661393D02*
X3101025Y660639D01*
G01X3101763Y662398D02*
X3101271Y661393D01*
G01X3108653Y654105D02*
X3109145Y655110D01*
G01X3117019Y658880D02*
X3116773Y658377D01*
G01X3105208Y653602D02*
X3106438Y653854D01*
G01X3105208Y662900D02*
X3103978Y662649D01*
G01X3105208Y664157D02*
X3103731Y663906D01*
G01X3102255Y660639D02*
X3102009Y659131D01*
G01X3108161Y655864D02*
X3108407Y657372D01*
G01X3101025Y660639D02*
X3100779Y659382D01*
G01X3109391Y655864D02*
X3109637Y657121D01*
G01X3109145Y655110D02*
X3109391Y655864D01*
G01X3118495Y659382D02*
X3117757D01*
G01X3114558D02*
X3114066D01*
G01Y660387D02*
X3115050D01*
G01X3111606D02*
X3112836D01*
G01X3118003D02*
X3118987D01*
G01X3122678D02*
X3123909D01*
G01X3100779Y659382D02*
Y657121D01*
G01X3102009Y659131D02*
Y657372D01*
G01X3108407D02*
Y659131D01*
G01X3109637Y657121D02*
Y659382D01*
G01X3112836Y660387D02*
Y659634D01*
G01X3123909Y660387D02*
Y659634D01*
G01X3106684Y663906D02*
X3105208Y664157D01*
G01X3103978Y653854D02*
X3105208Y653602D01*
G01X3106438Y662649D02*
X3105208Y662900D01*
G01X3115050Y660387D02*
X3115789Y660136D01*
G01X3118987Y660387D02*
X3119726Y660136D01*
G01X3100779Y657121D02*
X3101025Y655864D01*
G01X3102009Y657372D02*
X3102255Y655864D01*
G01X3108407Y659131D02*
X3108161Y660639D01*
G01X3115050Y659131D02*
X3114558Y659382D01*
G01X3118987Y659131D02*
X3118495Y659382D01*
G01X3102501Y653351D02*
X3103731Y652597D01*
G01X3107915Y663152D02*
X3106684Y663906D01*
G01X3103239Y654356D02*
X3103978Y653854D01*
G01X3107176Y662146D02*
X3106438Y662649D01*
G01X3101763Y654105D02*
X3102501Y653351D01*
G01X3108653Y662398D02*
X3107915Y663152D01*
G01X3115296Y658880D02*
X3115050Y659131D01*
G01X3115789Y660136D02*
X3116527Y659382D01*
G01X3119233Y658880D02*
X3118987Y659131D01*
G01X3119726Y660136D02*
X3120218Y659634D01*
G01X3102255Y655864D02*
X3103239Y654356D01*
G01X3108161Y660639D02*
X3107176Y662146D01*
G01X3101271Y655110D02*
X3101763Y654105D01*
G01X3109145Y661393D02*
X3108653Y662398D01*
G01X3115543Y658377D02*
X3115296Y658880D01*
G01X3119480Y658377D02*
X3119233Y658880D01*
G01X3120218Y659634D02*
X3120710Y658377D01*
G01X3101025Y655864D02*
X3101271Y655110D01*
G01X3109391Y660639D02*
X3109145Y661393D01*
G01X3109637Y659382D02*
X3109391Y660639D01*
G01X3105208Y652346D02*
X3106684Y652597D01*
G01X3123909Y652346D02*
X3122678D01*
G01X3120710D02*
X3119480D01*
G01X3116773D02*
X3115543D01*
G01X3112836D02*
X3111606D01*
G01D02*
Y660387D01*
G01X3112836Y658628D02*
Y652346D01*
G01X3115543D02*
Y658377D01*
G01X3116773D02*
Y652346D01*
G01X3119480D02*
Y658377D01*
G01X3120710D02*
Y652346D01*
G01X3122678D02*
Y660387D01*
G01X3123909Y658628D02*
Y652346D01*
G01X3103731Y652597D02*
X3105208Y652346D01*
G01X3167393Y-1135820D02*
X3168106Y-1131067D01*
X3168819Y-1128215D01*
X3169532Y-1126314D01*
X3170245Y-1124413D01*
X3164541D01*
G01X3155986D02*
Y-1135820D01*
G01X3167216Y215406D02*
X3168190Y216127D01*
G01X3167216Y210353D02*
Y219015D01*
G01X3136035Y215406D02*
X3138958D01*
G01X3137496Y210353D02*
Y219015D01*
G01X3155035Y212519D02*
X3154061Y211075D01*
X3153087Y210353D01*
X3152112Y211075D01*
X3151138Y212519D01*
Y213962D01*
X3152112Y215406D01*
X3153087Y216127D01*
X3154061Y215406D01*
X3155035Y213962D01*
Y212519D01*
G01X3142856Y216127D02*
X3143830Y210353D01*
X3145291Y216127D01*
X3146266Y210353D01*
X3147728Y216127D01*
G01X3163508Y285023D02*
X3158587D01*
G01D02*
Y303451D01*
G01Y308477D02*
Y324393D01*
G01X3163508D02*
Y285023D01*
G01X3158587Y303451D02*
X3135621D01*
G01Y308477D02*
X3158587D01*
G01X3135621Y324393D02*
Y308477D01*
G01Y303451D02*
Y285023D01*
G01X3158587Y324393D02*
X3163508D01*
G01X3156881Y647228D02*
Y861795D01*
G01X3137196Y671913D02*
Y842110D01*
G01X3156881Y861795D02*
G03X3137196Y842110I0J-19685D01*
G01X3166952Y892897D02*
Y866913D01*
G01Y892897D02*
Y866913D01*
G01X3161833Y861795D02*
G03X3166952Y866913I1J5118D01*
G01X3161833Y861795D02*
G03X3166952Y866913I1J5118D01*
G01X3161833Y861795D02*
X3156881D01*
G01D02*
X3544511D01*
G01X3168920Y894866D02*
G03X3166952Y892897I1J-1969D01*
G01X3168920Y894866D02*
G03X3166952Y892897I1J-1969D01*
G01X3167393Y2155892D02*
X3168106Y2160645D01*
X3168819Y2163497D01*
G01X3155986Y2167300D02*
Y2155892D01*
G01X3168819Y2163497D02*
X3170245Y2167300D01*
X3164541D01*
G01X3200833Y215406D02*
X3200346Y216127D01*
X3199371D01*
X3198884Y215406D01*
Y214684D01*
X3200833Y213240D01*
G01D02*
X3201320Y212519D01*
Y211797D01*
G01D02*
X3200346Y210353D01*
X3199371D01*
X3198397Y211797D01*
G01X3168190Y216127D02*
X3169165D01*
X3170139Y214684D01*
Y210353D01*
G01X3193525Y211797D02*
X3193037Y211075D01*
X3192063Y210353D01*
X3191089Y211075D01*
X3190114Y212519D01*
Y213962D01*
X3191089Y215406D01*
X3192063Y216127D01*
X3193037Y215406D01*
X3193525Y213962D01*
X3190114D01*
G01X3178421Y212519D02*
X3177447Y211075D01*
X3176472Y210353D01*
X3175498Y211075D01*
X3174524Y212519D01*
Y213962D01*
X3175498Y215406D01*
X3176472Y216127D01*
X3177447Y215406D01*
X3178421Y213962D01*
Y212519D01*
G01X3184268Y210353D02*
Y219015D01*
G01X3203698Y285023D02*
X3198777D01*
G01D02*
Y317692D01*
G01X3175811Y305127D02*
X3187294Y299263D01*
G01X3185654Y296750D02*
X3170070Y305127D01*
G01D02*
X3185654Y313503D01*
G01X3187294Y310990D02*
X3175811Y305127D01*
G01X3187294Y299263D02*
X3185654Y296750D01*
G01X3198777Y324393D02*
X3203698D01*
G01X3193856Y318529D02*
X3198777Y324393D01*
G01X3193856Y311828D02*
Y318529D01*
G01X3198777Y317692D02*
X3193856Y311828D01*
G01X3185654Y313503D02*
X3187294Y310990D01*
G01X3191853Y913763D02*
Y904708D01*
G01X3194019D02*
Y913763D01*
G01X3195003D02*
Y904708D01*
G01X3197168D02*
Y913763D01*
G01X3198152D02*
Y904708D01*
G01X3200318D02*
Y913763D01*
G01X3195003Y904708D02*
X3197168D01*
G01X3191853D02*
X3194019D01*
G01X3198152D02*
X3200318D01*
G01Y913763D02*
X3198152D01*
G01X3197168D02*
X3195003D01*
G01X3194019D02*
X3191853D01*
G01X3177832Y903824D02*
X3177927Y903866D01*
G01Y902987D02*
X3177832Y902945D01*
G01X3177673Y903070D02*
X3177736Y903112D01*
G01X3174521Y903866D02*
X3174426Y903782D01*
G01X3175922Y903866D02*
X3175826Y903782D01*
G01X3174839Y902400D02*
X3174935Y902484D01*
G01X3176240Y902400D02*
X3176335Y902484D01*
G01X3174489Y904075D02*
X3174330Y903950D01*
G01X3175890Y904075D02*
X3175731Y903950D01*
G01X3174871Y902191D02*
X3175030Y902316D01*
G01X3176272Y902191D02*
X3176431Y902316D01*
G01X3177673Y903950D02*
X3177800Y904075D01*
G01X3174330Y903950D02*
X3174235Y903824D01*
G01X3175731Y903950D02*
X3175635Y903824D01*
G01X3175030Y902316D02*
X3175126Y902442D01*
G01X3176431Y902316D02*
X3176527Y902442D01*
G01X3177768Y903740D02*
X3177832Y903824D01*
G01Y902945D02*
X3177768Y902861D01*
G01X3174038Y913763D02*
X3177975Y918881D01*
G01X3174038Y913763D02*
X3177975Y918881D01*
G01X3177577Y903782D02*
X3177673Y903950D01*
G01X3177577Y902903D02*
X3177673Y903070D01*
G01X3177100Y902484D02*
X3177291Y902777D01*
G01Y902442D02*
X3177100Y902149D01*
G01X3174426Y903782D02*
X3174298Y903531D01*
G01X3174935Y902484D02*
X3175062Y902735D01*
G01X3175826Y903782D02*
X3175699Y903531D01*
G01X3176335Y902484D02*
X3176463Y902735D01*
G01X3174235Y903824D02*
X3174171Y903657D01*
G01X3175635Y903824D02*
X3175572Y903657D01*
G01X3175126Y902442D02*
X3175190Y902610D01*
G01X3176527Y902442D02*
X3176590Y902610D01*
G01X3174171Y903657D02*
X3174139Y903531D01*
G01X3175190Y902610D02*
X3175221Y902735D01*
G01X3175572Y903657D02*
X3175540Y903531D01*
G01X3176590Y902610D02*
X3176622Y902735D01*
G01X3177545Y903657D02*
X3177577Y903782D01*
G01X3177736Y903615D02*
X3177768Y903740D01*
G01X3177545Y902777D02*
X3177577Y902903D01*
G01X3177768Y902861D02*
X3177736Y902735D01*
G01X3174298Y903531D02*
X3174267Y903280D01*
G01X3175062Y902735D02*
X3175094Y902987D01*
G01X3175699Y903531D02*
X3175667Y903280D01*
G01X3176463Y902735D02*
X3176495Y902987D01*
G01X3174139Y903531D02*
X3174107Y903322D01*
G01X3175221Y902735D02*
X3175253Y902945D01*
G01X3175540Y903531D02*
X3175508Y903322D01*
G01X3176622Y902735D02*
X3176654Y902945D01*
G01X3174038Y913763D02*
Y896834D01*
G01Y913763D02*
Y896834D01*
G01X3174107Y903322D02*
Y902945D01*
G01X3174267Y903280D02*
Y902987D01*
G01X3175094D02*
Y903280D01*
G01X3175253Y902945D02*
Y903322D01*
G01X3175508D02*
Y902945D01*
G01X3175667Y903280D02*
Y902987D01*
G01X3176105Y913763D02*
Y904708D01*
G01X3176495Y902987D02*
Y903280D01*
G01X3176654Y902945D02*
Y903322D01*
G01X3176909Y902149D02*
Y904118D01*
G01X3177100D02*
Y902484D01*
G01X3177291Y902777D02*
Y902442D01*
G01X3177545Y902610D02*
Y902777D01*
G01Y903447D02*
Y903657D01*
G01X3177736Y902735D02*
Y902651D01*
G01Y903489D02*
Y903615D01*
G01X3178270Y904708D02*
Y913763D01*
G01X3178532Y903866D02*
Y903238D01*
G01Y902400D02*
Y902987D01*
G01X3178723Y904118D02*
Y902149D01*
G01X3179255Y913763D02*
Y904708D01*
G01X3181420D02*
Y913763D01*
G01X3182404D02*
Y904708D01*
G01X3184570D02*
Y913763D01*
G01X3185554D02*
Y904708D01*
G01X3187719D02*
Y913763D01*
G01X3188704D02*
Y904708D01*
G01X3190869D02*
Y913763D01*
G01X3176081Y902358D02*
X3176240Y902400D01*
G01X3174680Y902358D02*
X3174839Y902400D01*
G01X3177800Y904075D02*
X3177959Y904118D01*
G01X3176081Y903908D02*
X3175922Y903866D01*
G01X3174680Y903908D02*
X3174521Y903866D01*
G01X3176081Y902149D02*
X3176272Y902191D01*
G01X3174680Y902149D02*
X3174871Y902191D01*
G01X3176081Y904118D02*
X3175890Y904075D01*
G01X3174680Y904118D02*
X3174489Y904075D01*
G01X3174107Y902945D02*
X3174139Y902735D01*
G01X3175253Y903322D02*
X3175221Y903531D01*
G01X3175508Y902945D02*
X3175540Y902735D01*
G01X3176654Y903322D02*
X3176622Y903531D01*
G01X3174267Y902987D02*
X3174298Y902735D01*
G01X3175094Y903280D02*
X3175062Y903531D01*
G01X3175667Y902987D02*
X3175699Y902735D01*
G01X3176495Y903280D02*
X3176463Y903531D01*
G01X3172070Y894866D02*
X3168920D01*
G01X3172070D02*
X3168920D01*
G01X3178723Y902149D02*
X3177959D01*
G01X3177100D02*
X3176909D01*
G01X3177927Y902400D02*
X3178532D01*
G01Y902987D02*
X3177927D01*
G01X3178532Y903238D02*
X3177927D01*
G01Y903866D02*
X3178532D01*
G01X3176909Y904118D02*
X3177100D01*
G01X3177959D02*
X3178723D01*
G01X3176105Y904708D02*
X3178270D01*
G01X3179255D02*
X3181420D01*
G01X3185554D02*
X3187719D01*
G01X3182404D02*
X3184570D01*
G01X3188704D02*
X3190869D01*
G01Y913763D02*
X3188704D01*
G01X3187719D02*
X3185554D01*
G01X3184570D02*
X3182404D01*
G01X3181420D02*
X3179255D01*
G01X3178270D02*
X3176105D01*
G01X3174038D02*
X3353959D01*
G01X3174171Y902610D02*
X3174235Y902442D01*
G01X3175572Y902610D02*
X3175635Y902442D01*
G01X3175190Y903657D02*
X3175126Y903824D01*
G01X3176590Y903657D02*
X3176527Y903824D01*
G01X3174139Y902735D02*
X3174171Y902610D01*
G01X3175221Y903531D02*
X3175190Y903657D01*
G01X3175540Y902735D02*
X3175572Y902610D01*
G01X3176622Y903531D02*
X3176590Y903657D01*
G01X3177577Y902484D02*
X3177545Y902610D01*
G01X3177736Y902651D02*
X3177768Y902526D01*
G01X3177577Y903322D02*
X3177545Y903447D01*
G01X3177768Y903364D02*
X3177736Y903489D01*
G01X3174489Y902191D02*
X3174680Y902149D01*
G01X3175890Y902191D02*
X3176081Y902149D01*
G01X3174871Y904075D02*
X3174680Y904118D01*
G01X3176272Y904075D02*
X3176081Y904118D01*
G01X3174521Y902400D02*
X3174680Y902358D01*
G01X3175922Y902400D02*
X3176081Y902358D01*
G01X3177959Y902149D02*
X3177800Y902191D01*
G01X3174839Y903866D02*
X3174680Y903908D01*
G01X3176240Y903866D02*
X3176081Y903908D01*
G01X3177673Y902316D02*
X3177577Y902484D01*
G01X3177673Y903154D02*
X3177577Y903322D01*
G01X3174298Y902735D02*
X3174426Y902484D01*
G01X3175062Y903531D02*
X3174935Y903782D01*
G01X3175699Y902735D02*
X3175826Y902484D01*
G01X3176463Y903531D02*
X3176335Y903782D01*
G01X3177832Y902442D02*
X3177927Y902400D01*
G01Y903238D02*
X3177832Y903280D01*
G01X3177736Y903112D02*
X3177673Y903154D01*
G01X3174330Y902316D02*
X3174489Y902191D01*
G01X3175731Y902316D02*
X3175890Y902191D01*
G01X3175030Y903950D02*
X3174871Y904075D01*
G01X3176431Y903950D02*
X3176272Y904075D01*
G01X3174426Y902484D02*
X3174521Y902400D01*
G01X3175826Y902484D02*
X3175922Y902400D01*
G01X3174935Y903782D02*
X3174839Y903866D01*
G01X3176335Y903782D02*
X3176240Y903866D01*
G01X3177800Y902191D02*
X3177673Y902316D01*
G01X3174235Y902442D02*
X3174330Y902316D01*
G01X3175635Y902442D02*
X3175731Y902316D01*
G01X3175126Y903824D02*
X3175030Y903950D01*
G01X3176527Y903824D02*
X3176431Y903950D01*
G01X3177768Y902526D02*
X3177832Y902442D01*
G01Y903280D02*
X3177768Y903364D01*
G01X3172070Y894866D02*
G03X3174038Y896834I0J1968D01*
G01X3172070Y894866D02*
G03X3174038Y896834I0J1968D01*
G01X3350022Y918881D02*
X3177975D01*
G01D02*
X3350022D01*
G01X3231885Y-1115412D02*
X3230910Y-1114690D01*
X3230423Y-1113969D01*
X3229936Y-1112525D01*
Y-1109638D01*
X3230423Y-1108194D01*
X3230910Y-1107473D01*
X3231885Y-1106751D01*
X3232859Y-1107473D01*
X3233346Y-1108194D01*
X3233833Y-1109638D01*
Y-1112525D01*
X3233346Y-1113969D01*
X3232859Y-1114690D01*
X3231885Y-1115412D01*
G01X3218243Y-1106751D02*
X3215320D01*
X3214833Y-1110360D01*
X3215807Y-1109638D01*
X3216781D01*
X3217756Y-1110360D01*
X3218243Y-1111081D01*
X3218730Y-1112525D01*
X3218243Y-1113969D01*
X3217756Y-1114690D01*
X3216781Y-1115412D01*
X3215807D01*
X3214833Y-1114690D01*
X3214345Y-1113969D01*
G01X3208499Y-1106751D02*
Y-1115412D01*
G01X3224090Y-1106751D02*
Y-1115412D01*
G01X3231885Y-1089428D02*
X3230910Y-1088706D01*
X3230423Y-1087984D01*
X3229936Y-1086541D01*
Y-1083654D01*
X3230423Y-1082210D01*
X3230910Y-1081488D01*
X3231885Y-1080766D01*
X3232859Y-1081488D01*
X3233346Y-1082210D01*
X3233833Y-1083654D01*
Y-1086541D01*
X3233346Y-1087984D01*
X3232859Y-1088706D01*
X3231885Y-1089428D01*
G01Y-1076436D02*
X3230910Y-1075714D01*
X3230423Y-1074992D01*
X3229936Y-1073549D01*
Y-1070662D01*
X3230423Y-1069218D01*
X3230910Y-1068496D01*
X3231885Y-1067774D01*
X3232859Y-1068496D01*
X3233346Y-1069218D01*
X3233833Y-1070662D01*
Y-1073549D01*
X3233346Y-1074992D01*
X3232859Y-1075714D01*
X3231885Y-1076436D01*
G01Y-1102420D02*
X3230910Y-1101698D01*
X3230423Y-1100977D01*
X3229936Y-1099533D01*
Y-1096646D01*
X3230423Y-1095202D01*
X3230910Y-1094481D01*
X3231885Y-1093758D01*
X3232859Y-1094481D01*
X3233346Y-1095202D01*
X3233833Y-1096646D01*
Y-1099533D01*
X3233346Y-1100977D01*
X3232859Y-1101698D01*
X3231885Y-1102420D01*
G01X3218243Y-1080766D02*
X3215320D01*
X3214833Y-1084375D01*
X3215807Y-1083654D01*
X3216781D01*
X3217756Y-1084375D01*
X3218243Y-1085097D01*
X3218730Y-1086541D01*
X3218243Y-1087984D01*
X3217756Y-1088706D01*
X3216781Y-1089428D01*
X3215807D01*
X3214833Y-1088706D01*
X3214345Y-1087984D01*
G01X3218243Y-1067774D02*
X3215320D01*
X3214833Y-1071383D01*
X3215807Y-1070662D01*
X3216781D01*
X3217756Y-1071383D01*
X3218243Y-1072105D01*
X3218730Y-1073549D01*
X3218243Y-1074992D01*
X3217756Y-1075714D01*
X3216781Y-1076436D01*
X3215807D01*
X3214833Y-1075714D01*
X3214345Y-1074992D01*
G01X3208499Y-1067774D02*
Y-1076436D01*
G01Y-1080766D02*
Y-1089428D01*
G01X3224090Y-1067774D02*
Y-1076436D01*
G01Y-1080766D02*
Y-1089428D01*
G01X3218243Y-1093758D02*
X3215320D01*
X3214833Y-1097368D01*
X3215807Y-1096646D01*
X3216781D01*
X3217756Y-1097368D01*
X3218243Y-1098089D01*
X3218730Y-1099533D01*
X3218243Y-1100977D01*
X3217756Y-1101698D01*
X3216781Y-1102420D01*
X3215807D01*
X3214833Y-1101698D01*
X3214345Y-1100977D01*
G01X3208499Y-1093758D02*
Y-1102420D01*
G01X3224090Y-1093758D02*
Y-1102420D01*
G01X3231885Y-1063444D02*
X3230910Y-1062722D01*
X3230423Y-1062000D01*
X3229936Y-1060557D01*
Y-1057670D01*
X3230423Y-1056226D01*
X3230910Y-1055504D01*
X3231885Y-1054782D01*
X3232859Y-1055504D01*
X3233346Y-1056226D01*
X3233833Y-1057670D01*
Y-1060557D01*
X3233346Y-1062000D01*
X3232859Y-1062722D01*
X3231885Y-1063444D01*
G01Y-1050451D02*
X3230910Y-1049730D01*
X3230423Y-1049008D01*
X3229936Y-1047564D01*
Y-1044677D01*
X3230423Y-1043234D01*
X3230910Y-1042512D01*
X3231885Y-1041790D01*
X3232859Y-1042512D01*
X3233346Y-1043234D01*
X3233833Y-1044677D01*
Y-1047564D01*
X3233346Y-1049008D01*
X3232859Y-1049730D01*
X3231885Y-1050451D01*
G01X3218243Y-1054782D02*
X3215320D01*
X3214833Y-1058391D01*
X3215807Y-1057670D01*
X3216781D01*
X3217756Y-1058391D01*
X3218243Y-1059113D01*
X3218730Y-1060557D01*
X3218243Y-1062000D01*
X3217756Y-1062722D01*
X3216781Y-1063444D01*
X3215807D01*
X3214833Y-1062722D01*
X3214345Y-1062000D01*
G01X3218243Y-1041790D02*
X3215320D01*
X3214833Y-1045399D01*
X3215807Y-1044677D01*
X3216781D01*
X3217756Y-1045399D01*
X3218243Y-1046121D01*
X3218730Y-1047564D01*
X3218243Y-1049008D01*
X3217756Y-1049730D01*
X3216781Y-1050451D01*
X3215807D01*
X3214833Y-1049730D01*
X3214345Y-1049008D01*
G01X3208499Y-1041790D02*
Y-1050451D01*
G01Y-1054782D02*
Y-1063444D01*
G01X3224090Y-1041790D02*
Y-1050451D01*
G01Y-1054782D02*
Y-1063444D01*
G01X3231885Y-1037459D02*
X3230910Y-1036738D01*
X3230423Y-1036016D01*
X3229936Y-1034572D01*
Y-1031685D01*
X3230423Y-1030242D01*
X3230910Y-1029520D01*
X3231885Y-1028798D01*
X3232859Y-1029520D01*
X3233346Y-1030242D01*
X3233833Y-1031685D01*
Y-1034572D01*
X3233346Y-1036016D01*
X3232859Y-1036738D01*
X3231885Y-1037459D01*
G01X3218243Y-1028798D02*
X3215320D01*
X3214833Y-1032407D01*
X3215807Y-1031685D01*
X3216781D01*
X3217756Y-1032407D01*
X3218243Y-1033129D01*
X3218730Y-1034572D01*
X3218243Y-1036016D01*
X3217756Y-1036738D01*
X3216781Y-1037459D01*
X3215807D01*
X3214833Y-1036738D01*
X3214345Y-1036016D01*
G01X3208499Y-1028798D02*
Y-1037459D01*
G01X3224090Y-1028798D02*
Y-1037459D01*
G01X3229578Y214684D02*
X3230552Y216127D01*
X3231527D01*
X3232014Y215406D01*
G01X3229578Y210353D02*
Y216127D01*
G01X3214474Y215406D02*
X3216423D01*
G01X3225193Y212519D02*
X3224219Y211075D01*
X3223244Y210353D01*
X3222270Y211075D01*
X3221295Y212519D01*
Y213962D01*
X3222270Y215406D01*
X3223244Y216127D01*
X3224219Y215406D01*
X3225193Y213962D01*
Y212519D01*
G01X3215449Y210353D02*
Y217571D01*
X3216423Y219015D01*
X3216911D01*
X3217398Y218293D01*
G01X3234046Y310153D02*
X3229945Y309315D01*
G01X3234046Y285023D02*
X3238147D01*
G01X3233226Y289211D02*
X3238968D01*
G01Y305964D02*
X3233226D01*
G01X3229945Y285861D02*
X3234046Y285023D01*
G01X3230765Y290049D02*
X3233226Y289211D01*
G01X3225844Y288374D02*
X3229945Y285861D01*
G01X3228305Y291724D02*
X3230765Y290049D01*
G01X3226665Y294237D02*
X3228305Y291724D01*
G01X3233226Y305964D02*
X3230765Y305127D01*
G01D02*
X3228305Y303451D01*
G01X3225844Y296750D02*
X3226665Y294237D01*
G01X3225844Y299263D02*
Y296750D01*
G01X3226665Y301776D02*
X3225844Y299263D01*
G01X3228305Y303451D02*
X3226665Y301776D01*
G01X3214361Y285023D02*
X3210260D01*
G01Y289211D02*
X3214361D01*
G01X3223383Y291724D02*
X3225844Y288374D01*
G01X3221743Y295912D02*
X3223383Y291724D01*
G01X3229945Y309315D02*
X3225024Y305964D01*
G01X3220923Y301776D02*
X3221743Y295912D01*
G01X3203698Y324393D02*
Y285023D01*
G01X3210260D02*
Y289211D01*
G01X3214361D02*
Y285023D01*
G01X3220923Y307640D02*
Y301776D01*
G01X3225024Y305964D02*
Y307640D01*
G01X3221743Y313503D02*
X3220923Y307640D01*
G01X3225024D02*
X3225844Y312666D01*
G01X3234046Y324393D02*
X3229945Y323555D01*
G01X3233226Y320205D02*
X3238147D01*
G01X3237327Y324393D02*
X3234046D01*
G01X3230765Y319367D02*
X3233226Y320205D01*
G01X3228305Y317692D02*
X3230765Y319367D01*
G01X3229945Y323555D02*
X3225844Y321042D01*
G01X3226665Y315179D02*
X3228305Y317692D01*
G01X3238147Y310153D02*
X3234046D01*
G01X3225844Y312666D02*
X3226665Y315179D01*
G01X3225844Y321042D02*
X3223383Y317692D01*
G01D02*
X3221743Y313503D01*
G01X3225515Y904708D02*
Y913763D01*
G01X3226499D02*
Y904708D01*
G01X3228664D02*
Y913763D01*
G01X3229648D02*
Y904708D01*
G01X3231814D02*
Y913763D01*
G01X3232798D02*
Y904708D01*
G01X3226499D02*
X3228664D01*
G01X3232798D02*
X3234963D01*
G01X3229648D02*
X3231814D01*
G01X3234963Y913763D02*
X3232798D01*
G01X3231814D02*
X3229648D01*
G01X3228664D02*
X3226499D01*
G01X3201302D02*
Y904708D01*
G01X3203467D02*
Y913763D01*
G01X3204452D02*
Y904708D01*
G01X3206617D02*
Y913763D01*
G01X3207601D02*
Y904708D01*
G01X3209767D02*
Y913763D01*
G01X3210751D02*
Y904708D01*
G01X3212916D02*
Y913763D01*
G01X3213900D02*
Y904708D01*
G01X3216066D02*
Y913763D01*
G01X3217050D02*
Y904708D01*
G01X3219215D02*
Y913763D01*
G01X3220200D02*
Y904708D01*
G01X3222365D02*
Y913763D01*
G01X3223349D02*
Y904708D01*
G01X3204452D02*
X3206617D01*
G01X3201302D02*
X3203467D01*
G01X3207601D02*
X3209767D01*
G01X3213900D02*
X3216066D01*
G01X3210751D02*
X3212916D01*
G01X3217050D02*
X3219215D01*
G01X3223349D02*
X3225515D01*
G01X3220200D02*
X3222365D01*
G01X3225515Y913763D02*
X3223349D01*
G01X3222365D02*
X3220200D01*
G01X3219215D02*
X3217050D01*
G01X3216066D02*
X3213900D01*
G01X3212916D02*
X3210751D01*
G01X3209767D02*
X3207601D01*
G01X3206617D02*
X3204452D01*
G01X3203467D02*
X3201302D01*
G01X3260630Y-1110360D02*
X3264041D01*
G01X3265015Y-1111803D02*
X3264041Y-1110360D01*
X3264528Y-1109638D01*
Y-1107473D01*
X3264041Y-1106751D01*
X3260630D01*
G01D02*
Y-1115412D01*
X3264041D01*
G01D02*
X3265015Y-1113969D01*
Y-1111803D01*
G01X3268157Y-1120610D02*
Y-1139623D01*
G01X3246014Y-1111081D02*
X3248937D01*
G01X3241629Y-1106751D02*
X3238706D01*
X3238219Y-1110360D01*
X3239193Y-1109638D01*
X3240167D01*
X3241142Y-1110360D01*
X3241629Y-1111081D01*
X3242116Y-1112525D01*
X3241629Y-1113969D01*
X3241142Y-1114690D01*
X3240167Y-1115412D01*
X3239193D01*
X3238219Y-1114690D01*
X3237731Y-1113969D01*
G01X3255270Y-1106751D02*
Y-1115412D01*
G01X3246014Y-1098089D02*
X3248937D01*
G01X3246014Y-1085097D02*
X3248937D01*
G01X3241629Y-1080766D02*
X3238706D01*
X3238219Y-1084375D01*
X3239193Y-1083654D01*
X3240167D01*
X3241142Y-1084375D01*
X3241629Y-1085097D01*
X3242116Y-1086541D01*
X3241629Y-1087984D01*
X3241142Y-1088706D01*
X3240167Y-1089428D01*
X3239193D01*
X3238219Y-1088706D01*
X3237731Y-1087984D01*
G01X3241629Y-1067774D02*
X3238706D01*
X3238219Y-1071383D01*
X3239193Y-1070662D01*
X3240167D01*
X3241142Y-1071383D01*
X3241629Y-1072105D01*
X3242116Y-1073549D01*
X3241629Y-1074992D01*
X3241142Y-1075714D01*
X3240167Y-1076436D01*
X3239193D01*
X3238219Y-1075714D01*
X3237731Y-1074992D01*
G01X3255270Y-1067774D02*
Y-1076436D01*
G01Y-1080766D02*
Y-1089428D01*
G01X3241629Y-1093758D02*
X3238706D01*
X3238219Y-1097368D01*
X3239193Y-1096646D01*
X3240167D01*
X3241142Y-1097368D01*
X3241629Y-1098089D01*
X3242116Y-1099533D01*
X3241629Y-1100977D01*
X3241142Y-1101698D01*
X3240167Y-1102420D01*
X3239193D01*
X3238219Y-1101698D01*
X3237731Y-1100977D01*
G01X3255270Y-1093758D02*
Y-1102420D01*
G01X3246014Y-1059113D02*
X3248937D01*
G01X3241629Y-1054782D02*
X3238706D01*
X3238219Y-1058391D01*
X3239193Y-1057670D01*
X3240167D01*
X3241142Y-1058391D01*
X3241629Y-1059113D01*
X3242116Y-1060557D01*
X3241629Y-1062000D01*
X3241142Y-1062722D01*
X3240167Y-1063444D01*
X3239193D01*
X3238219Y-1062722D01*
X3237731Y-1062000D01*
G01X3246014Y-1046121D02*
X3248937D01*
G01X3241629Y-1041790D02*
X3238706D01*
X3238219Y-1045399D01*
X3239193Y-1044677D01*
X3240167D01*
X3241142Y-1045399D01*
X3241629Y-1046121D01*
X3242116Y-1047564D01*
X3241629Y-1049008D01*
X3241142Y-1049730D01*
X3240167Y-1050451D01*
X3239193D01*
X3238219Y-1049730D01*
X3237731Y-1049008D01*
G01X3255270Y-1041790D02*
Y-1050451D01*
G01Y-1054782D02*
Y-1063444D01*
G01X3246014Y-1072105D02*
X3248937D01*
G01X3246014Y-1033129D02*
X3248937D01*
G01X3241629Y-1028798D02*
X3238706D01*
X3238219Y-1032407D01*
X3239193Y-1031685D01*
X3240167D01*
X3241142Y-1032407D01*
X3241629Y-1033129D01*
X3242116Y-1034572D01*
X3241629Y-1036016D01*
X3241142Y-1036738D01*
X3240167Y-1037459D01*
X3239193D01*
X3238219Y-1036738D01*
X3237731Y-1036016D01*
G01X3255270Y-1028798D02*
Y-1037459D01*
G01X3260759Y213240D02*
X3263682D01*
G01X3259785Y210353D02*
X3262221Y219015D01*
X3264657Y210353D01*
G01X3245169Y214684D02*
X3248092D01*
G01X3252476Y219015D02*
X3254425D01*
X3255400Y218293D01*
G01D02*
X3256374Y216849D01*
X3256861Y214684D01*
X3256374Y212519D01*
G01D02*
X3255400Y211075D01*
X3254425Y210353D01*
X3252476D01*
Y219015D01*
G01X3266855Y308477D02*
X3265214D01*
G01X3268495Y307640D02*
X3266855Y308477D01*
G01X3269315Y306802D02*
X3268495Y307640D01*
G01X3265214Y308477D02*
X3262754Y307640D01*
G01X3261113Y311828D02*
Y309315D01*
G01Y305964D02*
Y285023D01*
G01Y309315D02*
X3262754Y310990D01*
G01Y307640D02*
X3261113Y305964D01*
G01X3238147Y285023D02*
X3242248Y285861D01*
G01X3261113Y285023D02*
X3257012D01*
G01X3242248Y309315D02*
X3238147Y310153D01*
G01X3241428Y305127D02*
X3238968Y305964D01*
G01X3246350Y306802D02*
X3242248Y309315D01*
G01X3243889Y303451D02*
X3241428Y305127D01*
G01X3245529Y301776D02*
X3243889Y303451D01*
G01X3248810Y304289D02*
X3246350Y306802D01*
G01X3238968Y289211D02*
X3241428Y290049D01*
G01D02*
X3243889Y291724D01*
G01X3242248Y285861D02*
X3246350Y288374D01*
G01X3250450Y300101D02*
X3248810Y304289D01*
G01X3246350Y299263D02*
X3245529Y301776D01*
G01X3246350Y296750D02*
Y299263D01*
G01X3250450Y295912D02*
Y300101D01*
G01X3257012Y285023D02*
Y311828D01*
G01X3246350Y288374D02*
X3248810Y291724D01*
G01X3245529Y294237D02*
X3246350Y296750D01*
G01X3248810Y291724D02*
X3250450Y295912D01*
G01X3243889Y291724D02*
X3245529Y294237D01*
G01X3265214Y311828D02*
X3268495D01*
G01D02*
X3270956Y310990D01*
G01X3262754D02*
X3265214Y311828D01*
G01X3244709Y315179D02*
X3248810D01*
G01X3241428Y323555D02*
X3237327Y324393D01*
G01X3238147Y320205D02*
X3240608Y319367D01*
G01X3245529Y321042D02*
X3241428Y323555D01*
G01X3240608Y319367D02*
X3243069Y317692D01*
G01X3247990D02*
X3245529Y321042D01*
G01X3243069Y317692D02*
X3244709Y315179D01*
G01X3248810D02*
X3247990Y317692D01*
G01X3257012Y311828D02*
X3261113D01*
G01X3262798Y871283D02*
Y876811D01*
G01Y878319D02*
Y883094D01*
G01X3264274D02*
Y871283D01*
G01X3266243Y875304D02*
Y876309D01*
G01Y878319D02*
Y879324D01*
G01X3264274Y871283D02*
X3262798D01*
G01X3270180Y875304D02*
X3266243D01*
G01Y876309D02*
X3270180D01*
G01Y878319D02*
X3266243D01*
G01Y879324D02*
X3270180D01*
G01X3262798Y883094D02*
X3264274D01*
G01X3254432Y871283D02*
Y883094D01*
G01X3255908D02*
Y878319D01*
G01Y876811D02*
Y871283D01*
G01D02*
X3254432D01*
G01X3262798Y876811D02*
X3255908D01*
G01Y878319D02*
X3262798D01*
G01X3254432Y883094D02*
X3255908D01*
G01X3260160Y904708D02*
Y913763D01*
G01X3261144D02*
Y904708D01*
G01X3263310D02*
Y913763D01*
G01X3264294D02*
Y904708D01*
G01X3266459D02*
Y913763D01*
G01X3267444D02*
Y904708D01*
G01X3261144D02*
X3263310D01*
G01X3264294D02*
X3266459D01*
G01X3267444D02*
X3269609D01*
G01Y913763D02*
X3267444D01*
G01X3266459D02*
X3264294D01*
G01X3263310D02*
X3261144D01*
G01X3234963Y904708D02*
Y913763D01*
G01X3235948D02*
Y904708D01*
G01X3238113D02*
Y913763D01*
G01X3239097D02*
Y904708D01*
G01X3241263D02*
Y913763D01*
G01X3242247D02*
Y904708D01*
G01X3244412D02*
Y913763D01*
G01X3245396D02*
Y904708D01*
G01X3247562D02*
Y913763D01*
G01X3248546D02*
Y904708D01*
G01X3250711D02*
Y913763D01*
G01X3251696D02*
Y904708D01*
G01X3253861D02*
Y913763D01*
G01X3254845D02*
Y904708D01*
G01X3257011D02*
Y913763D01*
G01X3257995D02*
Y904708D01*
G01X3235948D02*
X3238113D01*
G01X3242247D02*
X3244412D01*
G01X3239097D02*
X3241263D01*
G01X3245396D02*
X3247562D01*
G01X3251696D02*
X3253861D01*
G01X3248546D02*
X3250711D01*
G01X3254845D02*
X3257011D01*
G01X3257995D02*
X3260160D01*
G01Y913763D02*
X3257995D01*
G01X3257011D02*
X3254845D01*
G01X3253861D02*
X3251696D01*
G01X3250711D02*
X3248546D01*
G01X3247562D02*
X3245396D01*
G01X3244412D02*
X3242247D01*
G01X3241263D02*
X3239097D01*
G01X3238113D02*
X3235948D01*
G01X3268157Y2171102D02*
Y2152090D01*
G01X3303991Y-1108194D02*
X3303504Y-1107473D01*
X3302530Y-1106751D01*
X3301555D01*
X3300581Y-1107473D01*
X3300094Y-1108194D01*
Y-1108916D01*
X3300581Y-1109638D01*
X3302530Y-1111081D01*
X3303504Y-1111803D01*
X3303991Y-1112525D01*
Y-1113969D01*
X3303504Y-1114690D01*
X3302530Y-1115412D01*
X3301555D01*
X3300581Y-1114690D01*
G01D02*
X3299606Y-1113247D01*
G01X3294734Y-1111081D02*
X3296196Y-1115412D01*
G01X3288400D02*
X3284503D01*
Y-1106751D01*
X3288400D01*
G01X3284503Y-1111081D02*
X3286939D01*
G01X3276220Y-1106751D02*
X3278657Y-1115412D01*
X3281093Y-1106751D01*
G01X3292298Y-1115412D02*
Y-1106751D01*
X3294734D01*
X3295709Y-1107473D01*
X3296196Y-1108194D01*
Y-1109638D01*
X3295709Y-1110360D01*
X3294734Y-1111081D01*
X3292298D01*
G01X3303991Y-1082210D02*
X3303504Y-1081488D01*
X3302530Y-1080766D01*
X3301555D01*
X3300581Y-1081488D01*
X3300094Y-1082210D01*
Y-1082932D01*
X3300581Y-1083654D01*
X3302530Y-1085097D01*
X3303504Y-1085819D01*
X3303991Y-1086541D01*
Y-1087984D01*
X3303504Y-1088706D01*
X3302530Y-1089428D01*
X3301555D01*
X3300581Y-1088706D01*
X3300094Y-1087984D01*
X3299606Y-1087262D01*
G01X3303991Y-1069218D02*
X3303504Y-1068496D01*
X3302530Y-1067774D01*
X3301555D01*
X3300581Y-1068496D01*
X3300094Y-1069218D01*
Y-1069940D01*
X3300581Y-1070662D01*
X3302530Y-1072105D01*
X3303504Y-1072827D01*
X3303991Y-1073549D01*
Y-1074992D01*
X3303504Y-1075714D01*
X3302530Y-1076436D01*
X3301555D01*
X3300581Y-1075714D01*
G01Y-1101698D02*
X3299606Y-1100255D01*
G01X3300581Y-1075714D02*
X3299606Y-1074270D01*
G01X3294734Y-1085097D02*
X3296196Y-1089428D01*
G01X3294734Y-1072105D02*
X3296196Y-1076436D01*
G01X3303991Y-1095202D02*
X3303504Y-1094481D01*
X3302530Y-1093758D01*
X3301555D01*
X3300581Y-1094481D01*
X3300094Y-1095202D01*
Y-1095924D01*
X3300581Y-1096646D01*
X3302530Y-1098089D01*
X3303504Y-1098811D01*
X3303991Y-1099533D01*
Y-1100977D01*
X3303504Y-1101698D01*
X3302530Y-1102420D01*
X3301555D01*
X3300581Y-1101698D01*
G01X3294734Y-1098089D02*
X3296196Y-1102420D01*
G01X3284503Y-1098089D02*
X3286939D01*
G01X3288400Y-1089428D02*
X3284503D01*
Y-1080766D01*
X3288400D01*
G01X3284503Y-1085097D02*
X3286939D01*
G01X3288400Y-1076436D02*
X3284503D01*
Y-1067774D01*
X3288400D01*
G01X3276220Y-1080766D02*
X3278657Y-1089428D01*
X3281093Y-1080766D01*
G01X3276220Y-1067774D02*
X3278657Y-1076436D01*
X3281093Y-1067774D01*
G01X3292298Y-1089428D02*
Y-1080766D01*
X3294734D01*
X3295709Y-1081488D01*
X3296196Y-1082210D01*
Y-1083654D01*
X3295709Y-1084375D01*
X3294734Y-1085097D01*
X3292298D01*
G01Y-1076436D02*
Y-1067774D01*
X3294734D01*
X3295709Y-1068496D01*
X3296196Y-1069218D01*
Y-1070662D01*
X3295709Y-1071383D01*
X3294734Y-1072105D01*
X3292298D01*
G01X3288400Y-1102420D02*
X3284503D01*
Y-1093758D01*
X3288400D01*
G01X3276220D02*
X3278657Y-1102420D01*
X3281093Y-1093758D01*
G01X3292298Y-1102420D02*
Y-1093758D01*
X3294734D01*
X3295709Y-1094481D01*
X3296196Y-1095202D01*
Y-1096646D01*
X3295709Y-1097368D01*
X3294734Y-1098089D01*
X3292298D01*
G01X3303991Y-1056226D02*
X3303504Y-1055504D01*
X3302530Y-1054782D01*
X3301555D01*
X3300581Y-1055504D01*
X3300094Y-1056226D01*
Y-1056947D01*
X3300581Y-1057670D01*
X3302530Y-1059113D01*
X3303504Y-1059835D01*
X3303991Y-1060557D01*
Y-1062000D01*
X3303504Y-1062722D01*
X3302530Y-1063444D01*
X3301555D01*
X3300581Y-1062722D01*
G01X3303991Y-1043234D02*
X3303504Y-1042512D01*
X3302530Y-1041790D01*
X3301555D01*
X3300581Y-1042512D01*
X3300094Y-1043234D01*
Y-1043955D01*
X3300581Y-1044677D01*
X3302530Y-1046121D01*
X3303504Y-1046843D01*
X3303991Y-1047564D01*
Y-1049008D01*
X3303504Y-1049730D01*
X3302530Y-1050451D01*
X3301555D01*
X3300581Y-1049730D01*
X3300094Y-1049008D01*
X3299606Y-1048286D01*
G01X3300581Y-1062722D02*
X3299606Y-1061278D01*
G01X3294734Y-1059113D02*
X3296196Y-1063444D01*
G01X3294734Y-1046121D02*
X3296196Y-1050451D01*
G01X3288400Y-1063444D02*
X3284503D01*
Y-1054782D01*
X3288400D01*
G01X3284503Y-1059113D02*
X3286939D01*
G01X3288400Y-1050451D02*
X3284503D01*
Y-1041790D01*
X3288400D01*
G01X3284503Y-1046121D02*
X3286939D01*
G01X3276220Y-1054782D02*
X3278657Y-1063444D01*
X3281093Y-1054782D01*
G01X3276220Y-1041790D02*
X3278657Y-1050451D01*
X3281093Y-1041790D01*
G01X3292298Y-1063444D02*
Y-1054782D01*
X3294734D01*
X3295709Y-1055504D01*
X3296196Y-1056226D01*
Y-1057670D01*
X3295709Y-1058391D01*
X3294734Y-1059113D01*
X3292298D01*
G01Y-1050451D02*
Y-1041790D01*
X3294734D01*
X3295709Y-1042512D01*
X3296196Y-1043234D01*
Y-1044677D01*
X3295709Y-1045399D01*
X3294734Y-1046121D01*
X3292298D01*
G01X3284503Y-1072105D02*
X3286939D01*
G01X3300581Y-1036738D02*
X3299606Y-1035294D01*
G01X3303991Y-1030242D02*
X3303504Y-1029520D01*
X3302530Y-1028798D01*
X3301555D01*
X3300581Y-1029520D01*
X3300094Y-1030242D01*
Y-1030963D01*
X3300581Y-1031685D01*
X3302530Y-1033129D01*
X3303504Y-1033851D01*
X3303991Y-1034572D01*
Y-1036016D01*
X3303504Y-1036738D01*
X3302530Y-1037459D01*
X3301555D01*
X3300581Y-1036738D01*
G01X3294734Y-1033129D02*
X3296196Y-1037459D01*
G01X3284503Y-1033129D02*
X3286939D01*
G01X3288400Y-1037459D02*
X3284503D01*
Y-1028798D01*
X3288400D01*
G01X3276220D02*
X3278657Y-1037459D01*
X3281093Y-1028798D01*
G01X3292298Y-1037459D02*
Y-1028798D01*
X3294734D01*
X3295709Y-1029520D01*
X3296196Y-1030242D01*
Y-1031685D01*
X3295709Y-1032407D01*
X3294734Y-1033129D01*
X3292298D01*
G01X3290843Y49797D02*
X3346759Y-73721D01*
G01X3289337Y55264D02*
X3365041Y-48516D01*
G01X3296627Y58763D02*
G03I-9843J0D01*
G01X3291115D02*
G03I-4331J0D01*
G01D02*
G03I-4331J0D01*
G01X3298023Y285023D02*
X3293922D01*
G01X3303764Y308477D02*
X3302124D01*
G01D02*
X3299663Y307640D01*
G01X3293922Y285023D02*
Y311828D01*
G01X3298023D02*
Y309315D01*
G01Y305964D02*
Y285023D01*
G01Y309315D02*
X3299663Y310990D01*
G01Y307640D02*
X3298023Y305964D01*
G01X3287360Y285023D02*
X3283259D01*
G01X3274237D02*
X3270135D01*
G01X3279978Y308477D02*
X3277517D01*
G01X3281619Y307640D02*
X3279978Y308477D01*
G01X3270956Y310990D02*
X3273417Y308477D01*
G01X3282439Y306802D02*
X3281619Y307640D01*
G01X3284079Y310990D02*
X3285720Y309315D01*
G01X3277517Y308477D02*
X3275877Y307640D01*
G01X3270135Y305127D02*
X3269315Y306802D01*
G01X3283259Y305127D02*
X3282439Y306802D01*
G01X3273417Y308477D02*
X3275877Y310990D01*
G01Y307640D02*
X3275057Y306802D01*
G01X3285720Y309315D02*
X3287360Y305127D01*
G01X3270135Y285023D02*
Y305127D01*
G01X3274237D02*
Y285023D01*
G01X3283259D02*
Y305127D01*
G01X3287360D02*
Y285023D01*
G01X3275057Y306802D02*
X3274237Y305127D01*
G01X3293922Y311828D02*
X3298023D01*
G01X3302124D02*
X3305405D01*
G01X3299663Y310990D02*
X3302124Y311828D01*
G01X3278338D02*
X3281619D01*
G01D02*
X3284079Y310990D01*
G01X3275877D02*
X3278338Y311828D01*
G01X3295770Y879073D02*
X3296509Y879324D01*
G01Y878319D02*
X3295770Y878068D01*
G01X3299707Y879073D02*
X3300446Y879324D01*
G01X3300200Y878319D02*
X3299707Y878068D01*
G01X3295278Y878571D02*
X3295770Y879073D01*
G01Y878068D02*
X3295278Y877565D01*
G01X3298969Y878319D02*
X3299707Y879073D01*
G01Y878068D02*
X3299461Y877817D01*
G01D02*
X3299215Y877314D01*
G01X3294048Y871283D02*
Y879324D01*
G01X3295278D02*
Y878571D01*
G01Y877565D02*
Y871283D01*
G01X3297985D02*
Y877314D01*
G01X3299215D02*
Y871283D01*
G01X3301922D02*
Y877314D01*
G01X3303152Y871283D02*
X3301922D01*
G01X3299215D02*
X3297985D01*
G01X3295278D02*
X3294048D01*
G01X3300938Y878319D02*
X3300200D01*
G01X3297001D02*
X3296509D01*
G01X3294048Y879324D02*
X3295278D01*
G01X3296509D02*
X3297493D01*
G01X3300446D02*
X3301430D01*
G01X3297493D02*
X3298231Y879073D01*
G01X3301430Y879324D02*
X3302168Y879073D01*
G01X3297493Y878068D02*
X3297001Y878319D01*
G01X3301430Y878068D02*
X3300938Y878319D01*
G01X3297739Y877817D02*
X3297493Y878068D01*
G01X3298231Y879073D02*
X3298969Y878319D01*
G01X3301676Y877817D02*
X3301430Y878068D01*
G01X3302168Y879073D02*
X3302660Y878571D01*
G01X3297985Y877314D02*
X3297739Y877817D01*
G01X3301922Y877314D02*
X3301676Y877817D01*
G01X3284698Y879073D02*
X3285436Y879324D01*
G01Y878319D02*
X3284698Y878068D01*
G01X3288635Y879073D02*
X3289373Y879324D01*
G01X3289127Y878319D02*
X3288635Y878068D01*
G01X3275347Y881586D02*
X3274609Y881083D01*
G01X3277808Y872791D02*
X3278546Y873293D01*
G01X3275101Y882843D02*
X3273871Y882089D01*
G01X3278054Y871534D02*
X3279284Y872288D01*
G01X3273871Y882089D02*
X3273133Y881335D01*
G01X3284206Y878571D02*
X3284698Y879073D01*
G01Y878068D02*
X3284206Y877565D01*
G01X3279284Y872288D02*
X3280022Y873042D01*
G01X3287896Y878319D02*
X3288635Y879073D01*
G01Y878068D02*
X3288389Y877817D01*
G01X3274609Y881083D02*
X3273625Y879576D01*
G01X3278546Y873293D02*
X3279530Y874801D01*
G01X3273133Y881335D02*
X3272641Y880330D01*
G01X3280022Y873042D02*
X3280515Y874047D01*
G01X3288389Y877817D02*
X3288143Y877314D01*
G01X3272641Y880330D02*
X3272394Y879576D01*
G01X3280515Y874047D02*
X3280761Y874801D01*
G01X3273625Y879576D02*
X3273379Y878068D01*
G01X3272394Y879576D02*
X3272148Y878319D01*
G01X3280761Y874801D02*
X3281007Y876058D01*
G01X3276578Y872539D02*
X3277808Y872791D01*
G01X3276578Y881837D02*
X3275347Y881586D01*
G01X3276578Y871283D02*
X3278054Y871534D01*
G01X3279530Y874801D02*
X3279776Y876309D01*
G01X3276578Y883094D02*
X3275101Y882843D01*
G01X3270180Y879324D02*
Y878319D01*
G01Y876309D02*
Y875304D01*
G01X3272148Y878319D02*
Y876058D01*
G01X3273379Y878068D02*
Y876309D01*
G01X3279776D02*
Y878068D01*
G01X3281007Y876058D02*
Y878319D01*
G01X3282975Y871283D02*
Y879324D01*
G01X3284206D02*
Y878571D01*
G01Y877565D02*
Y871283D01*
G01X3286912D02*
Y877314D01*
G01X3288143D02*
Y871283D01*
G01X3290849D02*
Y877314D01*
G01X3292080D02*
Y871283D01*
G01D02*
X3290849D01*
G01X3288143D02*
X3286912D01*
G01X3284206D02*
X3282975D01*
G01X3289865Y878319D02*
X3289127D01*
G01X3285928D02*
X3285436D01*
G01X3282975Y879324D02*
X3284206D01*
G01X3285436D02*
X3286420D01*
G01X3289373D02*
X3290357D01*
G01X3275101Y871534D02*
X3276578Y871283D01*
G01X3278054Y882843D02*
X3276578Y883094D01*
G01X3275347Y872791D02*
X3276578Y872539D01*
G01X3277808Y881586D02*
X3276578Y881837D01*
G01X3272148Y876058D02*
X3272394Y874801D01*
G01X3281007Y878319D02*
X3280761Y879576D01*
G01X3273379Y876309D02*
X3273625Y874801D01*
G01X3279776Y878068D02*
X3279530Y879576D01*
G01X3286420Y879324D02*
X3287158Y879073D01*
G01X3290357Y879324D02*
X3291095Y879073D01*
G01X3286420Y878068D02*
X3285928Y878319D01*
G01X3290357Y878068D02*
X3289865Y878319D01*
G01X3273871Y872288D02*
X3275101Y871534D01*
G01X3272641Y874047D02*
X3273133Y873042D01*
G01X3280515Y880330D02*
X3280022Y881335D01*
G01X3286912Y877314D02*
X3286666Y877817D01*
G01X3291587Y878571D02*
X3292080Y877314D01*
G01X3272394Y874801D02*
X3272641Y874047D01*
G01X3280761Y879576D02*
X3280515Y880330D01*
G01X3279284Y882089D02*
X3278054Y882843D01*
G01X3274609Y873293D02*
X3275347Y872791D01*
G01X3278546Y881083D02*
X3277808Y881586D01*
G01X3273133Y873042D02*
X3273871Y872288D01*
G01X3280022Y881335D02*
X3279284Y882089D01*
G01X3286666Y877817D02*
X3286420Y878068D01*
G01X3287158Y879073D02*
X3287896Y878319D01*
G01X3290603Y877817D02*
X3290357Y878068D01*
G01X3291095Y879073D02*
X3291587Y878571D01*
G01X3273625Y874801D02*
X3274609Y873293D01*
G01X3279530Y879576D02*
X3278546Y881083D01*
G01X3290849Y877314D02*
X3290603Y877817D01*
G01X3294806Y904708D02*
Y913763D01*
G01X3295790D02*
Y904708D01*
G01X3297956D02*
Y913763D01*
G01X3298940D02*
Y904708D01*
G01X3301105D02*
Y913763D01*
G01X3302089D02*
Y904708D01*
G01X3295790D02*
X3297956D01*
G01X3302089D02*
X3304255D01*
G01X3298940D02*
X3301105D01*
G01X3304255Y913763D02*
X3302089D01*
G01X3301105D02*
X3298940D01*
G01X3297956D02*
X3295790D01*
G01X3269609Y904708D02*
Y913763D01*
G01X3270593D02*
Y904708D01*
G01X3272759D02*
Y913763D01*
G01X3273743D02*
Y904708D01*
G01X3275908D02*
Y913763D01*
G01X3276893D02*
Y904708D01*
G01X3279058D02*
Y913763D01*
G01X3280042D02*
Y904708D01*
G01X3282207D02*
Y913763D01*
G01X3283192D02*
Y904708D01*
G01X3285357D02*
Y913763D01*
G01X3286341D02*
Y904708D01*
G01X3288507D02*
Y913763D01*
G01X3289491D02*
Y904708D01*
G01X3291656D02*
Y913763D01*
G01X3292641D02*
Y904708D01*
G01X3270593D02*
X3272759D01*
G01X3273743D02*
X3275908D01*
G01X3280042D02*
X3282207D01*
G01X3276893D02*
X3279058D01*
G01X3283192D02*
X3285357D01*
G01X3286341D02*
X3288507D01*
G01X3292641D02*
X3294806D01*
G01X3289491D02*
X3291656D01*
G01X3294806Y913763D02*
X3292641D01*
G01X3291656D02*
X3289491D01*
G01X3288507D02*
X3286341D01*
G01X3285357D02*
X3283192D01*
G01X3282207D02*
X3280042D01*
G01X3279058D02*
X3276893D01*
G01X3275908D02*
X3273743D01*
G01X3272759D02*
X3270593D01*
G01X3316171Y-1114690D02*
X3315197Y-1113247D01*
X3314710Y-1111081D01*
X3315197Y-1108916D01*
G01X3319094Y-1107473D02*
X3320069Y-1108916D01*
X3320556Y-1111081D01*
X3320069Y-1113247D01*
X3319094Y-1114690D01*
G01X3309837Y-1106751D02*
Y-1115412D01*
G01X3323479D02*
Y-1106751D01*
X3327377Y-1115412D01*
Y-1106751D01*
G01X3315197Y-1108916D02*
X3316171Y-1107473D01*
X3317146Y-1106751D01*
X3318120D01*
X3319094Y-1107473D01*
G01Y-1114690D02*
X3318120Y-1115412D01*
X3317146D01*
X3316171Y-1114690D01*
G01Y-1101698D02*
X3315197Y-1100255D01*
X3314710Y-1098089D01*
X3315197Y-1095924D01*
G01X3319094Y-1094481D02*
X3320069Y-1095924D01*
X3320556Y-1098089D01*
X3320069Y-1100255D01*
X3319094Y-1101698D01*
G01Y-1081488D02*
X3320069Y-1082932D01*
X3320556Y-1085097D01*
X3320069Y-1087262D01*
X3319581Y-1087984D01*
G01X3316171Y-1075714D02*
X3315197Y-1074270D01*
X3314710Y-1072105D01*
X3315197Y-1069940D01*
G01X3319094Y-1068496D02*
X3320069Y-1069940D01*
X3320556Y-1072105D01*
X3320069Y-1074270D01*
X3319094Y-1075714D01*
G01X3309837Y-1067774D02*
Y-1076436D01*
G01Y-1080766D02*
Y-1089428D01*
G01X3323479D02*
Y-1080766D01*
X3327377Y-1089428D01*
Y-1080766D01*
G01X3323479Y-1076436D02*
Y-1067774D01*
X3327377Y-1076436D01*
Y-1067774D01*
G01X3315197Y-1082932D02*
X3316171Y-1081488D01*
X3317146Y-1080766D01*
X3318120D01*
X3319094Y-1081488D01*
G01X3319581Y-1087984D02*
X3319094Y-1088706D01*
X3318120Y-1089428D01*
X3317146D01*
X3316171Y-1088706D01*
X3315684Y-1087984D01*
X3315197Y-1087262D01*
X3314710Y-1085097D01*
X3315197Y-1082932D01*
G01Y-1095924D02*
X3316171Y-1094481D01*
X3317146Y-1093758D01*
X3318120D01*
X3319094Y-1094481D01*
G01Y-1075714D02*
X3318120Y-1076436D01*
X3317146D01*
X3316171Y-1075714D01*
G01X3309837Y-1093758D02*
Y-1102420D01*
G01X3323479D02*
Y-1093758D01*
X3327377Y-1102420D01*
Y-1093758D01*
G01X3319094Y-1101698D02*
X3318120Y-1102420D01*
X3317146D01*
X3316171Y-1101698D01*
G01Y-1062722D02*
X3315197Y-1061278D01*
X3314710Y-1059113D01*
X3315197Y-1056947D01*
G01X3319094Y-1055504D02*
X3320069Y-1056947D01*
X3320556Y-1059113D01*
X3320069Y-1061278D01*
X3319094Y-1062722D01*
G01Y-1042512D02*
X3320069Y-1043955D01*
X3320556Y-1046121D01*
X3320069Y-1048286D01*
X3319581Y-1049008D01*
G01X3309837Y-1041790D02*
Y-1050451D01*
G01Y-1054782D02*
Y-1063444D01*
G01X3323479D02*
Y-1054782D01*
X3327377Y-1063444D01*
Y-1054782D01*
G01X3323479Y-1050451D02*
Y-1041790D01*
X3327377Y-1050451D01*
Y-1041790D01*
G01X3315197Y-1043955D02*
X3316171Y-1042512D01*
X3317146Y-1041790D01*
X3318120D01*
X3319094Y-1042512D01*
G01X3319581Y-1049008D02*
X3319094Y-1049730D01*
X3318120Y-1050451D01*
X3317146D01*
X3316171Y-1049730D01*
X3315684Y-1049008D01*
X3315197Y-1048286D01*
X3314710Y-1046121D01*
X3315197Y-1043955D01*
G01Y-1056947D02*
X3316171Y-1055504D01*
X3317146Y-1054782D01*
X3318120D01*
X3319094Y-1055504D01*
G01Y-1062722D02*
X3318120Y-1063444D01*
X3317146D01*
X3316171Y-1062722D01*
G01X3315197Y-1069940D02*
X3316171Y-1068496D01*
X3317146Y-1067774D01*
X3318120D01*
X3319094Y-1068496D01*
G01X3316171Y-1036738D02*
X3315197Y-1035294D01*
X3314710Y-1033129D01*
X3315197Y-1030963D01*
X3315684Y-1030242D01*
X3316171Y-1029520D01*
X3317146Y-1028798D01*
X3318120D01*
X3319094Y-1029520D01*
X3319581Y-1030242D01*
X3320069Y-1030963D01*
X3320556Y-1033129D01*
X3320069Y-1035294D01*
X3319094Y-1036738D01*
G01X3309837Y-1028798D02*
Y-1037459D01*
G01X3323479D02*
Y-1028798D01*
X3327377Y-1037459D01*
Y-1028798D01*
G01X3319094Y-1036738D02*
X3318120Y-1037459D01*
X3317146D01*
X3316171Y-1036738D01*
G01X3339934Y58763D02*
G03I-9843J0D01*
G01X3334422D02*
G03I-4331J0D01*
G01D02*
G03I-4331J0D01*
G01X3324269Y285023D02*
X3320169D01*
G01X3311146D02*
X3307045D01*
G01X3316887Y308477D02*
X3314427D01*
G01X3305405Y307640D02*
X3303764Y308477D01*
G01X3318528Y307640D02*
X3316887Y308477D01*
G01X3306225Y306802D02*
X3305405Y307640D01*
G01X3307865Y310990D02*
X3310326Y308477D01*
G01X3319348Y306802D02*
X3318528Y307640D01*
G01X3320989Y310990D02*
X3322629Y309315D01*
G01X3314427Y308477D02*
X3312787Y307640D01*
G01X3307045Y305127D02*
X3306225Y306802D01*
G01X3320169Y305127D02*
X3319348Y306802D01*
G01X3322629Y309315D02*
X3324269Y305127D01*
G01X3307045Y285023D02*
Y305127D01*
G01X3311146D02*
Y285023D01*
G01X3310326Y308477D02*
X3312787Y310990D01*
G01Y307640D02*
X3311966Y306802D01*
G01X3320169Y285023D02*
Y305127D01*
G01X3324269D02*
Y285023D01*
G01X3311966Y306802D02*
X3311146Y305127D01*
G01X3315247Y311828D02*
X3318528D01*
G01X3305405D02*
X3307865Y310990D01*
G01X3318528Y311828D02*
X3320989Y310990D01*
G01X3312787D02*
X3315247Y311828D01*
G01X3303152Y877314D02*
Y871283D01*
G01X3302660Y878571D02*
X3303152Y877314D01*
G01X3330436Y904708D02*
X3332601D01*
G01X3327286D02*
X3329452D01*
G01X3333585D02*
X3335751D01*
G01Y913763D02*
X3333585D01*
G01X3332601D02*
X3330436D01*
G01X3329452D02*
X3327286D01*
G01D02*
Y904708D01*
G01X3329452D02*
Y913763D01*
G01X3330436D02*
Y904708D01*
G01X3332601D02*
Y913763D01*
G01X3333585D02*
Y904708D01*
G01X3335751D02*
Y913763D01*
G01X3304255Y904708D02*
Y913763D01*
G01X3305239D02*
Y904708D01*
G01X3307404D02*
Y913763D01*
G01X3308389D02*
Y904708D01*
G01X3310554D02*
Y913763D01*
G01X3311538D02*
Y904708D01*
G01X3313704D02*
Y913763D01*
G01X3314688D02*
Y904708D01*
G01X3316853D02*
Y913763D01*
G01X3317837D02*
Y904708D01*
G01X3305239D02*
X3307404D01*
G01X3311538D02*
X3313704D01*
G01X3308389D02*
X3310554D01*
G01X3314688D02*
X3316853D01*
G01X3320987D02*
X3323152D01*
G01X3317837D02*
X3320003D01*
G01X3324137D02*
X3326302D01*
G01Y913763D02*
X3324137D01*
G01X3323152D02*
X3320987D01*
G01X3320003D02*
X3317837D01*
G01X3316853D02*
X3314688D01*
G01X3313704D02*
X3311538D01*
G01X3310554D02*
X3308389D01*
G01X3307404D02*
X3305239D01*
G01X3320003Y904708D02*
Y913763D01*
G01X3320987D02*
Y904708D01*
G01X3323152D02*
Y913763D01*
G01X3324137D02*
Y904708D01*
G01X3326302D02*
Y913763D01*
G01X3364404Y-1115412D02*
X3363430Y-1114690D01*
X3362943Y-1113969D01*
X3362456Y-1112525D01*
Y-1109638D01*
X3362943Y-1108194D01*
X3363430Y-1107473D01*
X3364404Y-1106751D01*
X3365379Y-1107473D01*
X3365866Y-1108194D01*
X3366353Y-1109638D01*
Y-1112525D01*
X3365866Y-1113969D01*
X3365379Y-1114690D01*
X3364404Y-1115412D01*
G01X3339557Y-1112525D02*
X3342480D01*
G01X3338583Y-1115412D02*
X3341019Y-1106751D01*
X3343455Y-1115412D01*
G01X3354661Y-1108194D02*
X3355148Y-1107473D01*
X3356122Y-1106751D01*
X3357096D01*
X3358071Y-1107473D01*
X3358558Y-1108194D01*
Y-1109638D01*
X3358071Y-1110360D01*
G01D02*
X3356122Y-1111803D01*
X3355148Y-1113247D01*
X3354661Y-1115412D01*
X3358558D01*
G01X3364404Y-1089428D02*
X3363430Y-1088706D01*
X3362943Y-1087984D01*
X3362456Y-1086541D01*
Y-1083654D01*
X3362943Y-1082210D01*
X3363430Y-1081488D01*
X3364404Y-1080766D01*
X3365379Y-1081488D01*
X3365866Y-1082210D01*
X3366353Y-1083654D01*
Y-1086541D01*
X3365866Y-1087984D01*
X3365379Y-1088706D01*
X3364404Y-1089428D01*
G01Y-1076436D02*
X3363430Y-1075714D01*
X3362943Y-1074992D01*
X3362456Y-1073549D01*
Y-1070662D01*
X3362943Y-1069218D01*
X3363430Y-1068496D01*
X3364404Y-1067774D01*
X3365379Y-1068496D01*
X3365866Y-1069218D01*
X3366353Y-1070662D01*
Y-1073549D01*
X3365866Y-1074992D01*
X3365379Y-1075714D01*
X3364404Y-1076436D01*
G01Y-1102420D02*
X3363430Y-1101698D01*
X3362943Y-1100977D01*
X3362456Y-1099533D01*
Y-1096646D01*
X3362943Y-1095202D01*
X3363430Y-1094481D01*
X3364404Y-1093758D01*
X3365379Y-1094481D01*
X3365866Y-1095202D01*
X3366353Y-1096646D01*
Y-1099533D01*
X3365866Y-1100977D01*
X3365379Y-1101698D01*
X3364404Y-1102420D01*
G01X3339557Y-1099533D02*
X3342480D01*
G01X3338583Y-1084375D02*
X3341993D01*
G01X3342967Y-1085819D02*
X3341993Y-1084375D01*
X3342480Y-1083654D01*
Y-1081488D01*
X3341993Y-1080766D01*
X3338583D01*
G01X3339557Y-1075714D02*
X3338583Y-1074270D01*
X3338095Y-1072105D01*
X3338583Y-1069940D01*
G01Y-1080766D02*
Y-1089428D01*
X3341993D01*
G01X3342967Y-1074992D02*
X3342480Y-1075714D01*
X3341506Y-1076436D01*
X3340531D01*
X3339557Y-1075714D01*
G01X3341993Y-1089428D02*
X3342967Y-1087984D01*
Y-1085819D01*
G01X3354661Y-1082210D02*
X3355148Y-1081488D01*
X3356122Y-1080766D01*
X3357096D01*
X3358071Y-1081488D01*
X3358558Y-1082210D01*
Y-1083654D01*
X3358071Y-1084375D01*
G01X3354661Y-1095202D02*
X3355148Y-1094481D01*
X3356122Y-1093758D01*
X3357096D01*
X3358071Y-1094481D01*
X3358558Y-1095202D01*
Y-1096646D01*
X3358071Y-1097368D01*
G01Y-1071383D02*
X3356122Y-1072827D01*
X3355148Y-1074270D01*
X3354661Y-1076436D01*
X3358558D01*
G01X3358071Y-1084375D02*
X3356122Y-1085819D01*
X3355148Y-1087262D01*
X3354661Y-1089428D01*
X3358558D01*
G01X3338583Y-1102420D02*
X3341019Y-1093758D01*
X3343455Y-1102420D01*
G01X3358071Y-1097368D02*
X3356122Y-1098811D01*
X3355148Y-1100255D01*
X3354661Y-1102420D01*
X3358558D01*
G01X3364404Y-1063444D02*
X3363430Y-1062722D01*
X3362943Y-1062000D01*
X3362456Y-1060557D01*
Y-1057670D01*
X3362943Y-1056226D01*
X3363430Y-1055504D01*
X3364404Y-1054782D01*
X3365379Y-1055504D01*
X3365866Y-1056226D01*
X3366353Y-1057670D01*
Y-1060557D01*
X3365866Y-1062000D01*
X3365379Y-1062722D01*
X3364404Y-1063444D01*
G01Y-1050451D02*
X3363430Y-1049730D01*
X3362943Y-1049008D01*
X3362456Y-1047564D01*
Y-1044677D01*
X3362943Y-1043234D01*
X3363430Y-1042512D01*
X3364404Y-1041790D01*
X3365379Y-1042512D01*
X3365866Y-1043234D01*
X3366353Y-1044677D01*
Y-1047564D01*
X3365866Y-1049008D01*
X3365379Y-1049730D01*
X3364404Y-1050451D01*
G01X3339070Y-1054782D02*
X3341019D01*
X3341993Y-1055504D01*
G01X3342967Y-1050451D02*
X3339070D01*
Y-1041790D01*
X3342967D01*
G01X3339070Y-1046121D02*
X3341506D01*
G01X3341993Y-1055504D02*
X3342967Y-1056947D01*
X3343455Y-1059113D01*
X3342967Y-1061278D01*
G01X3354661Y-1043234D02*
X3355148Y-1042512D01*
X3356122Y-1041790D01*
X3357096D01*
X3358071Y-1042512D01*
X3358558Y-1043234D01*
Y-1044677D01*
X3358071Y-1045399D01*
G01X3342967Y-1061278D02*
X3341993Y-1062722D01*
X3341019Y-1063444D01*
X3339070D01*
Y-1054782D01*
G01X3354661Y-1056226D02*
X3355148Y-1055504D01*
X3356122Y-1054782D01*
X3357096D01*
X3358071Y-1055504D01*
X3358558Y-1056226D01*
Y-1057670D01*
X3358071Y-1058391D01*
G01Y-1045399D02*
X3356122Y-1046843D01*
X3355148Y-1048286D01*
X3354661Y-1050451D01*
X3358558D01*
G01X3358071Y-1058391D02*
X3356122Y-1059835D01*
X3355148Y-1061278D01*
X3354661Y-1063444D01*
X3358558D01*
G01X3338583Y-1069940D02*
X3339557Y-1068496D01*
X3340531Y-1067774D01*
X3341506D01*
X3342480Y-1068496D01*
X3342967Y-1069218D01*
G01X3354661D02*
X3355148Y-1068496D01*
X3356122Y-1067774D01*
X3357096D01*
X3358071Y-1068496D01*
X3358558Y-1069218D01*
Y-1070662D01*
X3358071Y-1071383D01*
G01X3364404Y-1037459D02*
X3363430Y-1036738D01*
X3362943Y-1036016D01*
X3362456Y-1034572D01*
Y-1031685D01*
X3362943Y-1030242D01*
X3363430Y-1029520D01*
X3364404Y-1028798D01*
X3365379Y-1029520D01*
X3365866Y-1030242D01*
X3366353Y-1031685D01*
Y-1034572D01*
X3365866Y-1036016D01*
X3365379Y-1036738D01*
X3364404Y-1037459D01*
G01X3339070Y-1033129D02*
X3341506D01*
G01X3354661Y-1030242D02*
X3355148Y-1029520D01*
X3356122Y-1028798D01*
X3357096D01*
X3358071Y-1029520D01*
X3358558Y-1030242D01*
Y-1031685D01*
X3358071Y-1032407D01*
G01X3339070Y-1037459D02*
Y-1028798D01*
X3342967D01*
G01X3358071Y-1032407D02*
X3356122Y-1033851D01*
X3355148Y-1035294D01*
X3354661Y-1037459D01*
X3358558D01*
G01X3368802Y-65781D02*
X3371725Y-71556D01*
G01X3363930D02*
Y-62894D01*
X3360519Y-69390D01*
X3364904D01*
G01X3368802Y-71556D02*
X3371725Y-65781D01*
G01X3346759Y-73721D02*
X3349909D01*
G01D02*
X3604844D01*
G01X3365041Y-48516D02*
X3368191D01*
G01D02*
X3490606D01*
G01X3383241Y58763D02*
G03I-9843J0D01*
G01X3377729D02*
G03I-4331J0D01*
G01D02*
G03I-4331J0D01*
G01X3362621Y913763D02*
X3366558Y918881D01*
G01X3362621Y913763D02*
X3366558Y918881D01*
G01X3367247Y904708D02*
X3365081D01*
G01X3370396D02*
X3368231D01*
G01X3362621Y913763D02*
X3504747D01*
G01X3365081D02*
X3367247D01*
G01X3368231D02*
X3370396D01*
G01X3362621D02*
Y897228D01*
G01Y913763D02*
Y897228D01*
G01X3365081Y904708D02*
Y913763D01*
G01X3367247D02*
Y904708D01*
G01X3368231D02*
Y913763D01*
G01X3339885Y904708D02*
X3342050D01*
G01X3336735D02*
X3338900D01*
G01X3343034D02*
X3345200D01*
G01X3349333D02*
X3351499D01*
G01X3346184D02*
X3348349D01*
G01X3351499Y913763D02*
X3349333D01*
G01X3348349D02*
X3346184D01*
G01X3345200D02*
X3343034D01*
G01X3342050D02*
X3339885D01*
G01X3338900D02*
X3336735D01*
G01D02*
Y904708D01*
G01X3338900D02*
Y913763D01*
G01X3339885D02*
Y904708D01*
G01X3342050D02*
Y913763D01*
G01X3343034D02*
Y904708D01*
G01X3345200D02*
Y913763D01*
G01X3346184D02*
Y904708D01*
G01X3348349D02*
Y913763D01*
G01X3349333D02*
Y904708D01*
G01X3351499D02*
Y913763D01*
G01X3353959D02*
Y897228D01*
G01Y913763D02*
Y897228D01*
G01X3350022Y918881D02*
X3353959Y913763D01*
G01X3350022Y918881D02*
X3353959Y913763D01*
G01Y897228D02*
G03X3362621I4331J0D01*
G01X3353959D02*
G03X3362621I4331J0D01*
G01X3500810Y918881D02*
X3366558D01*
G01D02*
X3500810D01*
G01X3403381Y-1115412D02*
X3403868Y-1111803D01*
X3404355Y-1109638D01*
G01X3386329Y-1111081D02*
X3389252D01*
G01X3387221Y-1129166D02*
X3385795Y-1128215D01*
X3385083Y-1127265D01*
Y-1126314D01*
X3385795Y-1125364D01*
X3387221Y-1124413D01*
X3388647D01*
X3390073Y-1125364D01*
X3390786Y-1126314D01*
Y-1127265D01*
X3390073Y-1128215D01*
X3388647Y-1129166D01*
G01X3395585Y-1115412D02*
X3394611Y-1114690D01*
X3394124Y-1113969D01*
X3393637Y-1112525D01*
Y-1109638D01*
X3394124Y-1108194D01*
X3394611Y-1107473D01*
X3395585Y-1106751D01*
X3396560Y-1107473D01*
X3397047Y-1108194D01*
X3397534Y-1109638D01*
Y-1112525D01*
X3397047Y-1113969D01*
X3396560Y-1114690D01*
X3395585Y-1115412D01*
G01X3390073Y-1130117D02*
X3391499Y-1132018D01*
Y-1132968D01*
G01X3372200Y-1106751D02*
Y-1115412D01*
G01X3384369Y-1132968D02*
Y-1132018D01*
X3385795Y-1130117D01*
G01X3378046Y-1112525D02*
X3378533Y-1111081D01*
X3379995Y-1110360D01*
X3381457Y-1111081D01*
X3381944Y-1112525D01*
X3381457Y-1113969D01*
X3380969Y-1114690D01*
X3379995Y-1115412D01*
X3379020Y-1114690D01*
X3378533Y-1113969D01*
X3378046Y-1112525D01*
Y-1109638D01*
X3378533Y-1108194D01*
X3379020Y-1107473D01*
X3379995Y-1106751D01*
X3380969Y-1107473D01*
X3381457Y-1108194D01*
G01X3385795Y-1130117D02*
X3387221Y-1129166D01*
X3388647D01*
X3390073Y-1130117D01*
G01X3387221Y-1135820D02*
X3385795Y-1134870D01*
X3384369Y-1132968D01*
G01X3376527Y-1124413D02*
Y-1135820D01*
G01X3391499Y-1132968D02*
X3390073Y-1134870D01*
X3388647Y-1135820D01*
X3387221D01*
G01X3395585Y-1067774D02*
Y-1076436D01*
G01Y-1080766D02*
Y-1089428D01*
G01X3403381Y-1067774D02*
Y-1076436D01*
G01Y-1080766D02*
Y-1089428D01*
G01X3395585Y-1093758D02*
Y-1102420D01*
G01X3403381Y-1093758D02*
Y-1102420D01*
G01X3404355Y-1109638D02*
X3405330Y-1106751D01*
X3401432D01*
G01X3386329Y-1098089D02*
X3389252D01*
G01X3386329Y-1085097D02*
X3389252D01*
G01X3372200Y-1067774D02*
Y-1076436D01*
G01Y-1080766D02*
Y-1089428D01*
G01X3378046Y-1073549D02*
X3378533Y-1072105D01*
X3379995Y-1071383D01*
X3381457Y-1072105D01*
X3381944Y-1073549D01*
X3381457Y-1074992D01*
X3380969Y-1075714D01*
X3379995Y-1076436D01*
X3379020Y-1075714D01*
X3378533Y-1074992D01*
X3378046Y-1073549D01*
Y-1070662D01*
X3378533Y-1069218D01*
X3379020Y-1068496D01*
X3379995Y-1067774D01*
X3380969Y-1068496D01*
X3381457Y-1069218D01*
G01X3378046Y-1086541D02*
X3378533Y-1085097D01*
X3379995Y-1084375D01*
X3381457Y-1085097D01*
X3381944Y-1086541D01*
X3381457Y-1087984D01*
X3380969Y-1088706D01*
X3379995Y-1089428D01*
X3379020Y-1088706D01*
X3378533Y-1087984D01*
X3378046Y-1086541D01*
Y-1083654D01*
X3378533Y-1082210D01*
X3379020Y-1081488D01*
X3379995Y-1080766D01*
X3380969Y-1081488D01*
X3381457Y-1082210D01*
G01X3372200Y-1093758D02*
Y-1102420D01*
G01X3378046Y-1099533D02*
X3378533Y-1098089D01*
X3379995Y-1097368D01*
X3381457Y-1098089D01*
X3381944Y-1099533D01*
X3381457Y-1100977D01*
X3380969Y-1101698D01*
X3379995Y-1102420D01*
X3379020Y-1101698D01*
X3378533Y-1100977D01*
X3378046Y-1099533D01*
Y-1096646D01*
X3378533Y-1095202D01*
X3379020Y-1094481D01*
X3379995Y-1093758D01*
X3380969Y-1094481D01*
X3381457Y-1095202D01*
G01X3395585Y-1041790D02*
Y-1050451D01*
G01Y-1054782D02*
Y-1063444D01*
G01X3403381Y-1041790D02*
Y-1050451D01*
G01Y-1054782D02*
Y-1063444D01*
G01X3386329Y-1059113D02*
X3389252D01*
G01X3386329Y-1046121D02*
X3389252D01*
G01X3372200Y-1041790D02*
Y-1050451D01*
G01Y-1054782D02*
Y-1063444D01*
G01X3378046Y-1047564D02*
X3378533Y-1046121D01*
X3379995Y-1045399D01*
X3381457Y-1046121D01*
X3381944Y-1047564D01*
X3381457Y-1049008D01*
X3380969Y-1049730D01*
X3379995Y-1050451D01*
X3379020Y-1049730D01*
X3378533Y-1049008D01*
X3378046Y-1047564D01*
Y-1044677D01*
X3378533Y-1043234D01*
X3379020Y-1042512D01*
X3379995Y-1041790D01*
X3380969Y-1042512D01*
X3381457Y-1043234D01*
G01X3378046Y-1060557D02*
X3378533Y-1059113D01*
X3379995Y-1058391D01*
X3381457Y-1059113D01*
X3381944Y-1060557D01*
X3381457Y-1062000D01*
X3380969Y-1062722D01*
X3379995Y-1063444D01*
X3379020Y-1062722D01*
X3378533Y-1062000D01*
X3378046Y-1060557D01*
Y-1057670D01*
X3378533Y-1056226D01*
X3379020Y-1055504D01*
X3379995Y-1054782D01*
X3380969Y-1055504D01*
X3381457Y-1056226D01*
G01X3386329Y-1072105D02*
X3389252D01*
G01X3395585Y-1028798D02*
Y-1037459D01*
G01X3403381Y-1028798D02*
Y-1037459D01*
G01X3386329Y-1033129D02*
X3389252D01*
G01X3372200Y-1028798D02*
Y-1037459D01*
G01X3378046Y-1034572D02*
X3378533Y-1033129D01*
X3379995Y-1032407D01*
X3381457Y-1033129D01*
X3381944Y-1034572D01*
X3381457Y-1036016D01*
X3380969Y-1036738D01*
X3379995Y-1037459D01*
X3379020Y-1036738D01*
X3378533Y-1036016D01*
X3378046Y-1034572D01*
Y-1031685D01*
X3378533Y-1030242D01*
X3379020Y-1029520D01*
X3379995Y-1028798D01*
X3380969Y-1029520D01*
X3381457Y-1030242D01*
G01X3397403Y-71556D02*
X3396915D01*
Y-70834D01*
X3397403Y-71556D01*
G01X3405198D02*
X3404224Y-70834D01*
X3403736Y-70112D01*
X3403249Y-68668D01*
Y-65781D01*
X3403736Y-64338D01*
X3404224Y-63616D01*
X3405198Y-62894D01*
X3406172Y-63616D01*
X3406659Y-64338D01*
X3407146Y-65781D01*
Y-68668D01*
X3406659Y-70112D01*
X3406172Y-70834D01*
X3405198Y-71556D01*
G01X3391556Y-62894D02*
X3388633D01*
X3388146Y-66503D01*
X3389120Y-65781D01*
X3390094D01*
X3391069Y-66503D01*
X3391556Y-67225D01*
X3392043Y-68668D01*
X3391556Y-70112D01*
X3391069Y-70834D01*
X3390094Y-71556D01*
X3389120D01*
X3388146Y-70834D01*
X3387659Y-70112D01*
G01X3374161Y-67225D02*
X3374883Y-65060D01*
X3376326Y-63616D01*
X3378492Y-62894D01*
X3380657Y-63616D01*
X3382101Y-65060D01*
X3382822Y-67225D01*
X3382101Y-69390D01*
X3380657Y-70834D01*
X3378492Y-71556D01*
X3376326Y-70834D01*
X3374883Y-69390D01*
X3374161Y-67225D01*
G01X3374883Y-73721D02*
X3382101Y-60729D01*
G01X3387084Y-40577D02*
X3390007Y-46351D01*
G01X3382212D02*
Y-37689D01*
X3378802Y-44185D01*
X3383186D01*
G01X3392443Y-42020D02*
X3393165Y-39855D01*
X3394608Y-38411D01*
X3396774Y-37689D01*
X3398939Y-38411D01*
X3400383Y-39855D01*
X3401104Y-42020D01*
X3400383Y-44185D01*
X3398939Y-45629D01*
X3396774Y-46351D01*
X3394608Y-45629D01*
X3393165Y-44185D01*
X3392443Y-42020D01*
G01X3387084Y-46351D02*
X3390007Y-40577D01*
G01X3393165Y-48516D02*
X3400383Y-35524D01*
G01X3405042Y904708D02*
X3402877D01*
G01X3401893D02*
X3399727D01*
G01X3398743D02*
X3396578D01*
G01Y913763D02*
X3398743D01*
G01X3399727D02*
X3401893D01*
G01X3402877D02*
X3405042D01*
G01X3395593D02*
Y904708D01*
G01X3396578D02*
Y913763D01*
G01X3398743D02*
Y904708D01*
G01X3399727D02*
Y913763D01*
G01X3401893D02*
Y904708D01*
G01X3402877D02*
Y913763D01*
G01X3395593Y904708D02*
X3393428D01*
G01X3392444D02*
X3390278D01*
G01X3386144D02*
X3383979D01*
G01X3389294D02*
X3387129D01*
G01X3382995D02*
X3380830D01*
G01X3376696D02*
X3374530D01*
G01X3379845D02*
X3377680D01*
G01X3373546D02*
X3371381D01*
G01Y913763D02*
X3373546D01*
G01X3374530D02*
X3376696D01*
G01X3377680D02*
X3379845D01*
G01X3380830D02*
X3382995D01*
G01X3383979D02*
X3386144D01*
G01X3387129D02*
X3389294D01*
G01X3390278D02*
X3392444D01*
G01X3393428D02*
X3395593D01*
G01X3370396D02*
Y904708D01*
G01X3371381D02*
Y913763D01*
G01X3373546D02*
Y904708D01*
G01X3374530D02*
Y913763D01*
G01X3376696D02*
Y904708D01*
G01X3377680D02*
Y913763D01*
G01X3379845D02*
Y904708D01*
G01X3380830D02*
Y913763D01*
G01X3382995D02*
Y904708D01*
G01X3383979D02*
Y913763D01*
G01X3386144D02*
Y904708D01*
G01X3387129D02*
Y913763D01*
G01X3389294D02*
Y904708D01*
G01X3390278D02*
Y913763D01*
G01X3392444D02*
Y904708D01*
G01X3393428D02*
Y913763D01*
G01X3385795Y2161596D02*
X3387221Y2162547D01*
X3388647D01*
X3390073Y2161596D01*
G01X3391499Y2158744D02*
X3390073Y2156843D01*
X3388647Y2155892D01*
X3387221D01*
G01X3376527Y2167300D02*
Y2155892D01*
G01X3384369Y2158744D02*
Y2159695D01*
X3385795Y2161596D01*
G01X3387221Y2155892D02*
X3385795Y2156843D01*
X3384369Y2158744D01*
G01X3387221Y2162547D02*
X3385795Y2163497D01*
X3385083Y2164448D01*
Y2165399D01*
X3385795Y2166349D01*
X3387221Y2167300D01*
X3388647D01*
X3390073Y2166349D01*
X3390786Y2165399D01*
Y2164448D01*
X3390073Y2163497D01*
X3388647Y2162547D01*
G01X3390073Y2161596D02*
X3391499Y2159695D01*
Y2158744D01*
G01X3436331Y-1120137D02*
Y-965472D01*
G01X3409715Y-1111081D02*
X3412638D01*
G01X3418971Y-1115412D02*
X3417997Y-1114690D01*
X3417509Y-1113969D01*
X3417022Y-1112525D01*
Y-1109638D01*
X3417509Y-1108194D01*
X3417997Y-1107473D01*
X3418971Y-1106751D01*
X3419946Y-1107473D01*
X3420433Y-1108194D01*
X3420920Y-1109638D01*
Y-1112525D01*
X3420433Y-1113969D01*
X3419946Y-1114690D01*
X3418971Y-1115412D01*
G01X3428228D02*
Y-1106751D01*
X3424818Y-1113247D01*
X3429203D01*
G01X3436298Y-1093233D02*
X3602084D01*
G01X3409715Y-1098089D02*
X3412638D01*
G01X3409715Y-1085097D02*
X3412638D01*
G01X3418971Y-1089428D02*
X3417997Y-1088706D01*
X3417509Y-1087984D01*
X3417022Y-1086541D01*
Y-1083654D01*
X3417509Y-1082210D01*
X3417997Y-1081488D01*
X3418971Y-1080766D01*
X3419946Y-1081488D01*
X3420433Y-1082210D01*
X3420920Y-1083654D01*
Y-1086541D01*
X3420433Y-1087984D01*
X3419946Y-1088706D01*
X3418971Y-1089428D01*
G01Y-1076436D02*
X3417997Y-1075714D01*
X3417509Y-1074992D01*
X3417022Y-1073549D01*
Y-1070662D01*
X3417509Y-1069218D01*
X3417997Y-1068496D01*
X3418971Y-1067774D01*
X3419946Y-1068496D01*
X3420433Y-1069218D01*
X3420920Y-1070662D01*
Y-1073549D01*
X3420433Y-1074992D01*
X3419946Y-1075714D01*
X3418971Y-1076436D01*
G01X3428228Y-1089428D02*
Y-1080766D01*
X3424818Y-1087262D01*
X3429203D01*
G01X3426767Y-1076436D02*
X3427254Y-1072827D01*
X3427741Y-1070662D01*
X3428715Y-1067774D01*
G01X3418971Y-1102420D02*
X3417997Y-1101698D01*
X3417509Y-1100977D01*
X3417022Y-1099533D01*
Y-1096646D01*
X3417509Y-1095202D01*
X3417997Y-1094481D01*
X3418971Y-1093758D01*
X3419946Y-1094481D01*
X3420433Y-1095202D01*
X3420920Y-1096646D01*
Y-1099533D01*
X3420433Y-1100977D01*
X3419946Y-1101698D01*
X3418971Y-1102420D01*
G01X3426767Y-1093758D02*
Y-1102420D01*
G01X3436298Y-1044182D02*
X4155148D01*
G01X3436298Y-1068897D02*
X3880232D01*
G01X3428715Y-1067774D02*
X3424818D01*
G01X3409715Y-1059113D02*
X3412638D01*
G01X3409715Y-1046121D02*
X3412638D01*
G01X3428715Y-1041790D02*
X3425792D01*
X3425305Y-1045399D01*
X3426280Y-1044677D01*
X3427254D01*
X3428228Y-1045399D01*
X3428715Y-1046121D01*
X3429203Y-1047564D01*
X3428715Y-1049008D01*
X3428228Y-1049730D01*
X3427254Y-1050451D01*
X3426280D01*
X3425305Y-1049730D01*
X3424818Y-1049008D01*
G01X3418971Y-1063444D02*
X3417997Y-1062722D01*
X3417509Y-1062000D01*
X3417022Y-1060557D01*
Y-1057670D01*
X3417509Y-1056226D01*
X3417997Y-1055504D01*
X3418971Y-1054782D01*
X3419946Y-1055504D01*
X3420433Y-1056226D01*
X3420920Y-1057670D01*
Y-1060557D01*
X3420433Y-1062000D01*
X3419946Y-1062722D01*
X3418971Y-1063444D01*
G01Y-1041790D02*
Y-1050451D01*
G01X3428715Y-1057670D02*
X3428228Y-1059113D01*
X3426767Y-1059835D01*
X3425305Y-1059113D01*
X3424818Y-1057670D01*
X3425305Y-1056226D01*
X3425792Y-1055504D01*
X3426767Y-1054782D01*
X3427741Y-1055504D01*
X3428228Y-1056226D01*
X3428715Y-1057670D01*
Y-1060557D01*
X3428228Y-1062000D01*
X3427741Y-1062722D01*
X3426767Y-1063444D01*
X3425792Y-1062722D01*
X3425305Y-1062000D01*
G01X3409715Y-1072105D02*
X3412638D01*
G01X3436298Y-1019466D02*
X4155148D01*
G01X3409715Y-1033129D02*
X3412638D01*
G01X3418971Y-1028798D02*
Y-1037459D01*
G01X3424818Y-1034572D02*
X3425305Y-1033129D01*
X3426767Y-1032407D01*
X3428228Y-1033129D01*
X3428715Y-1034572D01*
X3428228Y-1036016D01*
X3427741Y-1036738D01*
X3426767Y-1037459D01*
X3425792Y-1036738D01*
X3425305Y-1036016D01*
X3424818Y-1034572D01*
Y-1031685D01*
X3425305Y-1030242D01*
X3425792Y-1029520D01*
X3426767Y-1028798D01*
X3427741Y-1029520D01*
X3428228Y-1030242D01*
G01X3436298Y-966232D02*
X4155148D01*
G01X3438328Y-69390D02*
X3437354Y-70834D01*
X3436379Y-71556D01*
X3435405Y-70834D01*
X3434430Y-69390D01*
Y-67947D01*
X3435405Y-66503D01*
X3436379Y-65781D01*
X3437354Y-66503D01*
X3438328Y-67947D01*
Y-69390D01*
G01X3412993Y-71556D02*
X3412019Y-70834D01*
X3411531Y-70112D01*
X3411044Y-68668D01*
Y-65781D01*
X3411531Y-64338D01*
X3412019Y-63616D01*
X3412993Y-62894D01*
X3413968Y-63616D01*
X3414455Y-64338D01*
X3414942Y-65781D01*
Y-68668D01*
X3414455Y-70112D01*
X3413968Y-70834D01*
X3412993Y-71556D01*
G01X3426635D02*
Y-62894D01*
X3430532Y-71556D01*
Y-62894D01*
G01X3421276D02*
X3420301Y-64338D01*
X3419814Y-66503D01*
Y-67947D01*
X3420301Y-70112D01*
X3421276Y-71556D01*
G01X3431275Y-46351D02*
X3430301Y-45629D01*
X3429813Y-44907D01*
X3429326Y-43464D01*
Y-40577D01*
X3429813Y-39133D01*
X3430301Y-38411D01*
X3431275Y-37689D01*
X3432250Y-38411D01*
X3432737Y-39133D01*
X3433224Y-40577D01*
Y-43464D01*
X3432737Y-44907D01*
X3432250Y-45629D01*
X3431275Y-46351D01*
G01X3415685D02*
X3415197D01*
Y-45629D01*
X3415685Y-46351D01*
G01X3421531Y-39133D02*
X3422018Y-38411D01*
X3422993Y-37689D01*
X3423967D01*
X3424941Y-38411D01*
X3425429Y-39133D01*
Y-40577D01*
X3424941Y-41298D01*
G01X3405940Y-39133D02*
X3406428Y-38411D01*
X3407402Y-37689D01*
X3408377D01*
X3409351Y-38411D01*
X3409838Y-39133D01*
Y-40577D01*
X3409351Y-41298D01*
G01D02*
X3407402Y-42742D01*
X3406428Y-44185D01*
X3405940Y-46351D01*
X3409838D01*
G01X3424941Y-41298D02*
X3422993Y-42742D01*
X3422018Y-44185D01*
X3421531Y-46351D01*
X3425429D01*
G01X3426548Y58763D02*
G03I-9843J0D01*
G01X3421036D02*
G03I-4331J0D01*
G01D02*
G03I-4331J0D01*
G01X3433389Y904708D02*
X3431223D01*
G01X3436538D02*
X3434373D01*
G01X3430239D02*
X3428074D01*
G01Y913763D02*
X3430239D01*
G01X3431223D02*
X3433389D01*
G01X3434373D02*
X3436538D01*
G01X3428074Y904708D02*
Y913763D01*
G01X3430239D02*
Y904708D01*
G01X3431223D02*
Y913763D01*
G01X3433389D02*
Y904708D01*
G01X3434373D02*
Y913763D01*
G01X3436538D02*
Y904708D01*
G01X3423940D02*
X3421774D01*
G01X3427089D02*
X3424924D01*
G01X3420790D02*
X3418625D01*
G01X3414491D02*
X3412326D01*
G01X3417641D02*
X3415475D01*
G01X3411341D02*
X3409176D01*
G01X3408192D02*
X3406026D01*
G01Y913763D02*
X3408192D01*
G01X3409176D02*
X3411341D01*
G01X3412326D02*
X3414491D01*
G01X3415475D02*
X3417641D01*
G01X3418625D02*
X3420790D01*
G01X3421774D02*
X3423940D01*
G01X3424924D02*
X3427089D01*
G01X3405042D02*
Y904708D01*
G01X3406026D02*
Y913763D01*
G01X3408192D02*
Y904708D01*
G01X3409176D02*
Y913763D01*
G01X3411341D02*
Y904708D01*
G01X3412326D02*
Y913763D01*
G01X3414491D02*
Y904708D01*
G01X3415475D02*
Y913763D01*
G01X3417641D02*
Y904708D01*
G01X3418625D02*
Y913763D01*
G01X3420790D02*
Y904708D01*
G01X3421774D02*
Y913763D01*
G01X3423940D02*
Y904708D01*
G01X3424924D02*
Y913763D01*
G01X3427089D02*
Y904708D01*
G01X3463509Y-1111213D02*
Y-1101707D01*
X3466233D01*
X3467322Y-1102499D01*
X3467867Y-1103291D01*
Y-1104876D01*
X3467322Y-1105668D01*
X3466233Y-1106460D01*
X3463509D01*
G01X3446626Y-1108044D02*
X3449894D01*
G01X3454796Y-1111213D02*
Y-1101707D01*
X3457519D01*
X3458608Y-1102499D01*
X3459152Y-1103291D01*
Y-1104876D01*
X3458608Y-1105668D01*
X3457519Y-1106460D01*
X3454796D01*
G01X3445537Y-1111213D02*
X3448260Y-1101707D01*
X3450983Y-1111213D01*
G01X3462915Y-1077480D02*
X3465028D01*
X3466084Y-1078272D01*
X3467140Y-1079857D01*
G01D02*
X3467669Y-1082233D01*
X3467140Y-1084610D01*
X3466084Y-1086194D01*
G01D02*
X3465028Y-1086986D01*
X3462915D01*
Y-1077480D01*
G01X3456578Y-1080649D02*
X3458691Y-1086986D01*
G01X3445487Y-1084610D02*
X3444959Y-1082233D01*
X3445487Y-1079857D01*
X3446544Y-1078272D01*
G01X3454465Y-1077480D02*
Y-1086986D01*
G01X3450241Y-1085402D02*
X3449713Y-1086194D01*
X3448656Y-1086986D01*
X3447600D01*
X3446544Y-1086194D01*
X3445487Y-1084610D01*
G01X3454465Y-1083025D02*
X3458691Y-1077480D01*
G01X3446544Y-1078272D02*
X3447600Y-1077480D01*
X3448656D01*
X3449713Y-1078272D01*
X3450241Y-1079064D01*
G01X3462915Y-1060804D02*
Y-1051297D01*
X3467140Y-1060804D01*
Y-1051297D01*
G01X3446016D02*
X3448128D01*
X3449184Y-1052090D01*
G01X3454994Y-1054466D02*
X3458162Y-1056843D01*
X3458691Y-1057635D01*
Y-1059220D01*
X3458162Y-1060012D01*
X3457106Y-1060804D01*
X3456050D01*
X3454994Y-1060012D01*
G01X3458691Y-1052882D02*
X3458162Y-1052090D01*
X3457106Y-1051297D01*
X3456050D01*
X3454994Y-1052090D01*
X3454465Y-1052882D01*
Y-1053674D01*
X3454994Y-1054466D01*
G01X3449184Y-1052090D02*
X3450241Y-1053674D01*
X3450769Y-1056051D01*
X3450241Y-1058427D01*
G01X3454994Y-1060012D02*
X3453937Y-1058427D01*
G01X3450241D02*
X3449184Y-1060012D01*
X3448128Y-1060804D01*
X3446016D01*
Y-1051297D01*
G01X3462915Y-1036577D02*
Y-1027071D01*
X3467140Y-1036577D01*
Y-1027071D01*
G01X3446016D02*
X3448128D01*
X3449184Y-1027863D01*
G01D02*
X3450241Y-1029447D01*
X3450769Y-1031824D01*
X3450241Y-1034200D01*
G01X3457106Y-1031824D02*
X3458691Y-1036577D01*
G01X3454465D02*
Y-1027071D01*
X3457106D01*
X3458162Y-1027863D01*
X3458691Y-1028655D01*
Y-1030239D01*
X3458162Y-1031032D01*
X3457106Y-1031824D01*
X3454465D01*
G01X3450241Y-1034200D02*
X3449184Y-1035784D01*
X3448128Y-1036577D01*
X3446016D01*
Y-1027071D01*
G01X3472516Y-999112D02*
X3468080D01*
Y-989607D01*
X3472516D01*
G01X3468080Y-994359D02*
X3470853D01*
G01X3459207Y-989607D02*
X3461426D01*
X3462535Y-990399D01*
X3463089Y-991191D01*
X3463644Y-991983D01*
X3464198Y-994359D01*
X3463644Y-996736D01*
G01X3450890Y-998320D02*
X3449781Y-996736D01*
X3449226Y-994359D01*
X3449781Y-991983D01*
X3450335Y-991191D01*
X3450890Y-990399D01*
X3451999Y-989607D01*
X3453108D01*
X3454217Y-990399D01*
G01D02*
X3455326Y-991983D01*
X3455880Y-994359D01*
X3455326Y-996736D01*
G01X3440909Y-999112D02*
Y-989607D01*
X3443681Y-997528D01*
X3446454Y-989607D01*
Y-999112D01*
G01X3455326Y-996736D02*
X3454217Y-998320D01*
X3453108Y-999112D01*
X3451999D01*
X3450890Y-998320D01*
G01X3463644Y-996736D02*
X3462535Y-998320D01*
X3461426Y-999112D01*
X3459207D01*
Y-989607D01*
G01X3469509Y-65781D02*
Y-71556D01*
G01Y-69390D02*
X3468534Y-70834D01*
X3467560Y-71556D01*
X3466586Y-70834D01*
X3465611Y-69390D01*
Y-67947D01*
X3466586Y-66503D01*
X3467560Y-65781D01*
X3468534Y-66503D01*
X3469509Y-67947D01*
G01X3450508Y-66503D02*
X3453431D01*
G01X3451970Y-71556D02*
Y-62894D01*
G01X3458303Y-71556D02*
Y-65781D01*
G01Y-67225D02*
X3459278Y-65781D01*
X3460252D01*
X3460739Y-66503D01*
G01X3468303Y-42020D02*
X3472200D01*
G01X3462456Y-37689D02*
Y-46351D01*
G01X3468303Y-37689D02*
Y-46351D01*
G01X3460020Y-37689D02*
X3464892D01*
G01X3452712Y-46351D02*
Y-37689D01*
X3455148D01*
X3456122Y-38411D01*
X3456609Y-39133D01*
Y-40577D01*
X3456122Y-41298D01*
X3455148Y-42020D01*
X3452712D01*
G01X3447353Y-37689D02*
X3446378Y-39133D01*
X3445891Y-41298D01*
Y-42742D01*
X3446378Y-44907D01*
X3447353Y-46351D01*
G01X3454550Y5495D02*
Y17306D01*
G01Y5495D02*
Y17306D01*
G01X3450613Y1558D02*
G03X3454550Y5495I0J3937D01*
G01X3450613Y1558D02*
G03X3454550Y5495I0J3937D01*
G01X3544511Y21243D02*
X3458487D01*
G01X3544511D02*
X3458487D01*
G01D02*
G03X3454550Y17306I0J-3937D01*
G01X3458487Y21243D02*
G03X3454550Y17306I0J-3937D01*
G01X3497857Y77149D02*
G03I-15748J0D01*
G01X3471184Y904708D02*
X3469019D01*
G01X3464885D02*
X3462719D01*
G01X3468034D02*
X3465869D01*
G01X3462719Y913763D02*
X3464885D01*
G01X3465869D02*
X3468034D01*
G01X3469019D02*
X3471184D01*
G01X3461735D02*
Y904708D01*
G01X3462719D02*
Y913763D01*
G01X3464885D02*
Y904708D01*
G01X3465869D02*
Y913763D01*
G01X3468034D02*
Y904708D01*
G01X3469019D02*
Y913763D01*
G01X3461735Y904708D02*
X3459570D01*
G01X3458585D02*
X3456420D01*
G01X3452286D02*
X3450121D01*
G01X3455436D02*
X3453270D01*
G01X3449137D02*
X3446971D01*
G01X3442837D02*
X3440672D01*
G01X3445987D02*
X3443822D01*
G01X3439688D02*
X3437522D01*
G01Y913763D02*
X3439688D01*
G01X3440672D02*
X3442837D01*
G01X3443822D02*
X3445987D01*
G01X3446971D02*
X3449137D01*
G01X3450121D02*
X3452286D01*
G01X3453270D02*
X3455436D01*
G01X3456420D02*
X3458585D01*
G01X3459570D02*
X3461735D01*
G01X3437522Y904708D02*
Y913763D01*
G01X3439688D02*
Y904708D01*
G01X3440672D02*
Y913763D01*
G01X3442837D02*
Y904708D01*
G01X3443822D02*
Y913763D01*
G01X3445987D02*
Y904708D01*
G01X3446971D02*
Y913763D01*
G01X3449137D02*
Y904708D01*
G01X3450121D02*
Y913763D01*
G01X3452286D02*
Y904708D01*
G01X3453270D02*
Y913763D01*
G01X3455436D02*
Y904708D01*
G01X3456420D02*
Y913763D01*
G01X3458585D02*
Y904708D01*
G01X3459570D02*
Y913763D01*
G01X3486870Y-1093233D02*
Y-1120610D01*
G01D02*
X3570524D01*
G01X3475491Y-1102499D02*
X3476580Y-1104084D01*
X3477125Y-1106460D01*
X3476580Y-1108836D01*
G01X3486870Y-966232D02*
Y-1120610D01*
G01X3476580Y-1108836D02*
X3475491Y-1110421D01*
X3474402Y-1111213D01*
X3472224D01*
Y-1101707D01*
G01X3488699Y-1120610D02*
Y-1139623D01*
G01X3486870Y-1068897D02*
Y-1093233D01*
G01D02*
X3570524D01*
G01X3486870D02*
X3570524D01*
G01X3472224Y-1101707D02*
X3474402D01*
X3475491Y-1102499D01*
G01X3486870Y-1019466D02*
Y-1044072D01*
G01D02*
X3570335D01*
G01X3486870Y-1044182D02*
X3570335D01*
G01X3486870D02*
Y-1068788D01*
G01D02*
X3570335D01*
G01X3486870Y-1068897D02*
X3570524D01*
G01X3486671Y-966461D02*
Y-1019365D01*
G01D02*
X3601828D01*
G01X3486870Y-1019466D02*
X3570335D01*
G01X3476952Y-989607D02*
Y-999112D01*
X3481389D01*
G01X3486671Y-966461D02*
X3601828D01*
G01X3500690Y-65781D02*
Y-71556D01*
G01Y-69390D02*
X3499715Y-70834D01*
X3498741Y-71556D01*
X3497767Y-70834D01*
X3496793Y-69390D01*
Y-67947D01*
X3497767Y-66503D01*
X3498741Y-65781D01*
X3499715Y-66503D01*
X3500690Y-67947D01*
G01X3484612Y-70112D02*
X3484125Y-70834D01*
X3483150Y-71556D01*
X3482176Y-70834D01*
X3481202Y-69390D01*
Y-67947D01*
X3482176Y-66503D01*
X3483150Y-65781D01*
X3484125Y-66503D01*
X3484612Y-67947D01*
X3481202D01*
G01X3476330Y-70834D02*
X3475356Y-71556D01*
X3474381Y-70834D01*
X3473407Y-69390D01*
Y-67947D01*
X3474381Y-66503D01*
X3475356Y-65781D01*
X3476330Y-66503D01*
G01X3477559Y-37689D02*
X3478534Y-39133D01*
X3479021Y-41298D01*
Y-42742D01*
X3478534Y-44907D01*
X3477559Y-46351D01*
G01X3472200Y-37689D02*
Y-46351D01*
G01X3488408Y77149D02*
G03I-6299J0D01*
G01D02*
G03I-6299J0D01*
G01X3516558Y157070D02*
G03I-7480J0D01*
G01D02*
G03I-7480J0D01*
G01X3524826D02*
G03I-15748J0D01*
G01Y822425D02*
G03I-15748J0D01*
G01X3516558D02*
G03I-7480J0D01*
G01D02*
G03I-7480J0D01*
G01X3501866Y903824D02*
X3501989Y903866D01*
G01Y902987D02*
X3501866Y902945D01*
G01X3501661Y903070D02*
X3501743Y903112D01*
G01X3501661Y903950D02*
X3501825Y904075D01*
G01X3501784Y903740D02*
X3501866Y903824D01*
G01Y902945D02*
X3501784Y902861D01*
G01X3500923Y902484D02*
X3501169Y902777D01*
G01Y902442D02*
X3500923Y902149D01*
G01X3501538Y903782D02*
X3501661Y903950D01*
G01X3501538Y902903D02*
X3501661Y903070D01*
G01X3501825Y904075D02*
X3502030Y904118D01*
G01X3503015Y902149D02*
X3502030D01*
G01X3500923D02*
X3500677D01*
G01X3501989Y902400D02*
X3502769D01*
G01Y902987D02*
X3501989D01*
G01X3502769Y903238D02*
X3501989D01*
G01Y903866D02*
X3502769D01*
G01X3502030Y904118D02*
X3503015D01*
G01X3500677D02*
X3500923D01*
G01X3502680Y904708D02*
X3500515D01*
G01X3499530D02*
X3497365D01*
G01Y913763D02*
X3499530D01*
G01X3500515D02*
X3502680D01*
G01X3501497Y903657D02*
X3501538Y903782D01*
G01X3501743Y903615D02*
X3501784Y903740D01*
G01X3501497Y902777D02*
X3501538Y902903D01*
G01X3501784Y902861D02*
X3501743Y902735D01*
G01X3502030Y902149D02*
X3501825Y902191D01*
G01X3501866Y902442D02*
X3501989Y902400D01*
G01Y903238D02*
X3501866Y903280D01*
G01X3496381Y913763D02*
Y904708D01*
G01X3497365D02*
Y913763D01*
G01X3499530D02*
Y904708D01*
G01X3500515D02*
Y913763D01*
G01X3500677Y902149D02*
Y904118D01*
G01X3500923D02*
Y902484D01*
G01X3501169Y902777D02*
Y902442D01*
G01X3501497Y902610D02*
Y902777D01*
G01Y903447D02*
Y903657D01*
G01X3501743Y902735D02*
Y902651D01*
G01Y903489D02*
Y903615D01*
G01X3502680Y913763D02*
Y904708D01*
G01X3502769Y903866D02*
Y903238D01*
G01Y902400D02*
Y902987D01*
G01X3503015Y904118D02*
Y902149D01*
G01X3504747Y896834D02*
Y913763D01*
G01Y896834D02*
Y913763D01*
G01X3501743Y903112D02*
X3501661Y903154D01*
G01X3501825Y902191D02*
X3501661Y902316D01*
G01X3501784Y902526D02*
X3501866Y902442D01*
G01Y903280D02*
X3501784Y903364D01*
G01X3500810Y918881D02*
X3504747Y913763D01*
G01X3500810Y918881D02*
X3504747Y913763D01*
G01X3501661Y902316D02*
X3501538Y902484D01*
G01X3501661Y903154D02*
X3501538Y903322D01*
G01Y902484D02*
X3501497Y902610D01*
G01X3501743Y902651D02*
X3501784Y902526D01*
G01X3501538Y903322D02*
X3501497Y903447D01*
G01X3501784Y903364D02*
X3501743Y903489D01*
G01X3504747Y896834D02*
G03X3506715Y894866I1968J0D01*
G01X3504747Y896834D02*
G03X3506715Y894866I1968J0D01*
G01X3493231Y904708D02*
X3491066D01*
G01X3496381D02*
X3494215D01*
G01X3490081D02*
X3487916D01*
G01X3483782D02*
X3481617D01*
G01X3486932D02*
X3484767D01*
G01X3480633D02*
X3478467D01*
G01X3474333D02*
X3472168D01*
G01X3477483D02*
X3475318D01*
G01X3472168Y913763D02*
X3474333D01*
G01X3475318D02*
X3477483D01*
G01X3478467D02*
X3480633D01*
G01X3481617D02*
X3483782D01*
G01X3484767D02*
X3486932D01*
G01X3487916D02*
X3490081D01*
G01X3491066D02*
X3493231D01*
G01X3494215D02*
X3496381D01*
G01X3471184D02*
Y904708D01*
G01X3472168D02*
Y913763D01*
G01X3474333D02*
Y904708D01*
G01X3475318D02*
Y913763D01*
G01X3477483D02*
Y904708D01*
G01X3478467D02*
Y913763D01*
G01X3480633D02*
Y904708D01*
G01X3481617D02*
Y913763D01*
G01X3483782D02*
Y904708D01*
G01X3484767D02*
Y913763D01*
G01X3486932D02*
Y904708D01*
G01X3487916D02*
Y913763D01*
G01X3490081D02*
Y904708D01*
G01X3491066D02*
Y913763D01*
G01X3493231D02*
Y904708D01*
G01X3494215D02*
Y913763D01*
G01X3488699Y2171102D02*
Y2152090D01*
G01X3529922Y-71556D02*
Y-62894D01*
G01X3537717Y-71556D02*
Y-62894D01*
G01X3505075Y-66503D02*
X3507998D01*
G01X3506536Y-71556D02*
Y-62894D01*
G01X3524076Y-65781D02*
Y-71556D01*
G01Y-69390D02*
X3523101Y-70834D01*
X3522127Y-71556D01*
X3521152Y-70834D01*
X3520178Y-69390D01*
Y-67947D01*
X3521152Y-66503D01*
X3522127Y-65781D01*
X3523101Y-66503D01*
X3524076Y-67947D01*
G01X3531396Y40524D02*
X3593927Y19828D01*
G01X3536565Y31381D02*
X3608706Y-40588D01*
G01X3541164Y42503D02*
G03I-15748J0D01*
G01X3531715D02*
G03I-6299J0D01*
G01D02*
G03I-6299J0D01*
G01X3541164Y111795D02*
G03I-15748J0D01*
G01X3531715D02*
G03I-6299J0D01*
G01D02*
G03I-6299J0D01*
G01X3515939Y160049D02*
X3593625Y193780D01*
G01X3520562Y167845D02*
X3592667Y235497D01*
G01X3532700Y324393D02*
X3548448D01*
G01X3532700Y861795D02*
Y324393D01*
G01X3547267Y495062D02*
X3534432D01*
G01Y496667D02*
X3539620D01*
G01Y504154D02*
X3534432D01*
G01Y505758D02*
X3547267D01*
G01X3539620Y507897D02*
X3538528D01*
G01Y512175D02*
X3539620D01*
G01X3534432Y495062D02*
Y496667D01*
G01Y504154D02*
Y505758D01*
G01X3538528Y507897D02*
Y512175D01*
G01X3539620Y523940D02*
X3538255Y523673D01*
G01X3539893Y522603D02*
X3538255Y522336D01*
G01X3547267Y526079D02*
X3538528D01*
G01Y527416D02*
X3539347D01*
G01X3547267Y538112D02*
X3538528D01*
G01Y539449D02*
X3539347D01*
G01X3538255Y523673D02*
X3537436Y523406D01*
G01D02*
X3536343Y522871D01*
G01X3538255Y522336D02*
X3536617Y521266D01*
G01X3536343Y522871D02*
X3535524Y522069D01*
G01X3536617Y521266D02*
X3536070Y520464D01*
G01X3535524Y522069D02*
X3534705Y520732D01*
G01X3538528Y546134D02*
X3538801Y546936D01*
G01X3538528Y541855D02*
X3538801Y542658D01*
G01X3538528Y534101D02*
X3538801Y534903D01*
G01X3538528Y529823D02*
X3538801Y530625D01*
G01X3538528Y526079D02*
Y527416D01*
G01Y528753D02*
Y529823D01*
G01Y533032D02*
Y534101D01*
G01Y538112D02*
Y539449D01*
G01Y540786D02*
Y541855D01*
G01Y545064D02*
Y546134D01*
G01X3534705Y520732D02*
X3534432Y519127D01*
G01X3536070Y520464D02*
X3535797Y519127D01*
G01X3538801Y527951D02*
X3538528Y528753D01*
G01X3538801Y532229D02*
X3538528Y533032D01*
G01X3538801Y539984D02*
X3538528Y540786D01*
G01X3538801Y544262D02*
X3538528Y545064D01*
G01X3535797Y519127D02*
X3536070Y517790D01*
G01X3534432Y519127D02*
X3534705Y517523D01*
G01X3538255Y515919D02*
X3539893Y515651D01*
G01X3538255Y514582D02*
X3539620Y514314D01*
G01X3537436Y514849D02*
X3538255Y514582D01*
G01X3536343Y515384D02*
X3537436Y514849D01*
G01X3536617Y516988D02*
X3538255Y515919D01*
G01X3535524Y516186D02*
X3536343Y515384D01*
G01X3536070Y517790D02*
X3536617Y516988D01*
G01X3534705Y517523D02*
X3535524Y516186D01*
G01X3516211Y824675D02*
X3569452Y841471D01*
G01X3519672Y834077D02*
X3567893Y887113D01*
G01X3516952Y861795D02*
X3544511D01*
G01X3511833Y866913D02*
Y892897D01*
G01Y866913D02*
Y892897D01*
G01Y866913D02*
G03X3516952Y861795I5118J0D01*
G01X3511833Y866913D02*
G03X3516952Y861795I5118J0D01*
G01X3509865Y894866D02*
X3506715D01*
G01X3509865D02*
X3506715D01*
G01X3511833Y892897D02*
G03X3509865Y894866I-1969J0D01*
G01X3511833Y892897D02*
G03X3509865Y894866I-1969J0D01*
G01X3570524Y-1093233D02*
Y-1120610D01*
G01Y-1093233D02*
Y-1120610D01*
G01D02*
X3602084D01*
G01X3570524Y-1019466D02*
Y-1120610D01*
G01Y-1068897D02*
Y-1093233D01*
G01X3570327Y-1068874D02*
Y-1093210D01*
G01D02*
X3601887D01*
G01X3570524Y-1093233D02*
X3602084D01*
G01X3570335Y-1019466D02*
Y-1044072D01*
G01X3570979Y-1019406D02*
Y-1044012D01*
G01D02*
X3602475D01*
G01X3570524Y-1044182D02*
X3602020D01*
G01X3570335D02*
Y-1068788D01*
G01X3570524Y-1044182D02*
Y-1068788D01*
G01D02*
X3602020D01*
G01X3570327Y-1068874D02*
X3601887D01*
G01X3570979Y-1019406D02*
X3602475D01*
G01X3566950Y-65781D02*
X3568898Y-70834D01*
X3568411Y-72999D01*
X3567437Y-74443D01*
X3566463D01*
G01X3563052Y-65781D02*
Y-71556D01*
G01X3568898Y-70834D02*
X3570848Y-65781D01*
G01X3553308Y-71556D02*
Y-62894D01*
G01X3563052Y-69390D02*
X3562078Y-70834D01*
X3561103Y-71556D01*
X3560129Y-70834D01*
X3559154Y-69390D01*
Y-67947D01*
X3560129Y-66503D01*
X3561103Y-65781D01*
X3562078Y-66503D01*
X3563052Y-67947D01*
G01X3548448Y25180D02*
Y57464D01*
G01Y25180D02*
Y57464D01*
G01X3544511Y21243D02*
G03X3548448Y25180I0J3937D01*
G01X3544511Y21243D02*
G03X3548448Y25180I0J3937D01*
G01X3546479Y59432D02*
X3545101D01*
G01X3543133Y92897D02*
Y61401D01*
G01Y92897D02*
Y61401D01*
G01X3548448Y57464D02*
G03X3546479Y59432I-1969J-1D01*
G01X3543133Y61401D02*
G03X3545101Y59432I1969J0D01*
G01X3546479Y94866D02*
X3545101D01*
G01X3548448Y96834D02*
Y857858D01*
G01D02*
Y96834D01*
G01X3546479Y94866D02*
G03X3548448Y96834I1J1968D01*
G01X3545101Y94866D02*
G03X3543133Y92897I1J-1969D01*
G01X3541259Y496667D02*
X3547267D01*
G01Y504154D02*
X3541259D01*
G01X3542897Y507897D02*
X3541805D01*
G01Y512175D02*
X3542897D01*
G01X3539620D02*
Y507897D01*
G01Y496667D02*
Y504154D01*
G01X3541259D02*
Y496667D01*
G01X3541805Y507897D02*
Y512175D01*
G01X3542897D02*
Y507897D01*
G01X3547267Y505758D02*
Y504154D01*
G01Y496667D02*
Y495062D01*
G01X3541805Y522603D02*
X3539893D01*
G01X3542078Y523940D02*
X3539620D01*
G01X3540439Y527416D02*
X3547267D01*
G01Y530358D02*
X3540713D01*
G01Y531695D02*
X3547267D01*
G01Y534636D02*
X3540713D01*
G01Y535973D02*
X3547267D01*
G01X3540439Y539449D02*
X3547267D01*
G01Y542390D02*
X3540713D01*
G01Y543727D02*
X3547267D01*
G01X3539347Y535438D02*
X3540713Y535973D01*
G01Y542390D02*
X3540167Y542123D01*
G01X3540713Y534636D02*
X3540167Y534368D01*
G01X3540713Y530358D02*
X3540167Y530090D01*
G01X3543443Y522336D02*
X3541805Y522603D01*
G01X3543443Y523673D02*
X3542078Y523940D01*
G01X3544263Y523406D02*
X3543443Y523673D01*
G01X3540167Y546401D02*
X3539893Y546134D01*
G01X3538801Y542658D02*
X3539620Y543460D01*
G01X3545355Y522871D02*
X3544263Y523406D01*
G01X3540167Y531962D02*
X3540713Y531695D01*
G01X3540167Y543994D02*
X3540713Y543727D01*
G01X3540167Y542123D02*
X3539893Y541855D01*
G01X3538801Y534903D02*
X3539347Y535438D01*
G01X3540167Y534368D02*
X3539893Y534101D01*
G01X3538801Y530625D02*
X3539620Y531427D01*
G01X3540167Y530090D02*
X3539893Y529823D01*
G01X3545082Y521266D02*
X3543443Y522336D01*
G01X3539893Y546134D02*
X3539620Y545599D01*
G01X3539893Y541855D02*
X3539620Y541321D01*
G01X3539893Y534101D02*
X3539620Y533566D01*
G01X3539893Y529823D02*
X3539620Y529288D01*
G01X3539347Y527416D02*
X3538801Y527951D01*
G01X3539893D02*
X3540439Y527416D01*
G01X3546174Y522069D02*
X3545355Y522871D01*
G01X3539620Y531427D02*
X3538801Y532229D01*
G01X3539893D02*
X3540167Y531962D01*
G01X3539347Y539449D02*
X3538801Y539984D01*
G01X3539893D02*
X3540439Y539449D01*
G01X3539620Y543460D02*
X3538801Y544262D01*
G01X3539893D02*
X3540167Y543994D01*
G01X3545628Y520464D02*
X3545082Y521266D01*
G01X3546993Y520732D02*
X3546174Y522069D01*
G01X3539620Y545599D02*
Y544797D01*
G01Y541321D02*
Y540786D01*
G01Y533566D02*
Y532764D01*
G01Y529288D02*
Y528753D01*
G01X3547267Y543727D02*
Y542390D01*
G01Y535973D02*
Y534636D01*
G01Y539449D02*
Y538112D01*
G01Y531695D02*
Y530358D01*
G01Y527416D02*
Y526079D01*
G01X3546993Y517523D02*
X3547267Y519127D01*
G01X3545628Y517790D02*
X3545901Y519127D01*
G01X3539620Y532764D02*
X3539893Y532229D01*
G01X3539620Y544797D02*
X3539893Y544262D01*
G01X3539620Y528753D02*
X3539893Y527951D01*
G01X3539620Y540786D02*
X3539893Y539984D01*
G01X3545901Y519127D02*
X3545628Y520464D01*
G01X3547267Y519127D02*
X3546993Y520732D01*
G01X3542078Y514314D02*
X3543443Y514582D01*
G01X3541805Y515651D02*
X3543443Y515919D01*
G01X3539620Y514314D02*
X3542078D01*
G01X3539893Y515651D02*
X3541805D01*
G01X3543443Y514582D02*
X3544263Y514849D01*
G01D02*
X3545355Y515384D01*
G01X3543443Y515919D02*
X3545082Y516988D01*
G01X3545355Y515384D02*
X3546174Y516186D01*
G01D02*
X3546993Y517523D01*
G01X3545082Y516988D02*
X3545628Y517790D01*
G01X3547267Y546668D02*
X3540713D01*
G01Y548005D02*
X3547267D01*
G01X3539347Y547471D02*
X3540713Y548005D01*
G01Y546668D02*
X3540167Y546401D01*
G01X3538801Y546936D02*
X3539347Y547471D01*
G01X3547267Y548005D02*
Y546668D01*
G01X3569452Y841471D02*
X3572602D01*
G01X3548448Y857858D02*
G03X3544511Y861795I-3937J0D01*
G01X3548448Y857858D02*
G03X3544511Y861795I-3937J0D01*
G01X3567893Y887113D02*
X3571043D01*
G01D02*
X3631095D01*
G01X3602084Y-1093233D02*
Y-1120610D01*
G01Y-966232D02*
Y-1120610D01*
G01X3597068Y-1124413D02*
Y-1135820D01*
G01X3611327Y-1128215D02*
X3610614Y-1130117D01*
X3608476Y-1131067D01*
X3606337Y-1130117D01*
X3605624Y-1128215D01*
X3606337Y-1126314D01*
X3607050Y-1125364D01*
X3608476Y-1124413D01*
X3609901Y-1125364D01*
X3610614Y-1126314D01*
X3611327Y-1128215D01*
Y-1132018D01*
X3610614Y-1133919D01*
X3609901Y-1134870D01*
X3608476Y-1135820D01*
X3607050Y-1134870D01*
X3606337Y-1133919D01*
G01X3576383Y-1109546D02*
X3576737Y-1109021D01*
X3577446Y-1108497D01*
X3578155D01*
X3578863Y-1109021D01*
X3579218Y-1109546D01*
Y-1110596D01*
X3578863Y-1111121D01*
X3578155Y-1111646D01*
X3577446Y-1112171D01*
X3576737Y-1113221D01*
X3576383Y-1114796D01*
X3579218D01*
G01X3583470D02*
X3582761Y-1114271D01*
X3582407Y-1113746D01*
X3582052Y-1112696D01*
Y-1110596D01*
X3582407Y-1109546D01*
X3582761Y-1109021D01*
X3583470Y-1108497D01*
X3584178Y-1109021D01*
X3584532Y-1109546D01*
X3584887Y-1110596D01*
Y-1112696D01*
X3584532Y-1113746D01*
X3584178Y-1114271D01*
X3583470Y-1114796D01*
G01X3589139Y-1108497D02*
Y-1114796D01*
G01X3593391Y-1112696D02*
X3593745Y-1111646D01*
X3594808Y-1111121D01*
X3595871Y-1111646D01*
X3596226Y-1112696D01*
X3595871Y-1113746D01*
X3595517Y-1114271D01*
X3594808Y-1114796D01*
X3594100Y-1114271D01*
X3593745Y-1113746D01*
X3593391Y-1112696D01*
Y-1110596D01*
X3593745Y-1109546D01*
X3594100Y-1109021D01*
X3594808Y-1108497D01*
X3595517Y-1109021D01*
X3595871Y-1109546D01*
G01X3601887Y-1068874D02*
Y-1093210D01*
G01X3577603Y-1079467D02*
X3576894Y-1078942D01*
X3576540Y-1078418D01*
X3576186Y-1077368D01*
Y-1075268D01*
X3576540Y-1074218D01*
X3576894Y-1073693D01*
X3577603Y-1073168D01*
X3578312Y-1073693D01*
X3578666Y-1074218D01*
X3579020Y-1075268D01*
Y-1077368D01*
X3578666Y-1078418D01*
X3578312Y-1078942D01*
X3577603Y-1079467D01*
G01X3584690Y-1073168D02*
X3582564D01*
X3582209Y-1075793D01*
X3582918Y-1075268D01*
X3583627D01*
X3584335Y-1075793D01*
X3584690Y-1076318D01*
X3585044Y-1077368D01*
X3584690Y-1078418D01*
X3584335Y-1078942D01*
X3583627Y-1079467D01*
X3582918D01*
X3582209Y-1078942D01*
X3581855Y-1078418D01*
G01X3588942Y-1079467D02*
X3588233Y-1078942D01*
X3587879Y-1078418D01*
X3587524Y-1077368D01*
Y-1075268D01*
X3587879Y-1074218D01*
X3588233Y-1073693D01*
X3588942Y-1073168D01*
X3589650Y-1073693D01*
X3590005Y-1074218D01*
X3590359Y-1075268D01*
Y-1077368D01*
X3590005Y-1078418D01*
X3589650Y-1078942D01*
X3588942Y-1079467D01*
G01X3596028Y-1075268D02*
X3595674Y-1076318D01*
X3594611Y-1076843D01*
X3593548Y-1076318D01*
X3593194Y-1075268D01*
X3593548Y-1074218D01*
X3593902Y-1073693D01*
X3594611Y-1073168D01*
X3595320Y-1073693D01*
X3595674Y-1074218D01*
X3596028Y-1075268D01*
Y-1077368D01*
X3595674Y-1078418D01*
X3595320Y-1078942D01*
X3594611Y-1079467D01*
X3593902Y-1078942D01*
X3593548Y-1078418D01*
G01X3576186Y-1083667D02*
X3576540Y-1083142D01*
X3577249Y-1082617D01*
X3577957D01*
X3578666Y-1083142D01*
X3579020Y-1083667D01*
Y-1084717D01*
X3578666Y-1085242D01*
X3577957Y-1085767D01*
X3577249Y-1086292D01*
X3576540Y-1087342D01*
X3576186Y-1088916D01*
X3579020D01*
G01X3583272D02*
X3582564Y-1088391D01*
X3582209Y-1087866D01*
X3581855Y-1086816D01*
Y-1084717D01*
X3582209Y-1083667D01*
X3582564Y-1083142D01*
X3583272Y-1082617D01*
X3583981Y-1083142D01*
X3584335Y-1083667D01*
X3584690Y-1084717D01*
Y-1086816D01*
X3584335Y-1087866D01*
X3583981Y-1088391D01*
X3583272Y-1088916D01*
G01X3588942Y-1082617D02*
Y-1088916D01*
G01X3593194Y-1086816D02*
X3593548Y-1085767D01*
X3594611Y-1085242D01*
X3595674Y-1085767D01*
X3596028Y-1086816D01*
X3595674Y-1087866D01*
X3595320Y-1088391D01*
X3594611Y-1088916D01*
X3593902Y-1088391D01*
X3593548Y-1087866D01*
X3593194Y-1086816D01*
Y-1084717D01*
X3593548Y-1083667D01*
X3593902Y-1083142D01*
X3594611Y-1082617D01*
X3595320Y-1083142D01*
X3595674Y-1083667D01*
G01X3577800Y-1105347D02*
X3577092Y-1104822D01*
X3576737Y-1104297D01*
X3576383Y-1103247D01*
Y-1101147D01*
X3576737Y-1100097D01*
X3577092Y-1099573D01*
X3577800Y-1099048D01*
X3578509Y-1099573D01*
X3578863Y-1100097D01*
X3579218Y-1101147D01*
Y-1103247D01*
X3578863Y-1104297D01*
X3578509Y-1104822D01*
X3577800Y-1105347D01*
G01X3584887Y-1099048D02*
X3582761D01*
X3582407Y-1101672D01*
X3583115Y-1101147D01*
X3583824D01*
X3584532Y-1101672D01*
X3584887Y-1102197D01*
X3585241Y-1103247D01*
X3584887Y-1104297D01*
X3584532Y-1104822D01*
X3583824Y-1105347D01*
X3583115D01*
X3582407Y-1104822D01*
X3582052Y-1104297D01*
G01X3589139Y-1105347D02*
X3588430Y-1104822D01*
X3588076Y-1104297D01*
X3587722Y-1103247D01*
Y-1101147D01*
X3588076Y-1100097D01*
X3588430Y-1099573D01*
X3589139Y-1099048D01*
X3589848Y-1099573D01*
X3590202Y-1100097D01*
X3590556Y-1101147D01*
Y-1103247D01*
X3590202Y-1104297D01*
X3589848Y-1104822D01*
X3589139Y-1105347D01*
G01X3596226Y-1101147D02*
X3595871Y-1102197D01*
X3594808Y-1102722D01*
X3593745Y-1102197D01*
X3593391Y-1101147D01*
X3593745Y-1100097D01*
X3594100Y-1099573D01*
X3594808Y-1099048D01*
X3595517Y-1099573D01*
X3595871Y-1100097D01*
X3596226Y-1101147D01*
Y-1103247D01*
X3595871Y-1104297D01*
X3595517Y-1104822D01*
X3594808Y-1105347D01*
X3594100Y-1104822D01*
X3593745Y-1104297D01*
G01X3602475Y-1019406D02*
Y-1044012D01*
G01X3602020Y-1044182D02*
Y-1068788D01*
G01X3578713Y-1054910D02*
X3578083Y-1054385D01*
X3577768Y-1053860D01*
X3577454Y-1052810D01*
Y-1050710D01*
X3577768Y-1049660D01*
X3578083Y-1049136D01*
X3578713Y-1048611D01*
X3579343Y-1049136D01*
X3579658Y-1049660D01*
X3579973Y-1050710D01*
Y-1052810D01*
X3579658Y-1053860D01*
X3579343Y-1054385D01*
X3578713Y-1054910D01*
G01X3585012Y-1048611D02*
X3583122D01*
X3582807Y-1051235D01*
X3583438Y-1050710D01*
X3584067D01*
X3584697Y-1051235D01*
X3585012Y-1051760D01*
X3585327Y-1052810D01*
X3585012Y-1053860D01*
X3584697Y-1054385D01*
X3584067Y-1054910D01*
X3583438D01*
X3582807Y-1054385D01*
X3582493Y-1053860D01*
G01X3588792Y-1054910D02*
X3588162Y-1054385D01*
X3587847Y-1053860D01*
X3587532Y-1052810D01*
Y-1050710D01*
X3587847Y-1049660D01*
X3588162Y-1049136D01*
X3588792Y-1048611D01*
X3589422Y-1049136D01*
X3589737Y-1049660D01*
X3590052Y-1050710D01*
Y-1052810D01*
X3589737Y-1053860D01*
X3589422Y-1054385D01*
X3588792Y-1054910D01*
G01X3595091Y-1050710D02*
X3594776Y-1051760D01*
X3593831Y-1052285D01*
X3592886Y-1051760D01*
X3592571Y-1050710D01*
X3592886Y-1049660D01*
X3593201Y-1049136D01*
X3593831Y-1048611D01*
X3594461Y-1049136D01*
X3594776Y-1049660D01*
X3595091Y-1050710D01*
Y-1052810D01*
X3594776Y-1053860D01*
X3594461Y-1054385D01*
X3593831Y-1054910D01*
X3593201Y-1054385D01*
X3592886Y-1053860D01*
G01X3577454Y-1059109D02*
X3577768Y-1058584D01*
X3578398Y-1058060D01*
X3579028D01*
X3579658Y-1058584D01*
X3579973Y-1059109D01*
Y-1060159D01*
X3579658Y-1060684D01*
X3579028Y-1061209D01*
X3578398Y-1061734D01*
X3577768Y-1062784D01*
X3577454Y-1064359D01*
X3579973D01*
G01X3583752D02*
X3583122Y-1063834D01*
X3582807Y-1063309D01*
X3582493Y-1062259D01*
Y-1060159D01*
X3582807Y-1059109D01*
X3583122Y-1058584D01*
X3583752Y-1058060D01*
X3584383Y-1058584D01*
X3584697Y-1059109D01*
X3585012Y-1060159D01*
Y-1062259D01*
X3584697Y-1063309D01*
X3584383Y-1063834D01*
X3583752Y-1064359D01*
G01X3588792Y-1058060D02*
Y-1064359D01*
G01X3592571Y-1062259D02*
X3592886Y-1061209D01*
X3593831Y-1060684D01*
X3594776Y-1061209D01*
X3595091Y-1062259D01*
X3594776Y-1063309D01*
X3594461Y-1063834D01*
X3593831Y-1064359D01*
X3593201Y-1063834D01*
X3592886Y-1063309D01*
X3592571Y-1062259D01*
Y-1060159D01*
X3592886Y-1059109D01*
X3593201Y-1058584D01*
X3593831Y-1058060D01*
X3594461Y-1058584D01*
X3594776Y-1059109D01*
G01X3601828Y-966461D02*
Y-1019365D01*
G01X3602873Y-965889D02*
Y-1018793D01*
G01D02*
X3881417D01*
G01X3579641Y-1030232D02*
X3579050Y-1029740D01*
X3578755Y-1029248D01*
X3578459Y-1028264D01*
Y-1026295D01*
X3578755Y-1025311D01*
X3579050Y-1024819D01*
X3579641Y-1024327D01*
X3580231Y-1024819D01*
X3580526Y-1025311D01*
X3580822Y-1026295D01*
Y-1028264D01*
X3580526Y-1029248D01*
X3580231Y-1029740D01*
X3579641Y-1030232D01*
G01X3585546Y-1024327D02*
X3583774D01*
X3583479Y-1026788D01*
X3584070Y-1026295D01*
X3584660D01*
X3585251Y-1026788D01*
X3585546Y-1027280D01*
X3585841Y-1028264D01*
X3585546Y-1029248D01*
X3585251Y-1029740D01*
X3584660Y-1030232D01*
X3584070D01*
X3583479Y-1029740D01*
X3583184Y-1029248D01*
G01X3589089Y-1030232D02*
X3588499Y-1029740D01*
X3588204Y-1029248D01*
X3587908Y-1028264D01*
Y-1026295D01*
X3588204Y-1025311D01*
X3588499Y-1024819D01*
X3589089Y-1024327D01*
X3589680Y-1024819D01*
X3589975Y-1025311D01*
X3590270Y-1026295D01*
Y-1028264D01*
X3589975Y-1029248D01*
X3589680Y-1029740D01*
X3589089Y-1030232D01*
G01X3594995Y-1026295D02*
X3594700Y-1027280D01*
X3593814Y-1027772D01*
X3592928Y-1027280D01*
X3592633Y-1026295D01*
X3592928Y-1025311D01*
X3593223Y-1024819D01*
X3593814Y-1024327D01*
X3594404Y-1024819D01*
X3594700Y-1025311D01*
X3594995Y-1026295D01*
Y-1028264D01*
X3594700Y-1029248D01*
X3594404Y-1029740D01*
X3593814Y-1030232D01*
X3593223Y-1029740D01*
X3592928Y-1029248D01*
G01X3578459Y-1034170D02*
X3578755Y-1033677D01*
X3579345Y-1033185D01*
X3579936D01*
X3580526Y-1033677D01*
X3580822Y-1034170D01*
Y-1035154D01*
X3580526Y-1035646D01*
X3579345Y-1036630D01*
X3578755Y-1037614D01*
X3578459Y-1039091D01*
X3580822D01*
G01X3584365D02*
X3583774Y-1038599D01*
X3583479Y-1038107D01*
X3583184Y-1037122D01*
Y-1035154D01*
X3583479Y-1034170D01*
X3583774Y-1033677D01*
X3584365Y-1033185D01*
X3584956Y-1033677D01*
X3585251Y-1034170D01*
X3585546Y-1035154D01*
Y-1037122D01*
X3585251Y-1038107D01*
X3584956Y-1038599D01*
X3584365Y-1039091D01*
G01X3589089Y-1033185D02*
Y-1039091D01*
G01X3592633Y-1037122D02*
X3592928Y-1036138D01*
X3593814Y-1035646D01*
X3594700Y-1036138D01*
X3594995Y-1037122D01*
X3594700Y-1038107D01*
X3594404Y-1038599D01*
X3593814Y-1039091D01*
X3593223Y-1038599D01*
X3592928Y-1038107D01*
X3592633Y-1037122D01*
Y-1035154D01*
X3592928Y-1034170D01*
X3593223Y-1033677D01*
X3593814Y-1033185D01*
X3594404Y-1033677D01*
X3594700Y-1034170D01*
G01X3602873Y-965889D02*
X3881417D01*
G01X3591797Y-62894D02*
X3592772Y-64338D01*
X3593259Y-66503D01*
Y-67947D01*
X3592772Y-70112D01*
X3591797Y-71556D01*
G01X3583028D02*
Y-65781D01*
G01X3578156Y-70112D02*
X3577668Y-70834D01*
X3576694Y-71556D01*
X3575719Y-70834D01*
X3574745Y-69390D01*
Y-67947D01*
X3575719Y-66503D01*
X3576694Y-65781D01*
X3577668Y-66503D01*
X3578156Y-67947D01*
X3574745D01*
G01X3583028Y-67225D02*
X3584002Y-65781D01*
X3584976D01*
X3585464Y-66503D01*
G01X3597076Y19828D02*
X3711696D01*
G01X3593927D02*
X3597076D01*
G01X3596774Y193780D02*
X3656827D01*
G01X3605436Y200277D02*
X3606157Y202442D01*
X3607601Y203886D01*
X3609767Y204607D01*
X3611932Y203886D01*
X3613375Y202442D01*
X3614097Y200277D01*
X3613375Y198111D01*
X3611932Y196668D01*
X3609767Y195946D01*
X3607601Y196668D01*
X3606157Y198111D01*
X3605436Y200277D01*
G01X3593625Y193780D02*
X3596774D01*
G01X3604478Y241993D02*
X3605200Y244159D01*
X3606643Y245602D01*
X3608809Y246324D01*
X3610974Y245602D01*
X3612417Y244159D01*
X3613139Y241993D01*
X3612417Y239828D01*
X3610974Y238384D01*
X3608809Y237663D01*
X3606643Y238384D01*
X3605200Y239828D01*
X3604478Y241993D01*
G01X3605200Y235497D02*
X3612417Y248490D01*
G01X3592667Y235497D02*
X3595817D01*
G01D02*
X3655869D01*
G01X3604505Y843636D02*
X3604018D01*
Y844358D01*
X3604505Y843636D01*
G01X3572602Y841471D02*
X3632655D01*
G01X3595248Y851576D02*
X3596223Y852297D01*
X3597197D01*
X3598172Y851576D01*
X3598659Y850854D01*
Y850132D01*
X3598172Y849410D01*
X3597197Y848689D01*
X3598172Y847967D01*
X3599146Y846523D01*
G01X3596223Y848689D02*
X3597197D01*
G01X3581985Y841471D02*
X3589203Y854463D01*
G01X3581264Y847967D02*
X3581985Y850132D01*
X3583429Y851576D01*
X3585594Y852297D01*
X3587759Y851576D01*
X3589203Y850132D01*
X3589925Y847967D01*
X3589203Y845801D01*
X3587759Y844358D01*
X3585594Y843636D01*
X3583429Y844358D01*
X3581985Y845801D01*
X3581264Y847967D01*
G01X3599146Y846523D02*
Y845801D01*
X3598172Y844358D01*
X3597197Y843636D01*
X3596223D01*
X3595248Y844358D01*
X3594761Y845080D01*
G01X3602945Y889278D02*
X3602458D01*
Y890000D01*
X3602945Y889278D01*
G01X3579704Y893609D02*
X3580426Y895774D01*
X3581869Y897218D01*
X3584035Y897940D01*
X3586200Y897218D01*
X3587644Y895774D01*
X3588365Y893609D01*
X3587644Y891443D01*
X3586200Y890000D01*
X3584035Y889278D01*
X3581869Y890000D01*
X3580426Y891443D01*
X3579704Y893609D01*
G01X3592714Y891443D02*
Y892165D01*
X3593201Y892887D01*
X3593689Y893609D01*
X3594663Y894330D01*
X3595637D01*
X3596612Y893609D01*
X3597586Y892165D01*
G01D02*
Y891443D01*
X3597099Y890721D01*
X3596612Y890000D01*
X3595637Y889278D01*
X3594663D01*
G01D02*
X3593689Y890000D01*
X3592714Y891443D01*
G01X3594663Y894330D02*
X3593689Y895052D01*
X3593201Y895774D01*
Y896496D01*
X3593689Y897218D01*
X3594663Y897940D01*
X3595637D01*
X3596612Y897218D01*
X3597099Y896496D01*
Y895774D01*
X3596612Y895052D01*
X3595637Y894330D01*
G01X3580426Y887113D02*
X3587644Y900105D01*
G01X3611327Y2163497D02*
X3610614Y2161596D01*
X3608476Y2160645D01*
X3606337Y2161596D01*
X3605624Y2163497D01*
X3606337Y2165399D01*
X3607050Y2166349D01*
X3608476Y2167300D01*
X3609901Y2166349D01*
X3610614Y2165399D01*
X3611327Y2163497D01*
Y2159695D01*
X3610614Y2157793D01*
X3609901Y2156843D01*
X3608476Y2155892D01*
X3607050Y2156843D01*
X3606337Y2157793D01*
G01X3597068Y2167300D02*
Y2155892D01*
G01X3643040Y-1053307D02*
X3642663Y-1052705D01*
X3641911Y-1052103D01*
X3641158D01*
X3640406Y-1052705D01*
X3640030Y-1053307D01*
Y-1053910D01*
X3640406Y-1054512D01*
X3641158Y-1055114D01*
X3641911Y-1055716D01*
X3642663Y-1056318D01*
X3643040Y-1056920D01*
Y-1058124D01*
X3642663Y-1058726D01*
X3641911Y-1059328D01*
X3641158D01*
X3640406Y-1058726D01*
X3639653Y-1057522D01*
G01X3635514Y-1052103D02*
Y-1059328D01*
G01X3615947Y-1055716D02*
X3617829D01*
G01X3615947Y-1059328D02*
Y-1052103D01*
X3618957D01*
G01X3623473D02*
Y-1059328D01*
G01X3627989D02*
Y-1052103D01*
X3630999Y-1059328D01*
Y-1052103D01*
G01X3638764Y-1031634D02*
X3640006Y-1035246D01*
G01X3636694D02*
Y-1028021D01*
X3638764D01*
X3639592Y-1028623D01*
X3640006Y-1029225D01*
Y-1030429D01*
X3639592Y-1031032D01*
X3638764Y-1031634D01*
X3636694D01*
G01X3617241Y-1032838D02*
X3619724D01*
G01X3630072Y-1031634D02*
X3632141D01*
G01X3623035Y-1028021D02*
X3627174D01*
G01X3633383Y-1035246D02*
X3630072D01*
Y-1028021D01*
X3633383D01*
G01X3609790Y-1035246D02*
Y-1028021D01*
X3611860Y-1034042D01*
X3613930Y-1028021D01*
Y-1035246D01*
G01X3625105Y-1028021D02*
Y-1035246D01*
G01X3616413D02*
X3618482Y-1028021D01*
X3620552Y-1035246D01*
G01X3637804Y-979921D02*
X3633446D01*
Y-970414D01*
X3637804D01*
G01X3633446Y-975168D02*
X3636169D01*
G01X3616563Y-976752D02*
X3619831D01*
G01X3607305Y-979921D02*
Y-970414D01*
X3611662Y-979921D01*
Y-970414D01*
G01X3624188Y-979921D02*
Y-970414D01*
X3626911Y-978336D01*
X3629634Y-970414D01*
Y-979921D01*
G01X3615474D02*
X3618197Y-970414D01*
X3620920Y-979921D01*
G01X3630749Y-32648D02*
X3633672Y-38423D01*
G01X3636108Y-34092D02*
X3636830Y-31927D01*
X3638274Y-30483D01*
X3640439Y-29761D01*
X3642604Y-30483D01*
X3644048Y-31927D01*
X3644769Y-34092D01*
X3644048Y-36257D01*
X3642604Y-37701D01*
X3640439Y-38423D01*
X3638274Y-37701D01*
X3636830Y-36257D01*
X3636108Y-34092D01*
G01X3630749Y-38423D02*
X3633672Y-32648D01*
G01X3636830Y-40588D02*
X3644048Y-27596D01*
G01X3608706Y-40588D02*
X3611856D01*
G01D02*
X3921357D01*
G01X3623928Y-38423D02*
X3622954Y-37701D01*
G01X3623928Y-33370D02*
X3622954Y-32648D01*
X3622466Y-31927D01*
Y-31205D01*
X3622954Y-30483D01*
X3623928Y-29761D01*
X3624902D01*
X3625877Y-30483D01*
X3626364Y-31205D01*
Y-31927D01*
X3625877Y-32648D01*
X3624902Y-33370D01*
G01X3622954Y-37701D02*
X3621979Y-36257D01*
Y-35536D01*
G01X3626851D02*
Y-36257D01*
X3625877Y-37701D01*
G01X3621979Y-35536D02*
X3622954Y-34092D01*
X3623928Y-33370D01*
X3624902D01*
X3625877Y-34092D01*
X3626851Y-35536D01*
G01X3625877Y-37701D02*
X3624902Y-38423D01*
X3623928D01*
G01X3636287Y27045D02*
X3637262D01*
G01X3639211Y24880D02*
Y24158D01*
G01D02*
X3638236Y22715D01*
X3637262Y21993D01*
X3636287D01*
X3635313Y22715D01*
X3634826Y23436D01*
G01X3635313Y29932D02*
X3636287Y30655D01*
X3637262D01*
X3638236Y29932D01*
X3638724Y29211D01*
Y28489D01*
X3638236Y27767D01*
X3637262Y27045D01*
X3638236Y26324D01*
X3639211Y24880D01*
G01X3609148Y21993D02*
X3608174Y22715D01*
X3607200Y24158D01*
G01X3609148Y27045D02*
X3608174Y27767D01*
X3607687Y28489D01*
Y29211D01*
X3608174Y29932D01*
X3609148Y30655D01*
X3610122D01*
X3611097Y29932D01*
X3611584Y29211D01*
Y28489D01*
X3611097Y27767D01*
X3610122Y27045D01*
G01X3615969Y27767D02*
X3618893Y21993D01*
G01X3607200Y24158D02*
Y24880D01*
G01X3612071D02*
Y24158D01*
G01X3621328Y26324D02*
X3622050Y28489D01*
X3623494Y29932D01*
X3625659Y30655D01*
X3627824Y29932D01*
X3629268Y28489D01*
X3629990Y26324D01*
X3629268Y24158D01*
X3627824Y22715D01*
X3625659Y21993D01*
X3623494Y22715D01*
X3622050Y24158D01*
X3621328Y26324D01*
G01X3615969Y21993D02*
X3618893Y27767D01*
G01X3622050Y19828D02*
X3629268Y32820D01*
G01X3607200Y24880D02*
X3608174Y26324D01*
X3609148Y27045D01*
X3610122D01*
X3611097Y26324D01*
X3612071Y24880D01*
G01Y24158D02*
X3611097Y22715D01*
X3610122Y21993D01*
X3609148D01*
G01X3635985Y195946D02*
X3635011Y196668D01*
X3634037Y198111D01*
G01X3635985Y200998D02*
X3635011Y201720D01*
X3634524Y202442D01*
Y203164D01*
X3635011Y203886D01*
X3635985Y204607D01*
X3636960D01*
X3637934Y203886D01*
X3638421Y203164D01*
Y202442D01*
X3637934Y201720D01*
X3636960Y200998D01*
G01X3637934Y200277D02*
X3638909Y198833D01*
Y198111D01*
G01X3634037D02*
Y198833D01*
G01D02*
X3635011Y200277D01*
X3635985Y200998D01*
X3636960D01*
X3637934Y200277D01*
G01X3638909Y198111D02*
X3637934Y196668D01*
X3636960Y195946D01*
X3635985D01*
G01X3628677D02*
X3628190D01*
Y196668D01*
X3628677Y195946D01*
G01X3620395Y200998D02*
X3621369D01*
G01X3619420Y203886D02*
X3620395Y204607D01*
X3621369D01*
X3622344Y203886D01*
X3622831Y203164D01*
Y202442D01*
X3622344Y201720D01*
X3621369Y200998D01*
X3622344Y200277D01*
X3623318Y198833D01*
G01D02*
Y198111D01*
G01X3606157Y193780D02*
X3613375Y206773D01*
G01X3623318Y198111D02*
X3622344Y196668D01*
X3621369Y195946D01*
X3620395D01*
X3619420Y196668D01*
X3618933Y197390D01*
G01X3635515Y237663D02*
X3634540Y238384D01*
X3634053Y239106D01*
X3633566Y240550D01*
Y243437D01*
X3634053Y244880D01*
X3634540Y245602D01*
X3635515Y246324D01*
X3636489Y245602D01*
X3636976Y244880D01*
X3637463Y243437D01*
Y240550D01*
X3636976Y239106D01*
X3636489Y238384D01*
X3635515Y237663D01*
G01X3627719D02*
X3627232D01*
Y238384D01*
X3627719Y237663D01*
G01X3619437D02*
X3618463Y238384D01*
G01D02*
X3617488Y239828D01*
Y240550D01*
G01X3621385Y238384D02*
X3620411Y237663D01*
X3619437D01*
G01X3617488Y240550D02*
X3618463Y241993D01*
X3619437Y242715D01*
X3620411D01*
X3621385Y241993D01*
X3622360Y240550D01*
G01D02*
Y239828D01*
X3621385Y238384D01*
G01X3619437Y242715D02*
X3618463Y243437D01*
X3617975Y244159D01*
Y244880D01*
X3618463Y245602D01*
X3619437Y246324D01*
X3620411D01*
X3621385Y245602D01*
X3621873Y244880D01*
Y244159D01*
X3621385Y243437D01*
X3620411Y242715D01*
G01X3609864Y846523D02*
X3610839Y847967D01*
X3611813Y848689D01*
X3612787D01*
X3613762Y847967D01*
X3614736Y846523D01*
G01D02*
Y845801D01*
X3614249Y845080D01*
X3613762Y844358D01*
X3612787Y843636D01*
X3611813D01*
G01X3620096D02*
X3619121Y844358D01*
X3618634Y845080D01*
X3618147Y846523D01*
Y849410D01*
X3618634Y850854D01*
X3619121Y851576D01*
X3620096Y852297D01*
X3621070Y851576D01*
X3621557Y850854D01*
X3622044Y849410D01*
Y846523D01*
X3621557Y845080D01*
X3621070Y844358D01*
X3620096Y843636D01*
G01X3611813D02*
X3610839Y844358D01*
G01X3611813Y848689D02*
X3610839Y849410D01*
X3610352Y850132D01*
Y850854D01*
X3610839Y851576D01*
X3611813Y852297D01*
X3612787D01*
X3613762Y851576D01*
X3614249Y850854D01*
Y850132D01*
X3613762Y849410D01*
X3612787Y848689D01*
G01X3610839Y844358D02*
X3609864Y845801D01*
Y846523D01*
G01X3610741Y889278D02*
X3609766Y890000D01*
X3609279Y890721D01*
X3608792Y892165D01*
Y895052D01*
X3609279Y896496D01*
X3609766Y897218D01*
X3610741Y897940D01*
X3611715Y897218D01*
X3612202Y896496D01*
X3612689Y895052D01*
Y892165D01*
X3612202Y890721D01*
X3611715Y890000D01*
X3610741Y889278D01*
G01X3618536D02*
X3617562Y890000D01*
X3617074Y890721D01*
X3616587Y892165D01*
Y895052D01*
X3617074Y896496D01*
X3617562Y897218D01*
X3618536Y897940D01*
X3619511Y897218D01*
X3619998Y896496D01*
X3620485Y895052D01*
Y892165D01*
X3619998Y890721D01*
X3619511Y890000D01*
X3618536Y889278D01*
G01X3666726Y-1019466D02*
Y-1044072D01*
G01D02*
X3773419D01*
G01X3666726Y-1044182D02*
X3880111D01*
G01X3666726D02*
Y-1068788D01*
G01D02*
X3880111D01*
G01X3666726Y-1019466D02*
Y-1068517D01*
G01X3646050Y-1055716D02*
X3649060D01*
G01X3646050Y-1052103D02*
Y-1059328D01*
G01X3649060Y-1052103D02*
Y-1059328D01*
G01X3666726Y-1019466D02*
X3773419D01*
G01X3650353Y-1032838D02*
X3652837D01*
G01X3644972Y-1028021D02*
Y-1035246D01*
G01X3656562Y-1028021D02*
Y-1035246D01*
X3659873D01*
G01X3649526D02*
X3651595Y-1028021D01*
X3653665Y-1035246D01*
G01X3667144Y-38423D02*
X3666170Y-37701D01*
X3665683Y-36979D01*
X3665196Y-35536D01*
Y-32648D01*
X3665683Y-31205D01*
X3666170Y-30483D01*
X3667144Y-29761D01*
X3668119Y-30483D01*
X3668606Y-31205D01*
X3669093Y-32648D01*
Y-35536D01*
X3668606Y-36979D01*
X3668119Y-37701D01*
X3667144Y-38423D01*
G01X3674940D02*
X3673966Y-37701D01*
X3673478Y-36979D01*
X3672991Y-35536D01*
Y-32648D01*
X3673478Y-31205D01*
X3673966Y-30483D01*
X3674940Y-29761D01*
X3675915Y-30483D01*
X3676402Y-31205D01*
X3676889Y-32648D01*
Y-35536D01*
X3676402Y-36979D01*
X3675915Y-37701D01*
X3674940Y-38423D01*
G01X3659350D02*
X3658863D01*
Y-37701D01*
X3659350Y-38423D01*
G01X3651067D02*
X3650093Y-37701D01*
G01X3651067Y-33370D02*
X3650093Y-32648D01*
X3649606Y-31927D01*
Y-31205D01*
X3650093Y-30483D01*
X3651067Y-29761D01*
X3652041D01*
X3653016Y-30483D01*
X3653503Y-31205D01*
Y-31927D01*
X3653016Y-32648D01*
X3652041Y-33370D01*
G01X3650093Y-37701D02*
X3649118Y-36257D01*
Y-35536D01*
G01X3653016Y-34092D02*
X3653990Y-35536D01*
Y-36257D01*
X3653016Y-37701D01*
G01X3649118Y-35536D02*
X3650093Y-34092D01*
X3651067Y-33370D01*
X3652041D01*
X3653016Y-34092D01*
G01Y-37701D02*
X3652041Y-38423D01*
X3651067D01*
G01X3668443Y30655D02*
X3667469Y29211D01*
X3666981Y27045D01*
Y25602D01*
X3667469Y23436D01*
X3668443Y21993D01*
G01X3644570D02*
X3644083D01*
Y22715D01*
X3644570Y21993D01*
G01X3660160D02*
X3659186Y22715D01*
X3658699Y23436D01*
X3658211Y24880D01*
Y27767D01*
X3658699Y29211D01*
X3659186Y29932D01*
X3660160Y30655D01*
X3661135Y29932D01*
X3661622Y29211D01*
X3662109Y27767D01*
Y24880D01*
X3661622Y23436D01*
X3661135Y22715D01*
X3660160Y21993D01*
G01X3650416Y29211D02*
X3650904Y29932D01*
X3651878Y30655D01*
X3652852D01*
X3653827Y29932D01*
X3654314Y29211D01*
Y27767D01*
X3653827Y27045D01*
G01D02*
X3651878Y25602D01*
X3650904Y24158D01*
X3650416Y21993D01*
X3654314D01*
G01X3644268Y195946D02*
X3643293Y196668D01*
X3642806Y197390D01*
X3642319Y198833D01*
Y201720D01*
X3642806Y203164D01*
X3643293Y203886D01*
X3644268Y204607D01*
X3645242Y203886D01*
X3645730Y203164D01*
X3646217Y201720D01*
Y198833D01*
X3645730Y197390D01*
X3645242Y196668D01*
X3644268Y195946D01*
G01X3643310Y237663D02*
X3642335Y238384D01*
X3641848Y239106D01*
X3641361Y240550D01*
Y243437D01*
X3641848Y244880D01*
X3642335Y245602D01*
X3643310Y246324D01*
X3644284Y245602D01*
X3644771Y244880D01*
X3645259Y243437D01*
Y240550D01*
X3644771Y239106D01*
X3644284Y238384D01*
X3643310Y237663D01*
G01X3704172Y-29761D02*
X3706121D01*
X3707095Y-30483D01*
G01D02*
X3708070Y-31927D01*
X3708557Y-34092D01*
X3708070Y-36257D01*
G01D02*
X3707095Y-37701D01*
X3706121Y-38423D01*
X3704172D01*
Y-29761D01*
G01X3696864Y-35536D02*
X3699787D01*
G01X3688582Y-38423D02*
Y-29761D01*
X3691018D01*
X3691992Y-30483D01*
X3692479Y-31205D01*
Y-32648D01*
X3691992Y-33370D01*
X3691018Y-34092D01*
X3688582D01*
G01X3695890Y-38423D02*
X3698326Y-29761D01*
X3700762Y-38423D01*
G01X3683222Y-29761D02*
X3682248Y-31205D01*
X3681761Y-33370D01*
Y-34814D01*
X3682248Y-36979D01*
X3683222Y-38423D01*
G01X3698650Y30655D02*
X3699624Y29211D01*
X3700111Y27045D01*
Y25602D01*
X3699624Y23436D01*
X3698650Y21993D01*
G01X3689393Y26324D02*
X3693291D01*
G01X3681110Y30655D02*
X3685982D01*
G01X3673802Y21993D02*
Y30655D01*
X3676238D01*
X3677213Y29932D01*
X3677700Y29211D01*
Y27767D01*
X3677213Y27045D01*
X3676238Y26324D01*
X3673802D01*
G01X3683546Y30655D02*
Y21993D01*
G01X3689393Y30655D02*
Y21993D01*
G01X3693291Y30655D02*
Y21993D01*
G01X3709240Y-1120610D02*
Y-1139623D01*
G01X3739251Y-36257D02*
X3738277Y-37701D01*
X3737302Y-38423D01*
X3736328Y-37701D01*
X3735354Y-36257D01*
Y-34814D01*
X3736328Y-33370D01*
X3737302Y-32648D01*
X3738277Y-33370D01*
X3739251Y-34814D01*
Y-36257D01*
G01X3713429Y-29761D02*
X3714404Y-31205D01*
X3714891Y-33370D01*
Y-34814D01*
X3714404Y-36979D01*
X3713429Y-38423D01*
G01X3727558D02*
Y-29761D01*
X3731456Y-38423D01*
Y-29761D01*
G01X3722199D02*
X3721224Y-31205D01*
X3720737Y-33370D01*
Y-34814D01*
X3721224Y-36979D01*
X3722199Y-38423D01*
G01X3709240Y2171102D02*
Y2152090D01*
G01X3773419Y-1019466D02*
Y-1044072D01*
G01X3880232D02*
X3773539D01*
G01Y-1019466D02*
Y-1044072D01*
G01X3880232Y-1019466D02*
X3773539D01*
G01X3770432Y-32648D02*
Y-38423D01*
G01Y-36257D02*
X3769458Y-37701D01*
X3768483Y-38423D01*
X3767509Y-37701D01*
X3766535Y-36257D01*
Y-34814D01*
X3767509Y-33370D01*
X3768483Y-32648D01*
X3769458Y-33370D01*
X3770432Y-34814D01*
G01X3777253Y-37701D02*
X3776278Y-38423D01*
X3775304Y-37701D01*
X3774330Y-36257D01*
Y-34814D01*
X3775304Y-33370D01*
X3776278Y-32648D01*
X3777253Y-33370D01*
G01X3751431D02*
X3754354D01*
G01X3752893Y-38423D02*
Y-29761D01*
G01X3759226Y-38423D02*
Y-32648D01*
G01Y-34092D02*
X3760201Y-32648D01*
X3761175D01*
X3761662Y-33370D01*
G01X3805998D02*
X3808921D01*
G01X3801613Y-32648D02*
Y-38423D01*
G01X3807460D02*
Y-29761D01*
G01X3801613Y-36257D02*
X3800639Y-37701D01*
X3799664Y-38423D01*
X3798690Y-37701D01*
X3797715Y-36257D01*
Y-34814D01*
X3798690Y-33370D01*
X3799664Y-32648D01*
X3800639Y-33370D01*
X3801613Y-34814D01*
G01X3785535Y-36979D02*
X3785048Y-37701D01*
X3784074Y-38423D01*
X3783100Y-37701D01*
X3782125Y-36257D01*
Y-34814D01*
X3783100Y-33370D01*
X3784074Y-32648D01*
X3785048Y-33370D01*
X3785535Y-34814D01*
X3782125D01*
G01X3829017Y-1135820D02*
X3827591Y-1134870D01*
X3826878Y-1133919D01*
X3826165Y-1132018D01*
Y-1128215D01*
X3826878Y-1126314D01*
X3827591Y-1125364D01*
X3829017Y-1124413D01*
X3830443Y-1125364D01*
X3831155Y-1126314D01*
X3831869Y-1128215D01*
Y-1132018D01*
X3831155Y-1133919D01*
X3830443Y-1134870D01*
X3829017Y-1135820D01*
G01X3814757Y-1126314D02*
X3815470Y-1125364D01*
X3816896Y-1124413D01*
X3818322D01*
X3819748Y-1125364D01*
X3820461Y-1126314D01*
Y-1128215D01*
X3819748Y-1129166D01*
X3818322Y-1130117D01*
X3816896Y-1131067D01*
X3815470Y-1132968D01*
X3814757Y-1135820D01*
X3820461D01*
G01X3816420Y-1033888D02*
X3818730D01*
G01X3816420Y-1029465D02*
X3818730D01*
G01X3837179Y-38423D02*
Y-32648D01*
G01Y-34092D02*
X3838154Y-32648D01*
X3839128D01*
X3840102Y-34092D01*
Y-38423D01*
G01X3823050Y-29761D02*
Y-30483D01*
G01Y-32648D02*
Y-38423D01*
G01X3829384D02*
Y-32648D01*
G01Y-34092D02*
X3830358Y-32648D01*
X3831333D01*
X3832307Y-34092D01*
Y-38423D01*
G01X3814757Y2165399D02*
X3815470Y2166349D01*
X3816896Y2167300D01*
X3818322D01*
X3819748Y2166349D01*
X3820461Y2165399D01*
Y2163497D01*
X3819748Y2162547D01*
X3818322Y2161596D01*
X3816896Y2160645D01*
X3815470Y2158744D01*
X3814757Y2155892D01*
X3820461D01*
G01X3829017D02*
X3827591Y2156843D01*
X3826878Y2157793D01*
X3826165Y2159695D01*
Y2163497D01*
X3826878Y2165399D01*
X3827591Y2166349D01*
X3829017Y2167300D01*
X3830443Y2166349D01*
X3831155Y2165399D01*
X3831869Y2163497D01*
Y2159695D01*
X3831155Y2157793D01*
X3830443Y2156843D01*
X3829017Y2155892D01*
G01X3869822Y-38423D02*
Y-29761D01*
G01X3879566Y-36257D02*
X3878592Y-37701D01*
X3877617Y-38423D01*
X3876643Y-37701D01*
X3875668Y-36257D01*
Y-34814D01*
X3876643Y-33370D01*
X3877617Y-32648D01*
X3878592Y-33370D01*
X3879566Y-34814D01*
G01X3852770Y-38423D02*
Y-32648D01*
G01X3847898Y-36979D02*
X3847411Y-37701D01*
X3846436Y-38423D01*
X3845462Y-37701D01*
X3844487Y-36257D01*
Y-34814D01*
X3845462Y-33370D01*
X3846436Y-32648D01*
X3847411Y-33370D01*
X3847898Y-34814D01*
X3844487D01*
G01X3852770Y-34092D02*
X3853744Y-32648D01*
X3854719D01*
X3855206Y-33370D01*
G01X3906172Y-1101265D02*
X3907469Y-1108870D01*
X3908765Y-1101265D01*
X3910061Y-1108870D01*
X3911357Y-1101265D01*
G01X3888889Y-1101898D02*
X3889753Y-1103166D01*
X3890185Y-1105067D01*
X3889753Y-1106968D01*
G01X3895370Y-1105067D02*
X3896667Y-1108870D01*
G01X3880232Y-1119850D02*
Y-966232D01*
G01X3893210Y-1108870D02*
Y-1101265D01*
X3895370D01*
X3896234Y-1101898D01*
X3896667Y-1102532D01*
Y-1103800D01*
X3896234Y-1104433D01*
X3895370Y-1105067D01*
X3893210D01*
G01X3899691Y-1108870D02*
X3901852Y-1101265D01*
X3904012Y-1108870D01*
G01X3889753Y-1106968D02*
X3888889Y-1108236D01*
X3888025Y-1108870D01*
X3886296D01*
Y-1101265D01*
G01X3904948Y-1074601D02*
Y-1082206D01*
G01X3900556Y-1106334D02*
X3903148D01*
G01X3886296Y-1101265D02*
X3888025D01*
X3888889Y-1101898D01*
G01X3880042Y-1093423D02*
X4155148D01*
G01X3918257Y-1069278D02*
G03I-13309J0D01*
G01X3912553D02*
G03I-7605J0D01*
G01X3904948Y-1054448D02*
Y-1063574D01*
G01X3903807Y-1069278D02*
X3906469D01*
G01X3908370D02*
X3918257D01*
G01X3904948Y-1073080D02*
Y-1065475D01*
G01X3880232Y-1019466D02*
Y-1044072D01*
G01X3880111Y-1044182D02*
Y-1068788D01*
G01X3890879Y-1069278D02*
X3901526D01*
G01X3904819Y-1027568D02*
X3907386Y-1035781D01*
X3909952Y-1027568D01*
G01X3881417Y-965889D02*
Y-1018793D01*
G01X4155148Y-1019466D02*
X3880227D01*
G01D02*
Y-1005686D01*
G01X3897119Y-1031674D02*
X3899686D01*
G01X3901226Y-1035781D02*
X3897119D01*
Y-1027568D01*
X3901226D01*
G01X3891473Y-1031674D02*
X3893013Y-1035781D01*
G01X3888906D02*
Y-1027568D01*
X3891473D01*
X3892499Y-1028252D01*
X3893013Y-1028936D01*
Y-1030305D01*
X3892499Y-1030990D01*
X3891473Y-1031674D01*
X3888906D01*
G01X4155148Y-1005686D02*
X3880227D01*
G01X3908311Y-29761D02*
X3909285Y-31205D01*
X3909773Y-33370D01*
Y-34814D01*
X3909285Y-36979D01*
X3908311Y-38423D01*
G01X3879566Y-32648D02*
Y-38423D01*
G01X3899541D02*
Y-32648D01*
G01X3885413Y-37701D02*
X3887361Y-32648D01*
G01X3894669Y-36979D02*
X3894182Y-37701D01*
X3893208Y-38423D01*
X3892233Y-37701D01*
X3891259Y-36257D01*
Y-34814D01*
X3892233Y-33370D01*
X3893208Y-32648D01*
X3894182Y-33370D01*
X3894669Y-34814D01*
X3891259D01*
G01X3899541Y-34092D02*
X3900516Y-32648D01*
X3901490D01*
X3901978Y-33370D01*
G01X3883464Y-32648D02*
X3885413Y-37701D01*
X3884925Y-39866D01*
X3883951Y-41310D01*
X3882976D01*
G01X3941604Y-1108870D02*
Y-1101265D01*
X3945061Y-1108870D01*
Y-1101265D01*
G01X3929506Y-1105067D02*
X3931234D01*
Y-1107602D01*
X3930802Y-1108236D01*
X3929938Y-1108870D01*
X3929074D01*
X3928209Y-1108236D01*
G01D02*
X3927345Y-1106968D01*
X3926913Y-1105067D01*
X3927345Y-1103166D01*
G01X3915679Y-1101265D02*
Y-1108870D01*
G01X3920864D02*
Y-1101265D01*
X3924321Y-1108870D01*
Y-1101265D01*
G01X3929781Y-1120610D02*
Y-1139623D01*
G01X3928143Y-1076882D02*
X3958943Y-1082586D01*
G01X3928143Y-1061673D02*
Y-1076882D01*
G01X3927345Y-1103166D02*
X3928209Y-1101898D01*
X3929074Y-1101265D01*
X3929938D01*
X3930802Y-1101898D01*
X3931234Y-1102532D01*
G01X3943353Y-1069278D02*
X3947155D01*
G01X3958943Y-1055969D02*
X3928143Y-1061673D01*
G01X3915806Y-1044182D02*
Y-966232D01*
G01X3924341Y-1069278D02*
X3939550D01*
G01X3929781Y2171102D02*
Y2152090D01*
G01X3971106Y-1093531D02*
Y-1119675D01*
G01D02*
X4154669D01*
G01X3957160Y-1108870D02*
X3956728D01*
Y-1108236D01*
X3957160Y-1108870D01*
G01X3948086Y-1103166D02*
X3948950Y-1101898D01*
X3949814Y-1101265D01*
X3950678D01*
X3951543Y-1101898D01*
X3951975Y-1102532D01*
X3952407Y-1103166D01*
X3952839Y-1105067D01*
X3952407Y-1106968D01*
G01D02*
X3951543Y-1108236D01*
X3950678Y-1108870D01*
X3949814D01*
X3948950Y-1108236D01*
X3948518Y-1107602D01*
X3948086Y-1106968D01*
X3947654Y-1105067D01*
X3948086Y-1103166D01*
G01X3971106Y-1093531D02*
X4154669D01*
G01X3972104Y-1093124D02*
Y-1044212D01*
G01X3958943Y-1082586D02*
Y-1055969D01*
G01X3976763Y-1053277D02*
X3978902D01*
X3979971Y-1054069D01*
X3981041Y-1055653D01*
G01X3979971Y-1061991D02*
X3978902Y-1062783D01*
X3976763D01*
Y-1053277D01*
G01X3972061Y-1069278D02*
X4155148D01*
G01X3950957D02*
X3962365D01*
G01X3972020Y-1031838D02*
X3974354D01*
G01X3975754Y-1035944D02*
X3972020D01*
Y-1027731D01*
X3975754D01*
G01X3964554D02*
X3966420D01*
X3967354Y-1028415D01*
X3967820Y-1029100D01*
X3968287Y-1029784D01*
X3968754Y-1031838D01*
X3968287Y-1033891D01*
X3967820Y-1034575D01*
X3967354Y-1035260D01*
X3966420Y-1035944D01*
X3964554D01*
Y-1027731D01*
G01X4011416Y-1086388D02*
X4006980D01*
Y-1076882D01*
X4011416D01*
G01X4006980Y-1081636D02*
X4009752D01*
G01X4002544Y-1086388D02*
X3998108D01*
Y-1076882D01*
X4002544D01*
G01X3989235Y-1081636D02*
X3993672D01*
G01X3998108D02*
X4000880D01*
G01X3980917Y-1080051D02*
X3984244Y-1082428D01*
X3984799Y-1083220D01*
Y-1084804D01*
X3984244Y-1085596D01*
X3983135Y-1086388D01*
X3982026D01*
X3980917Y-1085596D01*
X3979809Y-1084012D01*
G01X3984799Y-1078467D02*
X3984244Y-1077675D01*
X3983135Y-1076882D01*
X3982026D01*
X3980917Y-1077675D01*
X3980363Y-1078467D01*
Y-1079259D01*
X3980917Y-1080051D01*
G01X3989235Y-1076882D02*
Y-1086388D01*
G01X3993672Y-1076882D02*
Y-1086388D01*
G01X3981041Y-1055653D02*
X3981575Y-1058030D01*
X3981041Y-1060407D01*
X3979971Y-1061991D01*
G01X3987457Y-1053277D02*
Y-1062783D01*
G01X3993339D02*
Y-1053277D01*
X3996012Y-1061199D01*
X3998686Y-1053277D01*
Y-1062783D01*
G01X4003754Y-1027731D02*
Y-1035944D01*
G01X4009354D02*
Y-1027731D01*
X4011687D01*
X4012620Y-1028415D01*
X4013087Y-1029100D01*
Y-1030469D01*
X4012620Y-1031153D01*
X4011687Y-1031838D01*
X4009354D01*
G01X3983220Y-1029100D02*
X3982754Y-1028415D01*
X3981820Y-1027731D01*
X3980887D01*
X3979954Y-1028415D01*
X3979487Y-1029100D01*
Y-1029784D01*
X3979954Y-1030469D01*
G01X3986487Y-1029784D02*
X3987420Y-1028415D01*
X3988354Y-1027731D01*
X3989287D01*
X3990220Y-1028415D01*
X3990687Y-1029100D01*
G01X3979954Y-1030469D02*
X3982754Y-1032522D01*
X3983220Y-1033207D01*
Y-1034575D01*
X3982754Y-1035260D01*
X3981820Y-1035944D01*
X3980887D01*
X3979954Y-1035260D01*
G01D02*
X3979020Y-1033891D01*
G01X3987420Y-1035260D02*
X3986487Y-1033891D01*
X3986020Y-1031838D01*
X3986487Y-1029784D01*
G01X3996754Y-1031838D02*
X3998154Y-1035944D01*
G01X3994420D02*
Y-1027731D01*
X3996754D01*
X3997687Y-1028415D01*
X3998154Y-1029100D01*
Y-1030469D01*
X3997687Y-1031153D01*
X3996754Y-1031838D01*
X3994420D01*
G01X3990687Y-1034575D02*
X3990220Y-1035260D01*
X3989287Y-1035944D01*
X3988354D01*
X3987420Y-1035260D01*
G01X4035298Y-1126314D02*
X4036011Y-1125364D01*
X4037437Y-1124413D01*
X4038863D01*
X4040289Y-1125364D01*
X4041002Y-1126314D01*
Y-1128215D01*
X4040289Y-1129166D01*
G01D02*
X4037437Y-1131067D01*
X4036011Y-1132968D01*
X4035298Y-1135820D01*
X4041002D01*
G01X4026056Y-1069278D02*
Y-1093884D01*
G01D02*
X4079205D01*
G01X4015298Y-1076882D02*
X4020843D01*
G01X4018070D02*
Y-1086388D01*
G01X4026056Y-1044562D02*
Y-1093423D01*
G01X4044137Y-1056446D02*
Y-1062783D01*
G01Y-1058030D02*
X4045206Y-1056446D01*
X4046276D01*
X4047345Y-1058030D01*
Y-1062783D01*
G01X4013123Y-1053277D02*
Y-1062783D01*
G01X4019540D02*
Y-1053277D01*
X4023818Y-1062783D01*
Y-1053277D01*
G01X4026056Y-1069278D02*
X4079205D01*
G01X4039220Y-1035944D02*
Y-1027731D01*
X4042953Y-1035944D01*
Y-1027731D01*
G01X4016353D02*
X4021020D01*
G01X4031287Y-1029784D02*
X4032220Y-1028415D01*
X4033153Y-1027731D01*
X4034087D01*
X4035020Y-1028415D01*
X4035487Y-1029100D01*
X4035953Y-1029784D01*
X4036420Y-1031838D01*
X4035953Y-1033891D01*
G01X4032220Y-1035260D02*
X4031287Y-1033891D01*
X4030820Y-1031838D01*
X4031287Y-1029784D01*
G01X4018687Y-1027731D02*
Y-1035944D01*
G01X4026153Y-1027731D02*
Y-1035944D01*
G01X4035953Y-1033891D02*
X4035020Y-1035260D01*
X4034087Y-1035944D01*
X4033153D01*
X4032220Y-1035260D01*
G01X4040289Y2162547D02*
X4037437Y2160645D01*
X4036011Y2158744D01*
X4035298Y2155892D01*
X4041002D01*
G01X4035298Y2165399D02*
X4036011Y2166349D01*
X4037437Y2167300D01*
X4038863D01*
X4040289Y2166349D01*
X4041002Y2165399D01*
Y2163497D01*
X4040289Y2162547D01*
G01X4049557Y-1124413D02*
Y-1135820D01*
G01X4052693Y-1056446D02*
Y-1062783D01*
G01X4047345Y-1058030D02*
X4048415Y-1056446D01*
X4049484D01*
X4050554Y-1058030D01*
Y-1062783D01*
G01X4052693Y-1058030D02*
X4053762Y-1056446D01*
X4054831D01*
X4055901Y-1058030D01*
Y-1062783D01*
G01Y-1058030D02*
X4056970Y-1056446D01*
X4058039D01*
X4059109Y-1058030D01*
Y-1062783D01*
G01X4049557Y2167300D02*
Y2155892D01*
G01X4155148Y-1093884D02*
X4107904D01*
G01Y-1069278D02*
Y-1093884D01*
G01X4079205Y-1069278D02*
Y-1093884D01*
G01X4094515Y-1081445D02*
X4096991D01*
G01X4087089Y-1085406D02*
X4086098Y-1083822D01*
X4085603Y-1081445D01*
X4086098Y-1079069D01*
X4086593Y-1078277D01*
X4087089Y-1077484D01*
X4088079Y-1076692D01*
X4089069D01*
X4090059Y-1077484D01*
G01D02*
X4091049Y-1079069D01*
X4091544Y-1081445D01*
X4091049Y-1083822D01*
G01X4094515Y-1086199D02*
Y-1076692D01*
X4098476D01*
G01X4091049Y-1083822D02*
X4090059Y-1085406D01*
X4089069Y-1086199D01*
X4088079D01*
X4087089Y-1085406D01*
G01X4107428Y-1057979D02*
Y-1065584D01*
X4111230D01*
G01X4107428Y-1054829D02*
Y-1047223D01*
X4111230Y-1054829D01*
Y-1047223D01*
G01X4155148Y-1069278D02*
X4107904D01*
G01X4100298Y-1063049D02*
X4103150D01*
G01X4084613Y-1047223D02*
X4086514D01*
X4087465Y-1047857D01*
G01X4086039Y-1061148D02*
X4087940Y-1062415D01*
X4088415Y-1063049D01*
Y-1064316D01*
X4087940Y-1064950D01*
X4086989Y-1065584D01*
X4086039D01*
X4085088Y-1064950D01*
X4084137Y-1063682D01*
G01X4092693Y-1064950D02*
X4091743Y-1063682D01*
X4091267Y-1061781D01*
X4091743Y-1059880D01*
X4092218Y-1059246D01*
X4092693Y-1058613D01*
X4093644Y-1057979D01*
X4094594D01*
X4095545Y-1058613D01*
X4096020Y-1059246D01*
G01X4092693Y-1054195D02*
X4091743Y-1052927D01*
X4091267Y-1051026D01*
X4091743Y-1049125D01*
G01X4088415Y-1059246D02*
X4087940Y-1058613D01*
X4086989Y-1057979D01*
X4086039D01*
X4085088Y-1058613D01*
X4084613Y-1059246D01*
Y-1059880D01*
X4085088Y-1060514D01*
X4086039Y-1061148D01*
G01X4087465Y-1047857D02*
X4088415Y-1049125D01*
X4088891Y-1051026D01*
X4088415Y-1052927D01*
G01X4095545Y-1047857D02*
X4096496Y-1049125D01*
X4096971Y-1051026D01*
X4096496Y-1052927D01*
G01X4099348Y-1065584D02*
X4101724Y-1057979D01*
X4104100Y-1065584D01*
G01X4088415Y-1052927D02*
X4087465Y-1054195D01*
X4086514Y-1054829D01*
X4084613D01*
Y-1047223D01*
G01X4091743Y-1049125D02*
X4092693Y-1047857D01*
X4093644Y-1047223D01*
X4094594D01*
X4095545Y-1047857D01*
G01X4096496Y-1052927D02*
X4095545Y-1054195D01*
X4094594Y-1054829D01*
X4093644D01*
X4092693Y-1054195D01*
G01X4096020Y-1064316D02*
X4095545Y-1064950D01*
X4094594Y-1065584D01*
X4093644D01*
X4092693Y-1064950D01*
G01X4078529Y-1068517D02*
Y-966232D01*
G01X4105494Y-1036101D02*
Y-1028116D01*
X4108822Y-1036101D01*
Y-1028116D01*
G01X4085948Y-1030778D02*
X4088443Y-1032774D01*
G01X4088859Y-1029447D02*
X4088443Y-1028782D01*
X4087611Y-1028116D01*
X4086780D01*
X4085948Y-1028782D01*
X4085532Y-1029447D01*
Y-1030112D01*
X4085948Y-1030778D01*
G01X4098424Y-1030112D02*
X4099256Y-1028782D01*
X4100088Y-1028116D01*
X4100920D01*
X4101752Y-1028782D01*
X4102167Y-1029447D01*
G01X4100504Y-1032109D02*
X4102167D01*
Y-1034771D01*
X4101752Y-1035436D01*
X4100920Y-1036101D01*
X4100088D01*
X4099256Y-1035436D01*
G01X4085948D02*
X4085116Y-1034105D01*
G01X4088443Y-1032774D02*
X4088859Y-1033440D01*
Y-1034771D01*
X4088443Y-1035436D01*
X4087611Y-1036101D01*
X4086780D01*
X4085948Y-1035436D01*
G01X4099256D02*
X4098424Y-1034105D01*
X4098009Y-1032109D01*
X4098424Y-1030112D01*
G01X4093850Y-1028116D02*
Y-1036101D01*
G01X4147353Y-1061781D02*
X4149254D01*
Y-1064316D01*
X4148779Y-1064950D01*
X4147828Y-1065584D01*
X4146878D01*
X4145927Y-1064950D01*
X4144976Y-1063682D01*
G01D02*
X4144501Y-1061781D01*
X4144976Y-1059880D01*
X4145927Y-1058613D01*
G01X4136896Y-1057979D02*
X4138322Y-1065584D01*
X4139748Y-1057979D01*
X4141174Y-1065584D01*
X4142600Y-1057979D01*
G01X4118835Y-1065584D02*
X4115032D01*
Y-1057979D01*
X4118835D01*
G01X4115032Y-1061781D02*
X4117409D01*
G01X4130242Y-1057979D02*
X4132143D01*
X4133094Y-1058613D01*
X4134044Y-1059880D01*
G01X4122162Y-1047223D02*
X4126915D01*
G01X4119310Y-1049125D02*
X4119785Y-1051026D01*
X4119310Y-1052927D01*
X4118359Y-1054195D01*
G01X4134044Y-1059880D02*
X4134520Y-1061781D01*
X4134044Y-1063682D01*
X4133094Y-1064950D01*
G01X4114557Y-1052927D02*
X4114082Y-1051026D01*
X4114557Y-1049125D01*
X4115507Y-1047857D01*
G01X4116933Y-966232D02*
Y-1044182D01*
G01X4124538Y-1047223D02*
Y-1054829D01*
G01X4118359Y-1054195D02*
X4117409Y-1054829D01*
X4116458D01*
X4115507Y-1054195D01*
X4114557Y-1052927D01*
G01X4133094Y-1064950D02*
X4132143Y-1065584D01*
X4130242D01*
Y-1057979D01*
G01X4115507Y-1047857D02*
X4116458Y-1047223D01*
X4117409D01*
X4118359Y-1047857D01*
X4119310Y-1049125D01*
G01X4143943Y-1033218D02*
X4146231D01*
G01X4147603Y-1037211D02*
X4143943D01*
Y-1029226D01*
X4147603D01*
G01X4138454D02*
Y-1037211D01*
G01X4121984Y-1029226D02*
X4123815D01*
X4124729Y-1029891D01*
X4125644Y-1031222D01*
G01X4136166Y-1029226D02*
X4140741D01*
G01X4129761Y-1034549D02*
X4132507D01*
G01X4125644Y-1031222D02*
X4126102Y-1033218D01*
X4125644Y-1035214D01*
X4124729Y-1036545D01*
G01X4128846Y-1037211D02*
X4131134Y-1029226D01*
X4133421Y-1037211D01*
G01X4124729Y-1036545D02*
X4123815Y-1037211D01*
X4121984D01*
Y-1029226D01*
G01X4174160Y-1139623D02*
Y2171401D01*
G01X4154669Y-1093531D02*
Y-1119675D01*
G01X4155148Y2152090D02*
Y-1120610D01*
G01Y-1069278D02*
Y-1093884D01*
G01X4145927Y-1058613D02*
X4146878Y-1057979D01*
X4147828D01*
X4148779Y-1058613D01*
X4149254Y-1059246D01*
G01X4155148Y-1019466D02*
Y-1005686D01*
G01X4155066Y-965738D02*
Y-1018852D01*
G01X4162991Y-994093D02*
X4164417Y-992192D01*
X4165842Y-991241D01*
X4167268D01*
X4168694Y-992192D01*
X4170120Y-994093D01*
G01X4164417Y-1001697D02*
X4162991Y-999796D01*
X4162278Y-996945D01*
X4162991Y-994093D01*
G01X4170120D02*
X4170833Y-996945D01*
X4170120Y-999796D01*
X4168694Y-1001697D01*
G01D02*
X4167268Y-1002648D01*
X4165842D01*
X4164417Y-1001697D01*
G01X4155148Y-888575D02*
X4174160D01*
G01X4163704Y-785910D02*
Y-774502D01*
X4169407Y-785910D01*
Y-774502D01*
G01X4155148Y-671836D02*
X4174160D01*
G01X4162991Y-569171D02*
Y-557764D01*
X4166556Y-567270D01*
X4170120Y-557764D01*
Y-569171D01*
G01X4155148Y-455098D02*
X4174160D01*
G01X4163704Y-341215D02*
Y-352622D01*
X4169407D01*
G01X4155148Y-238359D02*
X4174160D01*
G01X4166556Y-128279D02*
X4169407Y-135884D01*
G01X4163704Y-124477D02*
Y-135884D01*
G01Y-131131D02*
X4169407Y-124477D01*
G01X4155148Y-21621D02*
X4174160D01*
G01X4166556Y92453D02*
Y82946D01*
X4166080Y81995D01*
X4165130Y81045D01*
X4164179D01*
X4163228Y81995D01*
X4162753Y82946D01*
G01X4155148Y195118D02*
X4174160D01*
G01X4162753Y309191D02*
Y297784D01*
G01X4155148Y411856D02*
X4174160D01*
G01X4162753Y520036D02*
X4166556D01*
G01X4162753Y525740D02*
Y514332D01*
G01X4166556Y525740D02*
Y514332D01*
G01X4155148Y628595D02*
X4174160D01*
G01X4164654Y736775D02*
X4166556D01*
Y732972D01*
X4166080Y732021D01*
X4165130Y731071D01*
X4164179D01*
X4163228Y732021D01*
G01X4162278Y739627D02*
X4163228Y741527D01*
X4164179Y742478D01*
X4165130D01*
X4166080Y741527D01*
X4166556Y740577D01*
G01X4163228Y732021D02*
X4162278Y733923D01*
X4161802Y736775D01*
X4162278Y739627D01*
G01X4155148Y845334D02*
X4174160D01*
G01X4162372Y948000D02*
Y959407D01*
X4166175D01*
G01X4162372Y953703D02*
X4164749D01*
G01X4155148Y1062073D02*
X4174160D01*
G01X4166556Y1164929D02*
X4162753D01*
Y1176336D01*
X4166556D01*
G01X4162753Y1170632D02*
X4165130D01*
G01X4155148Y1278811D02*
X4174160D01*
G01X4165605Y1382427D02*
X4164654Y1381477D01*
X4162753D01*
Y1392884D01*
G01X4166556Y1390032D02*
X4167031Y1387180D01*
X4166556Y1384329D01*
X4165605Y1382427D01*
G01X4162753Y1392884D02*
X4164654D01*
X4165605Y1391934D01*
X4166556Y1390032D01*
G01X4155148Y1495550D02*
X4174160D01*
G01X4162278Y1606961D02*
X4163228Y1608862D01*
X4164179Y1609813D01*
X4165130D01*
X4166080Y1608862D01*
X4166556Y1607912D01*
G01Y1600307D02*
X4166080Y1599356D01*
X4165130Y1598406D01*
X4164179D01*
X4163228Y1599356D01*
G01D02*
X4162278Y1601258D01*
X4161802Y1604109D01*
X4162278Y1606961D01*
G01X4155148Y1712288D02*
X4174160D01*
G01X4162278Y1821608D02*
X4165605D01*
G01Y1814954D02*
X4166556Y1816855D01*
Y1819707D01*
G01X4162278Y1826362D02*
Y1814954D01*
X4165605D01*
G01X4166556Y1819707D02*
X4165605Y1821608D01*
X4166080Y1822559D01*
Y1825411D01*
X4165605Y1826362D01*
X4162278D01*
G01X4155148Y1929027D02*
X4174160D01*
G01X4163228Y2035495D02*
X4166080D01*
G01X4162278Y2031693D02*
X4164654Y2043100D01*
X4167031Y2031693D01*
M02*
